;LEADER: 12 
;HEADER: 
;CODE  : ASCII 
;FILE  : 9332_F0TG_MB_C_V02_0417_0820-1-18.drl for  ... layers TOP and BOTTOM
;DESIGN: 9332_F0TG_MB_C_V02_0417_0820.brd
;   Holesize 1. = 8.000000 Tolerance = +0.000000/-8.000000 PLATED MILS Quantity = 14456
;   Holesize 2. = 9.840000 Tolerance = +2.000000/-2.000000 PLATED MILS Quantity = 176
;   Holesize 3. = 10.000000 Tolerance = +0.000000/-10.000000 PLATED MILS Quantity = 28575
;   Holesize 4. = 14.170000 Tolerance = +1.960000/-1.960000 PLATED MILS Quantity = 608
;   Holesize 5. = 19.680000 Tolerance = +1.960000/-1.960000 PLATED MILS Quantity = 336
;   Holesize 6. = 22.000000 Tolerance = +3.000000/-3.000000 PLATED MILS Quantity = 40
;   Holesize 7. = 32.000000 Tolerance = +3.930000/-0.000000 PLATED MILS Quantity = 8
;   Holesize 8. = 40.000000 Tolerance = +1.960000/-1.960000 PLATED MILS Quantity = 1
;   Holesize 9. = 40.000000 Tolerance = +3.000000/-3.000000 PLATED MILS Quantity = 30
;   Holesize 10. = 40.150000 Tolerance = +2.000000/-2.000000 PLATED MILS Quantity = 60
;   Holesize 11. = 41.000000 Tolerance = +3.000000/-3.000000 PLATED MILS Quantity = 21
;   Holesize 12. = 44.000000 Tolerance = +1.960000/-1.960000 PLATED MILS Quantity = 32
;   Holesize 13. = 46.000000 Tolerance = +3.000000/-3.000000 PLATED MILS Quantity = 8
;   Holesize 14. = 67.000000 Tolerance = +3.000000/-3.000000 PLATED MILS Quantity = 48
;   Holesize 15. = 79.000000 Tolerance = +3.000000/-3.000000 PLATED MILS Quantity = 2
;   Holesize 16. = 147.000000 Tolerance = +3.000000/-3.000000 PLATED MILS Quantity = 24
;   Holesize 17. = 150.000000 Tolerance = +3.000000/-3.000000 PLATED MILS Quantity = 2
;   Holesize 18. = 166.000000 Tolerance = +3.000000/-3.000000 PLATED MILS Quantity = 1
;   Holesize 19. = 221.000000 Tolerance = +3.000000/-3.000000 PLATED MILS Quantity = 21
;   Holesize 20. = 30.000000 Tolerance = +3.140000/-0.000000 NON_PLATED MILS Quantity = 2
;   Holesize 21. = 41.000000 Tolerance = +2.000000/-2.000000 NON_PLATED MILS Quantity = 128
;   Holesize 22. = 44.000000 Tolerance = +1.960000/-1.960000 NON_PLATED MILS Quantity = 8
;   Holesize 23. = 45.000000 Tolerance = +1.960000/-1.960000 NON_PLATED MILS Quantity = 2
;   Holesize 24. = 46.000000 Tolerance = +2.000000/-2.000000 NON_PLATED MILS Quantity = 1
;   Holesize 25. = 65.000000 Tolerance = +2.000000/-2.000000 NON_PLATED MILS Quantity = 1
;   Holesize 26. = 120.000000 Tolerance = +2.000000/-2.000000 NON_PLATED MILS Quantity = 2
;   Holesize 27. = 122.000000 Tolerance = +2.000000/-2.000000 NON_PLATED MILS Quantity = 1
;   Holesize 28. = 125.000000 Tolerance = +2.000000/-0.000000 NON_PLATED MILS Quantity = 4
;   Holesize 29. = 125.000000 Tolerance = +2.000000/-2.000000 NON_PLATED MILS Quantity = 6
;   Holesize 30. = 158.000000 Tolerance = +2.000000/-2.000000 NON_PLATED MILS Quantity = 14
;   Holesize 31. = 217.000000 Tolerance = +2.000000/-2.000000 NON_PLATED MILS Quantity = 2
;   Holesize 32. = 394.000000 Tolerance = +4.000000/-4.000000 NON_PLATED MILS Quantity = 4
%
G90
X0660877Y1530158
X1668750Y1563158
X0662353Y1534413
X1670227Y1567413
X0531208Y1528698
X0659270Y1528698
X0395097Y1528698
X0267035Y1528698
X1539082Y1561698
X1667143Y1561698
X1402970Y1561698
X1274908Y1561698
X0531537Y1531618
X0659359Y1531618
X0395186Y1531618
X0267124Y1531618
X1539171Y1564618
X1667232Y1564618
X1403059Y1564618
X1274997Y1564618
X0531926Y1534540
X0659358Y1534540
X0395185Y1534540
X0267123Y1534540
X1539170Y1567540
X1667231Y1567540
X1403058Y1567540
X1274996Y1567540
X0532310Y1536640
X0659358Y1536640
X0395185Y1536640
X0267123Y1536640
X1539170Y1569640
X1667231Y1569640
X1274996Y1569640
X1449133Y1551121
X1577195Y1551121
X1313021Y1551121
X1184959Y1551121
X1449534Y1554612
X1577596Y1554612
X1313422Y1554612
X1185360Y1554612
X1538819Y1549336
X1538875Y1547073
X1666881Y1549336
X1666937Y1547073
X1402707Y1549336
X1402763Y1547073
X1274645Y1549336
X1274701Y1547073
X1450792Y1546218
X1578854Y1546218
X1314680Y1546218
X1186618Y1546218
X1501647Y1559353
X1501096Y1556953
X1487474Y1559353
X1486923Y1556953
X1492199Y1559353
X1496923Y1559353
X1491648Y1556953
X1496372Y1556953
X1629158Y1556953
X1629709Y1559353
X1619710Y1556953
X1620261Y1559353
X1615536Y1559353
X1614985Y1556953
X1624985Y1559353
X1624434Y1556953
X1364984Y1556953
X1365535Y1559353
X1355536Y1556953
X1356087Y1559353
X1351362Y1559353
X1350811Y1556953
X1360811Y1559353
X1360260Y1556953
X1237473Y1559353
X1236922Y1556953
X1223300Y1559353
X1222749Y1556953
X1228025Y1559353
X1232749Y1559353
X1227474Y1556953
X1232198Y1556953
X1478025Y1559353
X1477474Y1556953
X1510545Y1556953
X1511096Y1559353
X1524719Y1556953
X1525270Y1559353
X1529994Y1559353
X1520545Y1559353
X1519994Y1556953
X1529443Y1556953
X1515270Y1556953
X1515821Y1559353
X1468026Y1556953
X1463301Y1556953
X1473301Y1559353
X1459128Y1559353
X1463852Y1559353
X1468577Y1559353
X1458577Y1556953
X1472750Y1556953
X1605536Y1556953
X1606087Y1559353
X1638607Y1556953
X1639158Y1559353
X1657505Y1556953
X1653332Y1559353
X1658056Y1559353
X1643883Y1559353
X1643332Y1556953
X1648056Y1556953
X1648607Y1559353
X1652781Y1556953
X1591914Y1559353
X1587190Y1559353
X1591363Y1556953
X1586639Y1556953
X1601363Y1559353
X1596088Y1556953
X1596639Y1559353
X1600812Y1556953
X1341362Y1556953
X1341913Y1559353
X1374433Y1556953
X1374984Y1559353
X1393331Y1556953
X1389158Y1559353
X1393882Y1559353
X1379709Y1559353
X1379158Y1556953
X1383882Y1556953
X1384433Y1559353
X1388607Y1556953
X1327740Y1559353
X1323016Y1559353
X1327189Y1556953
X1322465Y1556953
X1337189Y1559353
X1331914Y1556953
X1332465Y1559353
X1336638Y1556953
X1246922Y1559353
X1246371Y1556953
X1213851Y1559353
X1213300Y1556953
X1260545Y1556953
X1261096Y1559353
X1265820Y1559353
X1256371Y1559353
X1255820Y1556953
X1265269Y1556953
X1251096Y1556953
X1251647Y1559353
X1203852Y1556953
X1199127Y1556953
X1209127Y1559353
X1194954Y1559353
X1199678Y1559353
X1204403Y1559353
X1194403Y1556953
X1208576Y1556953
X1537468Y1540355
X1535368Y1540355
X1538585Y1571658
X1455098Y1577625
X1451027Y1573317
X1452827Y1540509
X1450627Y1540509
X1578689Y1540509
X1579089Y1573317
X1665530Y1540355
X1663430Y1540355
X1580940Y1540460
X1583160Y1577625
X1666647Y1571658
X1314515Y1540509
X1402473Y1571658
X1314915Y1573317
X1401356Y1540355
X1399256Y1540355
X1316766Y1540460
X1318986Y1577625
X1186453Y1540509
X1274411Y1571658
X1271194Y1540355
X1188653Y1540509
X1190924Y1577625
X1186853Y1573317
X1273294Y1540355
X0441259Y1518121
X0569321Y1518121
X0441660Y1521612
X0569722Y1521612
X0530945Y1516336
X0531001Y1514073
X0659007Y1516336
X0659063Y1514073
X0442918Y1513218
X0570980Y1513218
X0493773Y1526353
X0493222Y1523953
X0479600Y1526353
X0479049Y1523953
X0484325Y1526353
X0489049Y1526353
X0483774Y1523953
X0488498Y1523953
X0621284Y1523953
X0621835Y1526353
X0611836Y1523953
X0612387Y1526353
X0607662Y1526353
X0607111Y1523953
X0617111Y1526353
X0616560Y1523953
X0470151Y1526353
X0469600Y1523953
X0502671Y1523953
X0503222Y1526353
X0516845Y1523953
X0517396Y1526353
X0522120Y1526353
X0512671Y1526353
X0512120Y1523953
X0521569Y1523953
X0507396Y1523953
X0507947Y1526353
X0460152Y1523953
X0455427Y1523953
X0465427Y1526353
X0451254Y1526353
X0455978Y1526353
X0460703Y1526353
X0450703Y1523953
X0464876Y1523953
X0597662Y1523953
X0598213Y1526353
X0630733Y1523953
X0631284Y1526353
X0649631Y1523953
X0645458Y1526353
X0650182Y1526353
X0636009Y1526353
X0635458Y1523953
X0640182Y1523953
X0640733Y1526353
X0644907Y1523953
X0584040Y1526353
X0579316Y1526353
X0583489Y1523953
X0578765Y1523953
X0593489Y1526353
X0588214Y1523953
X0588765Y1526353
X0592938Y1523953
X0442753Y1507509
X0530711Y1538658
X0527494Y1507355
X0444953Y1507509
X0447224Y1544625
X0443153Y1540317
X0529594Y1507355
X0658773Y1538658
X0571215Y1540317
X0575286Y1544625
X0573066Y1507460
X0570815Y1507509
X0655556Y1507355
X0657656Y1507355
X0305148Y1518121
X0305549Y1521612
X0394834Y1516336
X0394890Y1514073
X0306807Y1513218
X0178745Y1513218
X0357111Y1523953
X0357662Y1526353
X0352938Y1526353
X0352387Y1523953
X0342938Y1523953
X0343489Y1526353
X0348214Y1526353
X0347663Y1523953
X0229600Y1526353
X0229049Y1523953
X0215427Y1526353
X0214876Y1523953
X0219601Y1523953
X0224325Y1523953
X0224876Y1526353
X0220152Y1526353
X0602938Y1526353
X0602387Y1523953
X0626560Y1526353
X0626009Y1523953
X0474876Y1526353
X0474325Y1523953
X0498498Y1526353
X0497947Y1523953
X0361836Y1523953
X0362387Y1526353
X0338214Y1523953
X0338765Y1526353
X0234325Y1526353
X0233774Y1523953
X0210152Y1523953
X0210703Y1526353
X0366560Y1523953
X0367111Y1526353
X0333489Y1523953
X0334040Y1526353
X0386009Y1526353
X0381285Y1526353
X0385458Y1523953
X0371836Y1526353
X0371285Y1523953
X0376009Y1523953
X0376560Y1526353
X0380734Y1523953
X0329316Y1526353
X0328765Y1523953
X0324592Y1526353
X0324041Y1523953
X0314592Y1523953
X0319316Y1523953
X0315143Y1526353
X0319867Y1526353
X0239049Y1526353
X0238498Y1523953
X0205978Y1526353
X0205427Y1523953
X0243774Y1526353
X0243223Y1523953
X0247947Y1523953
X0248498Y1526353
X0257947Y1526353
X0252672Y1523953
X0253223Y1526353
X0257396Y1523953
X0186530Y1523953
X0191254Y1523953
X0201254Y1526353
X0200703Y1523953
X0187081Y1526353
X0191805Y1526353
X0196530Y1526353
X0195979Y1523953
X0391383Y1507355
X0393483Y1507355
X0307042Y1540317
X0311113Y1544625
X0394600Y1538658
X0308893Y1507460
X0306694Y1507279
X0177086Y1518121
X0177487Y1521612
X0266772Y1516336
X0266828Y1514073
X0266538Y1538658
X0183051Y1544625
X0178980Y1540317
X0178580Y1507509
X0263321Y1507355
X0265421Y1507355
X0180780Y1507509
X0441706Y1537898
X0441706Y1535698
X0569768Y1537898
X0569768Y1535698
X0305595Y1537898
X0305595Y1535698
X0177533Y1537898
X0177533Y1535698
X1449580Y1570898
X1449580Y1568698
X1577642Y1570898
X1577642Y1568698
X1313468Y1570898
X1313468Y1568698
X1185406Y1570898
X1185406Y1568698
X1610812Y1559353
X1610261Y1556953
X1634434Y1559353
X1633883Y1556953
X1482750Y1559353
X1482199Y1556953
X1506372Y1559353
X1505821Y1556953
X1346638Y1559353
X1346087Y1556953
X1370260Y1559353
X1369709Y1556953
X1218576Y1559353
X1218025Y1556953
X1242198Y1559353
X1241647Y1556953
X0496422Y1533336
X0491698Y1533336
X0486973Y1533336
R02X-0004724
X0472800Y1533336
X0468076Y1533336
X0463351Y1533336
X0458627Y1533336
X0524769Y1533336
X0520044Y1533336
X0515320Y1533336
X0510595Y1533336
X0505871Y1533336
X0501147Y1533336
X0453903Y1533336
X0494847Y1530608
R02X-0004724
X0480674Y1530608
X0475950Y1530608
X0471225Y1530608
R02X-0004724
X0457052Y1530608
X0523194Y1530608
X0518470Y1530608
X0513745Y1530608
X0509021Y1530608
X0504296Y1530608
X0499572Y1530608
X0452328Y1530608
X0624484Y1533336
X0619760Y1533336
X0615035Y1533336
R02X-0004724
X0600862Y1533336
X0596138Y1533336
X0591413Y1533336
X0586689Y1533336
X0652831Y1533336
X0648106Y1533336
X0643382Y1533336
X0638657Y1533336
X0633933Y1533336
X0629209Y1533336
X0581965Y1533336
X0622909Y1530608
R02X-0004724
X0608736Y1530608
X0604012Y1530608
X0599287Y1530608
R02X-0004724
X0585114Y1530608
X0651256Y1530608
X0646532Y1530608
X0641807Y1530608
X0637083Y1530608
X0632358Y1530608
X0627634Y1530608
X0580390Y1530608
X0360311Y1533336
X0355587Y1533336
X0350862Y1533336
R02X-0004724
X0336689Y1533336
X0331965Y1533336
X0327240Y1533336
X0322516Y1533336
X0388658Y1533336
X0383933Y1533336
X0379209Y1533336
X0374484Y1533336
X0369760Y1533336
X0365036Y1533336
X0317792Y1533336
X0358736Y1530608
R02X-0004724
X0344563Y1530608
X0339839Y1530608
X0335114Y1530608
R02X-0004724
X0320941Y1530608
X0387083Y1530608
X0382359Y1530608
X0377634Y1530608
X0372910Y1530608
X0368185Y1530608
X0363461Y1530608
X0316217Y1530608
X0232249Y1533336
X0227525Y1533336
X0222800Y1533336
R02X-0004724
X0208627Y1533336
X0203903Y1533336
X0199178Y1533336
X0194454Y1533336
X0260596Y1533336
X0255871Y1533336
X0251147Y1533336
X0246422Y1533336
X0241698Y1533336
X0236974Y1533336
X0189730Y1533336
X0230674Y1530608
R02X-0004724
X0216501Y1530608
X0211777Y1530608
X0207052Y1530608
R02X-0004724
X0192879Y1530608
X0259021Y1530608
X0254297Y1530608
X0249572Y1530608
X0244848Y1530608
X0240123Y1530608
X0235399Y1530608
X0188155Y1530608
X1504296Y1566336
X1499572Y1566336
X1494847Y1566336
R02X-0004724
X1480674Y1566336
X1475950Y1566336
X1471225Y1566336
X1466501Y1566336
X1532643Y1566336
X1527918Y1566336
X1523194Y1566336
X1518469Y1566336
X1513745Y1566336
X1509021Y1566336
X1461777Y1566336
X1502721Y1563608
R02X-0004724
X1488548Y1563608
X1483824Y1563608
X1479099Y1563608
R02X-0004724
X1464926Y1563608
X1531068Y1563608
X1526344Y1563608
X1521619Y1563608
X1516895Y1563608
X1512170Y1563608
X1507446Y1563608
X1460202Y1563608
X1632358Y1566336
X1627634Y1566336
X1622909Y1566336
R02X-0004724
X1608736Y1566336
X1604012Y1566336
X1599287Y1566336
X1594563Y1566336
X1660705Y1566336
X1655980Y1566336
X1651256Y1566336
X1646531Y1566336
X1641807Y1566336
X1637083Y1566336
X1589839Y1566336
X1630783Y1563608
R02X-0004724
X1616610Y1563608
X1611886Y1563608
X1607161Y1563608
R02X-0004724
X1592988Y1563608
X1659130Y1563608
X1654406Y1563608
X1649681Y1563608
X1644957Y1563608
X1640232Y1563608
X1635508Y1563608
X1588264Y1563608
X1368184Y1566336
X1363460Y1566336
X1358735Y1566336
R02X-0004724
X1344562Y1566336
X1339838Y1566336
X1335113Y1566336
X1330389Y1566336
X1396531Y1566336
X1391806Y1566336
X1387082Y1566336
X1382357Y1566336
X1377633Y1566336
X1372909Y1566336
X1325665Y1566336
X1366609Y1563608
R02X-0004724
X1352436Y1563608
X1347712Y1563608
X1342987Y1563608
R02X-0004724
X1328814Y1563608
X1394956Y1563608
X1390232Y1563608
X1385507Y1563608
X1380783Y1563608
X1376058Y1563608
X1371334Y1563608
X1324090Y1563608
X1240122Y1566336
X1235398Y1566336
X1230673Y1566336
R02X-0004724
X1216500Y1566336
X1211776Y1566336
X1207051Y1566336
X1202327Y1566336
X1268469Y1566336
X1263744Y1566336
X1259020Y1566336
X1254295Y1566336
X1249571Y1566336
X1244847Y1566336
X1197603Y1566336
X1238547Y1563608
R02X-0004724
X1224374Y1563608
X1219650Y1563608
X1214925Y1563608
R02X-0004724
X1200752Y1563608
X1266894Y1563608
X1262170Y1563608
X1257445Y1563608
X1252721Y1563608
X1247996Y1563608
X1243272Y1563608
X1196028Y1563608
X1323036Y1028055
X1321185Y1031244
X1320004Y0988048
X1325556Y0991237
X1326737Y1053567
X1328587Y1044000
X1323036Y1047189
X1321185Y1056756
X1348941Y1028055
X1347091Y1031244
X1345910Y0988048
X1351461Y0991237
X1352642Y1053567
X1354493Y1044000
X1348941Y1047189
X1347091Y1056756
X1334138Y1028055
X1335989Y1031244
X1334808Y0988048
X1340359Y0991237
X1341540Y1053567
X1339689Y1044000
X1334138Y1047189
X1335989Y1056756
X1297130Y1028055
X1295280Y1031244
X1294099Y0988048
X1299650Y0991237
X1300831Y1053567
X1302682Y1044000
X1297130Y1047189
X1295280Y1056756
X1308233Y1028055
X1310083Y1031244
X1308902Y0988048
X1314453Y0991237
X1315634Y1053567
X1313784Y1044000
X1308233Y1047189
X1310083Y1056756
X1511751Y1028055
X1513602Y1031244
X1510570Y0991237
X1505019Y0994426
X1508050Y1053567
X1513602Y1044000
X1511751Y1047189
X1513602Y1056756
X1485846Y1028055
X1487696Y1031244
X1484665Y0991237
X1479113Y0994426
X1482145Y1053567
X1487696Y1044000
X1485846Y1047189
X1487696Y1056756
X1500649Y1028055
X1498798Y1031244
X1499468Y0991237
X1493917Y0994426
X1493247Y1053567
X1498798Y1044000
X1500649Y1047189
X1498798Y1056756
X1405123Y0886001
X1408824Y0886001
X1401423Y0879623
X1405123Y0879623
X1468011Y0886001
X1410004Y1158803
X1315634Y1161992
X1317485Y1165181
X1302682Y1165181
X1300831Y1161992
X1341540Y1161992
X1343390Y1158803
X1517972Y1010371
X1506869Y1010371
X1492066Y1010371
X1480964Y1010371
X1543877Y1010371
X1351461Y1010371
X1340359Y1010371
X1325556Y1010371
X1314453Y1010371
X1299650Y1010371
X1532775Y1010371
X1288548Y1010371
X1526554Y1028055
X1524704Y1031244
X1525373Y0991237
X1519822Y0994426
X1519153Y1053567
X1524704Y1044000
X1526554Y1047189
X1524704Y1056756
X1537657Y1028055
X1539507Y1031244
X1536476Y0991237
X1530924Y0994426
X1533956Y1053567
X1539507Y1044000
X1537657Y1047189
X1539507Y1056756
X0346894Y1028056
X0345043Y1031245
X0343862Y0988049
X0349414Y0991238
X0350595Y1053568
X0352445Y1044001
X0346894Y1047190
X0345043Y1056757
X0372799Y1028056
X0370949Y1031245
X0369768Y0988049
X0375319Y0991238
X0376500Y1053568
X0378351Y1044001
X0372799Y1047190
X0370949Y1056757
X0357996Y1028056
X0359847Y1031245
X0358666Y0988049
X0364217Y0991238
X0365398Y1053568
X0363547Y1044001
X0357996Y1047190
X0359847Y1056757
X0320988Y1028056
X0319138Y1031245
X0317957Y0988049
X0323508Y0991238
X0324689Y1053568
X0326540Y1044001
X0320988Y1047190
X0319138Y1056757
X0332091Y1028056
X0333941Y1031245
X0332760Y0988049
X0338311Y0991238
X0339492Y1053568
X0337642Y1044001
X0332091Y1047190
X0333941Y1056757
X0535609Y1028056
X0537460Y1031245
X0534428Y0991238
X0528877Y0994427
X0531908Y1053568
X0537460Y1044001
X0535609Y1047190
X0537460Y1056757
X0509704Y1028056
X0511554Y1031245
X0508523Y0991238
X0502971Y0994427
X0506003Y1053568
X0511554Y1044001
X0509704Y1047190
X0511554Y1056757
X0524507Y1028056
X0522656Y1031245
X0523326Y0991238
X0517775Y0994427
X0517105Y1053568
X0522656Y1044001
X0524507Y1047190
X0522656Y1056757
X0395673Y0886002
X0399374Y0886002
X0391973Y0879624
X0395673Y0879624
X0463444Y1165182
X0472696Y1161993
X0470845Y1152426
X0468995Y1155615
X0467145Y1158804
X0463444Y1158804
X0528877Y0879624
X0532578Y0873246
X0450491Y1155615
X0568916Y1161993
X0541160Y1158804
X0474546Y1165182
X0537460Y1158804
X0539310Y1161993
X0504153Y1165182
X0507853Y1165182
X0527027Y0882813
X0527027Y0876435
X0489349Y1165182
X0500452Y1165182
X0480097Y1155615
X0500452Y1158804
X0478247Y1165182
X0474546Y1158804
X0494901Y1155615
X0494901Y1161993
X0493050Y1152426
X0491200Y1155615
X0489349Y1158804
X0496751Y1158804
X0478247Y1158804
X0496751Y1165182
X0485649Y1165182
X0481948Y1152426
X0472696Y1155615
X0485649Y1158804
X0483798Y1161993
X0465964Y0873246
X0451160Y0873246
X0414177Y0873246
X0403075Y0873246
X0395673Y0873246
X0391973Y0873246
X0380870Y0873246
X0377169Y0873246
X0373469Y0873246
X0369768Y0873246
X0541830Y1010372
X0530727Y1010372
X0515924Y1010372
X0504822Y1010372
X0567735Y1010372
X0375319Y1010372
X0364217Y1010372
X0349414Y1010372
X0338311Y1010372
X0323508Y1010372
X0556633Y1010372
X0465964Y0879624
X0454861Y0879624
X0451160Y0879624
X0384571Y0879624
X0380870Y0879624
X0541830Y0882813
X0501121Y0882813
X0456712Y0882813
X0449310Y0882813
X0567735Y0882813
X0552932Y0882813
X0518956Y1158804
X0520806Y1161993
X0506003Y1161993
X0567066Y1165182
X0458562Y0886002
X0447460Y0886002
X0535609Y1161993
X0428311Y1155615
X0495570Y0879624
X0531908Y1161993
X0426461Y1158804
X0497420Y0882813
X0449310Y0876435
X0550412Y1028056
X0548562Y1031245
X0549231Y0991238
X0543680Y0994427
X0543011Y1053568
X0548562Y1044001
X0550412Y1047190
X0548562Y1056757
X0561515Y1028056
X0563365Y1031245
X0560334Y0991238
X0554782Y0994427
X0557814Y1053568
X0563365Y1044001
X0561515Y1047190
X0563365Y1056757
X1456909Y0886001
X1460609Y0886001
X1443287Y1158803
X1445137Y1155614
X1439586Y1152425
X1437735Y1155614
X1505019Y0879623
X0463444Y1152426
X0461593Y1155615
X1334138Y1161992
X1335989Y1165181
X1530255Y1161992
X1504350Y1161992
X1500649Y1161992
X0432012Y1155615
X1410004Y1152425
X1408154Y1155614
X0524507Y1161993
X0433862Y1152426
X1464310Y0879623
X1460609Y0879623
X1394021Y0879623
X1390320Y0879623
X1525373Y0876434
X1523523Y0879623
X1514271Y0876434
X1512421Y0879623
X1519822Y0873245
X1516121Y0873245
X1536476Y0876434
X1534625Y0879623
X1527224Y0873245
X1530924Y0873245
X0410477Y0968915
X0410477Y0962537
X0410477Y0975293
X0421579Y0968915
X0421579Y0962537
X0421579Y0975293
X0430831Y0965726
X0430831Y0959348
X0430831Y0972104
X0388272Y0968915
X0388272Y0962537
X0388272Y0975293
X0399374Y0968915
X0399374Y0962537
X0399374Y0975293
X0430831Y0978482
X0406776Y0968915
X0406776Y0962537
X0406776Y0975293
X0417878Y0968915
X0417878Y0962537
X0417878Y0975293
X0427130Y0965726
X0427130Y0959348
X0427130Y0972104
X0384571Y0968915
X0384571Y0962537
X0384571Y0975293
X0395673Y0968915
X0395673Y0962537
X0395673Y0975293
X0427130Y0978482
X1446987Y1088646
X1446987Y1095024
X1435885Y1082268
X1426633Y1098213
X1426633Y1091835
X1469192Y1088646
X1469192Y1095024
X1469192Y1082268
X1458090Y1088646
X1458090Y1095024
X1458090Y1082268
X1426633Y1085457
X1450688Y1088646
X1450688Y1095024
X1439586Y1082268
X1430334Y1098213
X1430334Y1091835
X1472893Y1088646
X1472893Y1095024
X1472893Y1082268
X1461791Y1088646
X1461791Y1095024
X1461791Y1082268
X1430334Y1085457
X1475950Y1552698
X1439586Y1133292
X1471225Y1552698
X1430334Y1142858
X1466501Y1552698
X1430334Y1136480
X1472893Y1126914
X1532643Y1552698
X1527918Y1552698
X1472893Y1139669
X1523194Y1552698
X1472893Y1146047
X1518469Y1552698
X1472893Y1133292
X1474375Y1549970
X1435885Y1133292
X1469651Y1549970
X1426633Y1142858
X1464926Y1549970
X1426633Y1136480
X1469192Y1126914
X1531068Y1549970
X1526344Y1549970
X1469192Y1139669
X1521619Y1549970
X1469192Y1146047
X1516895Y1549970
X1469192Y1133292
X0419059Y1152426
R02X-0011102
X0385752Y1152426
X0422760Y1152426
X0411658Y1152426
X0400555Y1152426
X0389453Y1152426
X0415358Y1158804
R02X-0011102
X0382051Y1158804
X0419059Y1158804
X0407957Y1158804
X0396855Y1158804
X0385752Y1158804
X1395201Y1152425
R02X-0011102
X1361894Y1152425
X1398902Y1152425
X1387800Y1152425
X1376697Y1152425
X1365595Y1152425
X1391500Y1158803
R02X-0011102
X1358193Y1158803
X1395201Y1158803
X1384099Y1158803
X1372997Y1158803
X1361894Y1158803
X1397722Y0886001
X1394021Y0886001
X0406776Y0879624
X1375516Y0886001
X0403075Y0879624
X1371815Y0886001
X0410477Y0886002
X1371815Y0879623
X0406776Y0886002
X1368115Y0879623
X0570767Y1165182
X1546909Y1165181
X0382051Y1056757
X1358193Y1056756
X0569586Y0879624
X1545728Y0879623
X0385752Y1056757
X1361894Y1056756
X0571436Y0876435
X0573286Y0879624
X1549428Y0879623
X0572617Y1161993
X1548759Y1161992
X1453208Y0873245
X1449507Y0873245
X1310083Y1165181
X1308233Y1161992
X1460609Y0873245
X1464310Y0873245
X1428484Y1158803
X0383902Y1053568
X1360044Y1053567
X1434035Y1155614
X0543011Y1028056
X1519153Y1028055
X0557814Y1028056
X1533956Y1028055
X0517105Y1028056
X1493247Y1028055
X0506003Y1028056
X1482145Y1028055
X0531908Y1028056
X1508050Y1028055
X0568916Y1028056
X1545058Y1028055
X0339492Y1028056
X1315634Y1028055
X0324689Y1028056
X1300831Y1028055
X0365398Y1028056
X1341540Y1028055
X0376500Y1028056
X1352642Y1028055
X0350595Y1028056
X1326737Y1028055
X0358665Y0879624
X0313587Y1028056
X1334807Y0879623
X1289729Y1028055
X0461593Y1161993
X0456042Y1165182
X0452341Y1158804
X0457893Y1155615
X0456042Y1158804
X0459743Y1165182
X0385752Y1101403
X0495570Y0937025
X0389453Y1101403
X0473365Y0937025
X0474546Y1101403
X0406776Y0937025
X0399374Y0937025
X0408626Y0933836
X0411658Y1101403
X0470845Y1101403
X0410477Y0937025
X0491869Y0937025
X0476397Y1104592
X0404925Y0933836
X0484467Y0937025
X0393154Y1101403
X0489349Y1101403
X0384571Y0937025
X0471515Y0933836
X0400555Y1101403
X0475215Y0933836
X0406107Y1104592
X0481948Y1101403
X0391973Y0937025
X0488168Y0937025
X0472696Y1104592
X0403075Y0937025
X0480767Y0937025
X0396855Y1101403
X0485649Y1101403
X0388272Y0937025
X0469664Y0937025
X0404256Y1101403
X0477066Y0937025
X0407957Y1101403
X0478247Y1101403
X0395673Y0937025
X0556633Y0882813
X0364217Y0876435
X0462263Y0886002
X0409807Y1104592
X0493050Y1101403
X0465964Y0930647
X1432184Y1158803
X1361894Y1101402
X1471712Y0937024
X1365595Y1101402
X1449507Y0937024
X1450688Y1101402
X1382918Y0937024
X1375516Y0937024
X1384768Y0933835
X1387800Y1101402
X1446987Y1101402
X1386619Y0937024
X1468011Y0937024
X1452539Y1104591
X1381067Y0933835
X1460609Y0937024
X1369296Y1101402
X1465491Y1101402
X1360713Y0937024
X1447657Y0933835
X1376697Y1101402
X1451357Y0933835
X1382249Y1104591
X1458090Y1101402
X1368115Y0937024
X1329256Y0876434
X1464310Y0937024
X1448838Y1104591
X1379217Y0937024
X1456909Y0937024
X1372997Y1101402
X1461791Y1101402
X1364414Y0937024
X1445806Y0937024
X1380398Y1101402
X1453208Y0937024
X1384099Y1101402
X1454389Y1101402
X1371815Y0937024
X1532775Y0882812
X1340359Y0876434
X1438405Y0886001
X1385949Y1104591
X1469192Y1101402
X1332957Y0876434
X1442106Y0930646
X1480964Y0876434
X1475413Y0873245
X1471712Y0873245
X0481948Y1165182
X1476594Y1158803
X1456239Y1155614
X1461791Y1158803
X1448838Y1155614
X0530727Y0882813
X0530727Y0876435
X1506869Y0882812
X1506869Y0876434
X1515452Y1161992
X1513602Y1158803
X1288549Y0876434
X1290399Y0879623
X1471712Y0886001
X1458090Y1152425
X0544861Y1158804
X0448641Y1158804
X0515924Y0882813
X1537657Y1161992
X1521003Y1158803
X1307052Y0876434
X1424783Y1158803
X1492066Y0882812
X1461791Y1165181
X0323508Y0882813
X1299650Y0882812
X0389453Y1050379
X0391303Y1053568
X1365595Y1050378
X1367445Y1053567
X0316107Y0914702
X0314256Y0924269
X0314256Y0905135
X0316107Y0895569
X0314256Y0943403
X0316107Y0952970
X0316107Y0933836
X0316107Y0991238
X0314256Y1000805
X0314256Y0981671
X0316107Y0972104
X0314256Y0962537
X0317288Y1047190
X0315437Y1056757
X0315437Y1037623
X0317288Y1028056
X0315437Y1095025
X0317288Y1104592
X0315437Y1075891
X0317288Y1085458
X0317288Y1066324
X0317288Y1123726
X0315437Y1133293
X0315437Y1114159
X0319138Y1158804
X0315437Y1152426
X0317288Y1142859
X0342012Y0895569
X0342012Y0914702
X0340162Y0924269
X0340162Y0905135
X0340162Y0943403
X0342012Y0952970
X0342012Y0933836
X0340162Y0981671
X0342012Y0972104
X0340162Y0962537
X0341343Y1037623
X0343193Y1028056
X0342012Y0991238
X0340162Y1000805
X0341343Y1075891
X0343193Y1085458
R02Y-0019134
X0341343Y1056757
X0341343Y1114159
X0343193Y1104592
X0341343Y1095025
X0343193Y1142859
X0341343Y1133293
X0343193Y1123726
X0345043Y1158804
X0341343Y1152426
X0367917Y0895569
X0379020Y0914702
X0367917Y0914702
X0366067Y0924269
X0379020Y0901947
X0366067Y0905135
X0379020Y0927458
X0367917Y0933836
X0379020Y0959348
X0366067Y0962537
X0379020Y0946592
X0367917Y0952970
X0366067Y0943403
X0379020Y0972104
X0367917Y0972104
X0366067Y0981671
X0369099Y1028056
X0379020Y1010372
X0367917Y0991238
X0366067Y1000805
X0369099Y1047190
X0367248Y1056757
X0367248Y1037623
X0380201Y1066324
X0369099Y1066324
X0380201Y1079080
X0369099Y1085458
X0367248Y1075891
X0380201Y1110970
X0367248Y1114159
X0369099Y1104592
X0367248Y1095025
X0380201Y1091836
X0380201Y1123726
X0367248Y1133293
X0369099Y1123726
X0367248Y1152426
X0380201Y1136481
X0369099Y1142859
X0380870Y0937025
X0383902Y1047190
X0391303Y1047190
X0382051Y1050379
X0383902Y1034434
X0383902Y1040812
X0389453Y1031245
X0389453Y1044001
X0391303Y1040812
X0389453Y1037623
X0391303Y1034434
X0382051Y1044001
R02Y-0006378
X0383902Y1028056
X0391303Y1028056
X0386421Y1010372
X0393823Y1010372
X0382051Y1101403
X0396855Y1037623
X0396855Y1031245
X0396855Y1044001
X1290398Y0905134
X1292249Y0895568
X1290398Y0924268
X1292249Y0914701
X1290398Y0943402
X1292249Y0952969
X1292249Y0933835
X1290398Y0981670
X1292249Y0972103
X1290398Y0962536
X1293430Y1028055
X1290398Y1000804
X1292249Y0991237
X1293430Y1047189
X1291579Y1056756
X1291579Y1037622
X1291579Y1075890
X1293430Y1085457
X1293430Y1066323
X1291579Y1095024
X1293430Y1104591
X1293430Y1123725
X1291579Y1133292
X1291579Y1114158
X1291579Y1152425
X1295280Y1158803
X1293430Y1142858
X1318154Y0895568
X1318154Y0914701
X1316304Y0924268
X1316304Y0905134
X1316304Y0943402
X1318154Y0952969
X1318154Y0933835
X1318154Y0991237
X1316304Y1000804
X1318154Y0972103
X1316304Y0981670
X1316304Y0962536
X1317485Y1037622
X1319335Y1028055
X1317485Y1075890
X1319335Y1085457
R02Y-0019134
X1317485Y1056756
X1317485Y1114158
X1317485Y1095024
X1319335Y1104591
X1319335Y1142858
X1319335Y1123725
X1317485Y1133292
X1317485Y1152425
X1321185Y1158803
X1342209Y0905134
X1344059Y0895568
X1342209Y0924268
X1344059Y0914701
X1344059Y0933835
X1342209Y0962536
X1344059Y0952969
X1342209Y0943402
X1342209Y1000804
X1344059Y0991237
X1344059Y0972103
X1342209Y0981670
X1345241Y1028055
X1343390Y1056756
X1345241Y1047189
X1343390Y1037622
X1345241Y1066323
X1345241Y1085457
X1343390Y1075890
X1343390Y1114158
X1345241Y1104591
X1343390Y1095024
X1345241Y1123725
X1343390Y1133292
X1343390Y1152425
X1345241Y1142858
X1355162Y0901946
X1355162Y0927457
X1357012Y0937024
X1355162Y0914701
X1355162Y0959347
X1355162Y0946591
X1355162Y0972103
X1358193Y1050378
X1360044Y1047189
X1358193Y1044000
X1358193Y1037622
X1360044Y1034433
X1360044Y1040811
X1358193Y1031244
X1360044Y1028055
X1362563Y1010371
X1355162Y1010371
X1356343Y1066323
X1356343Y1079079
X1358193Y1101402
X1356343Y1091835
X1356343Y1110969
X1356343Y1136480
X1356343Y1123725
X1372997Y1031244
X1365595Y1044000
R02Y-0006378
X1367445Y1034433
X1367445Y1040811
X1372997Y1044000
X1372997Y1037622
X1367445Y1028055
X1369965Y1010371
X1367445Y1047189
X0403075Y1007183
X0406763Y1007175
X0397524Y1003994
X0403075Y1000805
X0403075Y0994427
X0397524Y0997616
X0404925Y0991238
X0402406Y1034434
X0404256Y1031245
X0404256Y1037623
X0406094Y1034442
X0402406Y1028056
X0406094Y1028064
X0401225Y1010372
X0419729Y0991238
X0419716Y0997608
X0412327Y0991238
X0412315Y0997608
X0434519Y0997608
X0427130Y0991238
X0427118Y0997608
X0434532Y0991238
X0432681Y0988049
X0449310Y0991238
X0451160Y0988049
X0449323Y0997608
X0464113Y0991238
X0465964Y0988049
X0464126Y0997608
X0456712Y0991238
X0456724Y0997608
X0480767Y1007183
X0478916Y1010372
X0478916Y1003994
X0480767Y1000805
X0480767Y0988049
X0480767Y0994427
X0478916Y0991238
X0478916Y0997616
X0471515Y0991238
X0471527Y0997608
X0478247Y1031245
X0483798Y1028056
X0499271Y0937025
X0495570Y1000805
X0495570Y0988049
X0495570Y0994427
X0488168Y1000805
X0493719Y0991238
X0486318Y0991238
X0493719Y0997616
X0486318Y0997616
X0488168Y0994427
X0498601Y1034434
X0491200Y1034434
X0493050Y1031245
X0485649Y1031245
X0498601Y1028056
X0491200Y1028056
X0495570Y1007183
X0493719Y1010372
X0493719Y1003994
X0486318Y1010372
X0486318Y1003994
X0488168Y1007183
X0512223Y0895569
X0501121Y0914702
X0514074Y0924269
X0512223Y0914702
X0501121Y0901947
X0514074Y0905135
X0501121Y0927458
X0512223Y0933836
X0501121Y0946592
X0512223Y0952970
X0514074Y0943403
X0501121Y0984860
X0501121Y0972104
X0512223Y0972104
X0514074Y0981671
X0501121Y0959348
X0514074Y0962537
X0501121Y1003994
X0514074Y1000805
X0512223Y0991238
X0501121Y0991238
X0501121Y0997616
X0500452Y1031245
X0512223Y1010372
X0501121Y1010372
X0538129Y0914702
X0539979Y0924269
X0539979Y0905135
X0539979Y0886002
X0538129Y0895569
X0539979Y0943403
X0538129Y0952970
X0538129Y0933836
X0539979Y0981671
X0538129Y0972104
X0539979Y0962537
X0538129Y1010372
X0538129Y0991238
X0539979Y1000805
X0541160Y1037623
X0565885Y0905135
X0565885Y0886002
X0564034Y0895569
X0564034Y0876435
X0565885Y0879624
X0564034Y0933836
X0564034Y0914702
X0565885Y0924269
X0564034Y0972104
X0565885Y0981671
R02Y-0019134
X0564034Y0952970
X0567066Y1037623
X0564034Y1010372
X0564034Y0991238
X0565885Y1000805
X0565215Y1047190
X1378548Y1034433
X1378548Y1028055
X1373666Y1003993
X1377367Y1010371
X1379217Y1007182
X1379217Y1000804
X1373666Y0997615
X1379217Y0994426
X1388469Y0991237
X1388457Y0997607
X1381067Y0991237
X1380398Y1031244
X1380398Y1037622
X1382236Y1034441
X1382236Y1028063
X1382905Y1007174
X1403272Y0991237
X1408823Y0988048
X1403260Y0997607
X1395871Y0991237
X1395858Y0997607
X1410674Y0991237
X1410661Y0997607
X1432854Y0991237
X1425452Y0991237
X1427302Y0988048
X1432866Y0997607
X1425465Y0997607
X1447657Y0991237
X1440255Y0991237
X1442106Y0988048
X1447669Y0997607
X1440268Y0997607
X1467342Y1028055
X1459940Y1028055
X1455058Y1003993
X1455058Y1010371
X1462460Y1003993
X1462460Y1010371
X1456909Y1007182
X1464310Y1007182
X1464310Y1000804
X1456909Y1000804
X1455058Y0991237
X1455058Y0997615
X1462460Y0991237
X1462460Y0997615
X1456909Y0994426
X1456909Y0988048
X1464310Y0994426
X1467342Y1034433
X1454389Y1031244
X1461791Y1031244
X1477263Y0901946
X1477263Y0914701
X1477263Y0946591
X1475413Y0937024
X1477263Y0927457
X1477263Y0984859
X1477263Y0972103
X1477263Y0959347
X1469192Y1031244
X1476594Y1031244
X1474743Y1034433
X1474743Y1028055
X1469861Y1003993
X1469861Y1010371
X1477263Y1003993
X1477263Y1010371
X1471712Y1007182
X1471712Y1000804
X1477263Y0997615
X1471712Y0994426
X1471712Y0988048
X1469861Y0991237
X1469861Y0997615
X1477263Y0991237
X1488365Y0895568
X1490216Y0905134
X1488365Y0933835
X1490216Y0924268
X1488365Y0914701
X1488365Y0952969
X1490216Y0943402
X1490216Y0962536
X1488365Y0972103
X1490216Y0981670
X1488365Y1010371
X1490216Y1000804
X1488365Y0991237
X1516121Y0905134
X1514271Y0895568
X1516121Y0886001
X1514271Y0933835
X1514271Y0914701
X1516121Y0924268
X1516121Y0962536
X1514271Y0952969
X1516121Y0943402
X1514271Y0991237
X1516121Y1000804
X1514271Y0972103
X1516121Y0981670
X1517302Y1037622
X1514271Y1010371
X1540176Y0876434
X1542027Y0879623
X1542027Y0905134
X1542027Y0886001
X1540176Y0895568
X1540176Y0914701
X1542027Y0924268
X1542027Y0943402
X1540176Y0952969
X1540176Y0933835
X1542027Y0962536
X1540176Y0991237
X1542027Y1000804
X1540176Y0972103
X1542027Y0981670
X1543208Y1037622
X1540176Y1010371
X1541357Y1047189
X0476396Y1130103
X0424610Y1149237
X0413508Y1149237
X0417209Y1161993
X0413508Y1161993
X0402406Y1161993
X0406107Y1161993
X0393154Y1152426
X0395004Y1161993
X0391303Y1161993
X0383902Y1161993
X0380201Y1161993
X0372799Y1161993
X0369099Y1161993
X0370949Y1158804
X0380201Y1149237
X0389453Y1056757
X0387603Y1059946
X0383902Y1059946
X0395004Y1059946
X0387603Y1072702
X0383902Y1072702
X0395004Y1072702
X0387603Y1098214
X0383902Y1098214
X0395004Y1098214
X0387603Y1085458
X0383902Y1085458
X0395004Y1085458
X0383902Y1117348
X0387603Y1117348
X0395004Y1117348
X0391303Y1149237
X0383902Y1142859
X0387603Y1142859
X0395004Y1142859
X0383902Y1130103
X0387603Y1130103
X0395004Y1130103
X0382051Y1152426
X0404256Y1056757
X0406107Y1053568
X0406107Y1059946
X0409807Y1059946
X0396855Y1056757
X0396855Y1050379
X0398705Y1053568
X0398705Y1059946
X0409807Y1072702
X0406107Y1072702
X0398705Y1072702
X0409807Y1085458
X0406107Y1085458
X0398705Y1085458
X0409807Y1098214
X0406107Y1098214
X0398705Y1098214
X0409807Y1117348
X0406107Y1117348
X0407957Y1107781
X0398705Y1117348
X0409807Y1130103
X0406107Y1130103
X0398705Y1130103
X0404256Y1152426
X0402406Y1149237
X0409807Y1142859
X0406107Y1142859
X0398705Y1142859
X0420910Y1059946
X0417209Y1059946
X0419059Y1056757
X0420910Y1053568
X0411658Y1056757
X0413508Y1053568
X0411658Y1050379
X0420910Y1072702
X0417209Y1072702
X0417209Y1098214
X0420910Y1098214
X0420910Y1085458
X0417209Y1085458
X0417209Y1117348
X0420910Y1117348
X0419059Y1107781
X0422760Y1107781
X0411658Y1107781
X0420910Y1142859
X0417209Y1142859
X0417209Y1130103
X0420910Y1130103
X0415358Y1152426
X0424610Y1161993
X0435713Y1053568
X0433862Y1056757
X0428311Y1053568
X0426461Y1056757
X0426461Y1050379
X0433862Y1082269
X0430162Y1082269
X0433862Y1069513
X0430162Y1069513
X0433862Y1114159
X0430162Y1114159
X0432012Y1104592
X0433862Y1095025
X0428311Y1104592
X0430162Y1095025
X0433862Y1146048
X0433862Y1139670
X0430162Y1146048
X0430162Y1139670
X0433862Y1126915
X0430162Y1126915
X0430162Y1152426
X0426461Y1152426
X0428311Y1161993
X0452341Y1069513
X0448641Y1069513
X0452341Y1050379
X0450491Y1053568
X0452341Y1056757
X0454192Y1104592
X0450491Y1104592
X0452341Y1095025
X0448641Y1095025
X0452341Y1082269
X0448641Y1082269
X0452341Y1126915
X0448641Y1126915
X0452341Y1114159
X0448641Y1114159
X0448640Y1165182
X0452341Y1152426
X0454192Y1161993
X0452341Y1146048
X0448641Y1146048
X0452341Y1139670
X0448641Y1139670
X0465294Y1059946
X0459743Y1056757
X0461593Y1059946
X0457893Y1053568
X0465294Y1072702
X0461593Y1072702
X0467145Y1050379
X0467145Y1056757
X0465294Y1053568
X0465294Y1098214
X0461593Y1098214
X0465294Y1085458
X0461593Y1085458
X0465294Y1130103
X0461593Y1130103
X0465294Y1117348
X0463444Y1107781
X0461593Y1117348
X0459743Y1107781
X0456042Y1152426
X0457893Y1161993
X0467145Y1152426
X0465294Y1161993
X0468995Y1161993
X0468995Y1149237
X0465294Y1142859
X0457893Y1149237
X0461593Y1142859
X0481948Y1050379
X0480097Y1053568
X0481948Y1056757
X0483798Y1059946
X0476397Y1059946
X0472696Y1059946
X0472696Y1053568
X0474546Y1056757
X0483798Y1072702
X0472696Y1072702
X0476397Y1072702
X0483798Y1085458
X0476397Y1085458
X0472696Y1085458
X0483798Y1117348
X0472696Y1117348
X0476397Y1117348
X0474546Y1107781
X0470845Y1107781
X0483798Y1098214
X0476397Y1098214
X0472696Y1098214
X0483798Y1130103
X0472696Y1130103
X0470846Y1165182
X0478247Y1152426
X0476397Y1161993
X0480097Y1161993
X0480097Y1149237
X0483798Y1142859
X0476397Y1142859
X0472696Y1142859
X0498601Y1059946
X0496751Y1056757
X0487499Y1053568
X0489349Y1056757
X0487499Y1059946
X0494901Y1053568
X0494901Y1059946
X0498601Y1072702
X0487499Y1072702
X0494901Y1072702
X0498601Y1098214
X0487499Y1098214
X0494901Y1098214
X0498601Y1085458
X0487499Y1085458
X0494901Y1085458
X0498601Y1130103
X0494901Y1130103
X0487499Y1130103
X0498601Y1117348
X0487499Y1117348
X0494901Y1117348
X0493050Y1165182
X0489349Y1152426
X0491200Y1161993
X0487499Y1161993
X0498601Y1161993
X0498601Y1142859
X0491200Y1149237
X0487499Y1142859
X0494901Y1142859
X0502302Y1149237
X0500452Y1152426
X0502302Y1161993
X0509704Y1161993
X0511554Y1158804
X0513405Y1161993
X1452539Y1130103
X1345241Y1161992
X1348941Y1161992
X1347091Y1158803
X1360044Y1059945
X1363745Y1059945
X1360044Y1072701
X1363745Y1072701
X1360044Y1085457
X1363745Y1085457
X1360044Y1098213
X1363745Y1098213
X1360044Y1117347
X1363745Y1117347
X1356343Y1149236
X1363745Y1142858
X1360044Y1142858
X1360044Y1130102
X1363745Y1130102
X1360044Y1161992
X1356343Y1161992
X1358193Y1152425
X1374847Y1072701
X1371146Y1072701
X1365595Y1056756
X1374847Y1059945
X1372997Y1050378
X1372997Y1056756
X1371146Y1059945
X1374847Y1053567
X1371146Y1085457
X1374847Y1085457
X1371146Y1117347
X1374847Y1117347
X1371146Y1098213
X1374847Y1098213
X1374847Y1130102
X1371146Y1130102
X1367445Y1161992
X1378548Y1161992
X1371146Y1161992
X1369296Y1152425
X1367445Y1149236
X1378548Y1149236
X1371146Y1142858
X1374847Y1142858
X1389650Y1053567
X1387800Y1050378
X1393351Y1059945
X1387800Y1056756
X1380398Y1056756
X1385949Y1059945
X1382249Y1053567
X1382249Y1059945
X1393351Y1085457
X1385949Y1085457
X1382249Y1085457
X1393351Y1072701
X1385949Y1072701
X1382249Y1072701
X1393351Y1117347
X1387800Y1107780
X1385949Y1117347
X1382249Y1117347
X1384099Y1107780
X1393351Y1098213
X1385949Y1098213
X1382249Y1098213
X1389650Y1149236
X1393351Y1142858
X1385949Y1142858
X1382249Y1142858
X1393351Y1130102
X1382249Y1130102
X1385949Y1130102
X1389650Y1161992
X1393351Y1161992
X1391500Y1152425
X1382249Y1161992
X1380398Y1152425
X1404453Y1053567
X1397052Y1053567
X1397052Y1059945
X1395201Y1056756
X1402603Y1050378
X1402603Y1056756
X1397052Y1072701
X1406304Y1069512
X1406304Y1082268
X1397052Y1085457
X1404453Y1104591
X1408154Y1104591
X1406304Y1095024
X1397052Y1098213
X1406304Y1114158
X1397052Y1117347
X1395201Y1107780
X1398902Y1107780
X1406304Y1126914
X1397052Y1130102
X1404453Y1161992
X1406304Y1152425
X1400752Y1161992
X1402603Y1152425
X1406304Y1146047
X1406304Y1139669
X1400752Y1149236
X1397052Y1142858
X1410004Y1082268
R02Y-0012756
X1411855Y1053567
X1410004Y1146047
X1410004Y1139669
X1410004Y1126914
X1410004Y1114158
X1410004Y1095024
X1434035Y1053567
X1426633Y1053567
X1428483Y1056756
X1437735Y1072701
X1424783Y1069512
X1428483Y1069512
X1435885Y1056756
X1437735Y1059945
X1428483Y1050378
X1437735Y1098213
X1426633Y1104591
X1430334Y1104591
X1424783Y1095024
X1428483Y1095024
X1437735Y1085457
X1424783Y1082268
X1428483Y1082268
X1437735Y1117347
X1435885Y1107780
X1424783Y1114158
X1428483Y1114158
X1437735Y1130102
X1428483Y1126914
X1424783Y1126914
X1430334Y1161992
X1434035Y1161992
X1432184Y1152425
X1428483Y1152425
X1437735Y1142858
X1424783Y1146047
X1428483Y1146047
X1434035Y1149236
X1424783Y1139669
X1428483Y1139669
X1452539Y1072701
X1448838Y1072701
X1441436Y1072701
X1452539Y1059945
X1448838Y1059945
X1443287Y1050378
X1448838Y1053567
X1443287Y1056756
X1441436Y1053567
X1441436Y1059945
X1450688Y1056756
X1452539Y1085457
X1441436Y1085457
X1448838Y1085457
X1452539Y1117347
X1441436Y1117347
X1448838Y1117347
X1439586Y1107780
X1446987Y1107780
X1450688Y1107780
X1452539Y1098213
X1441436Y1098213
X1448838Y1098213
X1441436Y1130102
X1448838Y1130102
X1445137Y1161992
X1441436Y1161992
X1452539Y1161992
X1443287Y1152425
X1452539Y1142858
X1445137Y1149236
X1441436Y1142858
X1448838Y1142858
X1459940Y1072701
X1463641Y1072701
X1459940Y1059945
X1458090Y1050378
X1465491Y1056756
X1463641Y1059945
X1458090Y1056756
X1463641Y1053567
X1456239Y1053567
X1459940Y1085457
X1463641Y1085457
X1463641Y1117347
X1459940Y1117347
X1459940Y1098213
X1463641Y1098213
X1456239Y1161992
X1463641Y1161992
X1467342Y1161992
X1454389Y1152425
X1465491Y1152425
X1467342Y1149236
X1456239Y1149236
X1459940Y1142858
X1463641Y1142858
X1463641Y1130102
X1459940Y1130102
X1474743Y1072701
X1471043Y1059945
X1474743Y1059945
X1471043Y1053567
X1472893Y1056756
X1471043Y1072701
X1471043Y1098213
X1474743Y1098213
X1471043Y1085457
X1474743Y1085457
X1471043Y1117347
X1474743Y1117347
X1471043Y1130102
X1474743Y1130102
X1474743Y1161992
X1478444Y1161992
X1476594Y1152425
X1478444Y1149236
X1471043Y1142858
X1474743Y1142858
X1487696Y1158803
X1485846Y1161992
X1489547Y1161992
X0404925Y0908324
X0379020Y0876435
X0371618Y0876435
X0367917Y0876435
X0379020Y0889191
X0375319Y0882813
X0371618Y0882813
X0386421Y0895569
X0390122Y0889191
X0382721Y0895569
X0380870Y0886002
X0393823Y0895569
X0391973Y0886002
X0390122Y0876435
X0382721Y0876435
X0393823Y0876435
X0382721Y0908325
X0386421Y0908325
X0393823Y0908325
X0386421Y0940214
X0382721Y0940214
X0393823Y0940214
X0386421Y0921080
X0382721Y0921080
X0393823Y0921080
X0386421Y0952970
X0382721Y0952970
X0393823Y0952970
X0382721Y0978482
X0395673Y0981671
X0393823Y0978482
X0386421Y0965726
X0382721Y0965726
X0393823Y0965726
X0386421Y0978482
X0404925Y0895569
X0408626Y0895569
X0401225Y0889191
X0403075Y0886002
X0397524Y0895569
X0401225Y0876435
X0404925Y0876435
X0404925Y0921080
X0408626Y0921080
X0397524Y0921080
X0408626Y0908325
X0397524Y0908325
X0404925Y0952970
X0408626Y0952970
X0397524Y0952970
X0404925Y0940214
X0408626Y0940214
X0406776Y0930647
X0410477Y0930647
X0397524Y0940214
X0403075Y0988049
X0410477Y0988049
X0404925Y0984860
X0403075Y0981671
X0410477Y0981671
X0408626Y0978482
X0404925Y0978482
X0397524Y0984860
X0397524Y0978482
X0404925Y0965726
X0408626Y0965726
X0397524Y0965726
X0416028Y0908325
X0419729Y0908325
X0414177Y0886002
X0416028Y0895569
X0419729Y0895569
X0423429Y0889191
X0425280Y0886002
X0412327Y0889191
X0423429Y0876435
X0412327Y0876435
X0416028Y0876435
X0419729Y0940214
X0416028Y0940214
X0421579Y0930647
X0417878Y0930647
X0419729Y0921080
X0416028Y0921080
X0416028Y0965726
X0419729Y0965726
X0419729Y0952970
X0416028Y0952970
X0425280Y0988049
X0417878Y0988049
X0419729Y0984860
X0417878Y0981671
X0425280Y0981671
X0419729Y0978482
X0416028Y0978482
X0412327Y0984860
X0432681Y0898758
X0428981Y0898758
X0432681Y0911513
X0428981Y0911513
X0432681Y0892380
X0428981Y0892380
X0427130Y0876435
X0432681Y0956159
X0432681Y0943403
X0428981Y0956159
X0428981Y0943403
X0430831Y0933836
X0427130Y0933836
X0432681Y0924269
X0428981Y0924269
X0434532Y0984860
X0432681Y0981671
X0427130Y0984860
X0432681Y0968915
X0428981Y0968915
X0453011Y0876435
X0447460Y0924269
X0451160Y0924269
X0447460Y0898758
X0451160Y0898758
X0447460Y0911513
X0451160Y0911513
X0447460Y0892380
X0451160Y0892380
X0454861Y0886002
X0451160Y0886002
X0449310Y0984860
X0451160Y0981671
X0447460Y0968915
X0451160Y0968915
X0447460Y0956159
X0447460Y0943403
X0451160Y0956159
X0451160Y0943403
X0453011Y0933836
X0449310Y0933836
X0464113Y0895569
X0467814Y0889191
X0465964Y0886002
X0460412Y0895569
X0456712Y0889191
X0464113Y0876435
X0467814Y0876435
X0456712Y0876435
X0464113Y0952970
X0460412Y0952970
X0464113Y0940214
X0469664Y0930647
X0460412Y0940214
X0458562Y0930647
X0462263Y0930647
X0464113Y0921080
X0460412Y0921080
X0464113Y0908325
X0460412Y0908325
X0458562Y0988049
X0464113Y0984860
X0465964Y0981671
X0464113Y0978482
X0456712Y0984860
X0458562Y0981671
X0460412Y0978482
X0464113Y0965726
X0460412Y0965726
X0482617Y0895569
X0478916Y0889191
X0471515Y0895569
X0475215Y0895569
X0477066Y0886002
X0478916Y0876435
X0475215Y0876435
X0482617Y0940214
X0475215Y0940214
X0471515Y0940214
X0473365Y0930647
X0482617Y0921080
X0471515Y0921080
X0475215Y0921080
X0482617Y0908325
X0471515Y0908325
X0475215Y0908325
X0473365Y0988049
X0480767Y0981671
X0482617Y0978482
X0478916Y0984860
X0471515Y0984860
X0473365Y0981671
X0471515Y0978482
X0475215Y0978482
X0482617Y0965726
X0471515Y0965726
X0475215Y0965726
X0482617Y0952970
X0471515Y0952970
X0475215Y0952970
X0497420Y0895569
X0499271Y0886002
X0486318Y0895569
X0493719Y0895569
X0490019Y0889191
X0488168Y0886002
X0497420Y0876435
X0490019Y0876435
X0486318Y0876435
X0497420Y0940214
X0486318Y0940214
X0493719Y0940214
X0497420Y0921080
X0486318Y0921080
X0493719Y0921080
X0497420Y0908325
X0486318Y0908325
X0493719Y0908325
X0488168Y0988049
X0497420Y0978482
X0495570Y0981671
X0486318Y0984860
X0493719Y0984860
X0488168Y0981671
X0486318Y0978482
X0493719Y0978482
X0497420Y0965726
X0486318Y0965726
X0493719Y0965726
X0497420Y0952970
X0493719Y0952970
X0486318Y0952970
X0501121Y0876435
X0512223Y0876435
X0506672Y0879624
X0508523Y0876435
X0501121Y0889191
X1381067Y0908323
X1347760Y0876434
X1344059Y0876434
X1347760Y0882812
X1355162Y0889190
X1358863Y0895568
X1362563Y0895568
X1357012Y0886001
X1351461Y0882812
X1355162Y0876434
X1358863Y0876434
X1358863Y0908324
X1362563Y0908324
X1358863Y0940213
X1362563Y0940213
X1362563Y0921079
X1358863Y0921079
X1358863Y0965725
X1362563Y0965725
X1358863Y0952969
X1362563Y0952969
X1358863Y0978481
X1362563Y0978481
X1373666Y0908324
X1369965Y0908324
X1379216Y0886001
X1377366Y0889190
X1366264Y0889190
X1373666Y0895568
X1369965Y0895568
X1368115Y0886001
X1377367Y0876434
X1366264Y0876434
X1369965Y0876434
X1373666Y0965725
X1369965Y0965725
X1373666Y0952969
X1369965Y0952969
X1373666Y0940213
X1369965Y0940213
X1373666Y0921079
X1369965Y0921079
X1379217Y0988048
X1373666Y0984859
X1379217Y0981670
X1371815Y0981670
X1373666Y0978481
X1369965Y0978481
X1388469Y0889190
X1392170Y0895568
X1390319Y0886001
X1384768Y0895568
X1381067Y0895568
X1381067Y0876434
X1392170Y0876434
X1388469Y0876434
X1392170Y0940213
X1394020Y0930646
X1381067Y0940213
X1384768Y0940213
X1386619Y0930646
X1382918Y0930646
X1392170Y0921079
X1381067Y0921079
X1384768Y0921079
X1392170Y0908324
X1384768Y0908324
X1394020Y0988048
X1386619Y0988048
X1388469Y0984859
X1394020Y0981670
X1392170Y0978481
X1381067Y0984859
X1386619Y0981670
X1384768Y0978481
X1381067Y0978481
X1392170Y0965725
X1381067Y0965725
X1384768Y0965725
X1392170Y0952969
X1381067Y0952969
X1384768Y0952969
X1405123Y0892379
X1408823Y0892379
X1399571Y0889190
X1395871Y0895568
X1401422Y0886001
X1403272Y0876434
X1399571Y0876434
X1403272Y0933835
X1406973Y0933835
X1395871Y0940213
X1397721Y0930646
X1405123Y0924268
X1408823Y0924268
X1395871Y0921079
X1405123Y0898757
X1408823Y0898757
X1405123Y0911512
X1408823Y0911512
X1395871Y0908324
X1401422Y0988048
X1403272Y0984859
X1408823Y0981670
X1395871Y0984859
X1401422Y0981670
X1395871Y0978481
X1408823Y0968914
X1395871Y0965725
X1405123Y0968914
X1408823Y0956158
X1405123Y0956158
X1408823Y0943402
X1405123Y0943402
X1395871Y0952969
X1423602Y0924268
X1423602Y0898757
X1423602Y0911512
X1423602Y0892379
X1410674Y0984859
X1423602Y0968914
R02Y-0012756
X1436554Y0895568
X1432854Y0889190
X1427302Y0892379
X1427302Y0886001
X1431003Y0886001
X1432854Y0876434
X1429153Y0876434
X1427302Y0898757
X1436554Y0908324
X1427302Y0911512
X1436554Y0940213
X1438405Y0930646
X1434704Y0930646
X1425452Y0933835
X1429153Y0933835
X1436554Y0921079
X1427302Y0924268
X1436554Y0952969
X1427302Y0956158
X1427302Y0943402
X1436554Y0965725
X1427302Y0968914
X1434704Y0988048
X1436554Y0978481
X1432854Y0984859
X1425452Y0984859
X1434704Y0981670
X1427302Y0981670
X1451358Y0876434
X1440255Y0876434
X1443956Y0876434
X1451357Y0908324
X1440255Y0908324
X1447657Y0908324
X1451358Y0895568
X1453208Y0886001
X1440255Y0895568
X1447657Y0895568
X1443956Y0889190
X1442106Y0886001
X1451357Y0952969
X1440255Y0952969
X1447657Y0952969
X1451357Y0940213
X1440255Y0940213
X1447657Y0940213
X1449507Y0930646
X1445806Y0930646
X1451357Y0921079
X1440255Y0921079
X1447657Y0921079
X1449507Y0988048
X1451357Y0978481
X1440255Y0984859
X1447657Y0984859
X1449507Y0981670
X1442106Y0981670
X1447657Y0978481
X1440255Y0978481
X1451357Y0965725
X1447657Y0965725
X1440255Y0965725
X1455058Y0889190
X1466161Y0889190
X1462460Y0895568
X1458759Y0895568
X1464310Y0886001
X1466161Y0876434
X1455058Y0876434
X1462460Y0876434
X1462460Y0908324
X1458759Y0908324
X1458759Y0940213
X1462460Y0940213
X1462460Y0921079
X1458759Y0921079
X1458759Y0965725
X1462460Y0965725
X1462460Y0952969
X1458759Y0952969
X1464310Y0988048
X1455058Y0984859
X1462460Y0984859
X1456909Y0981670
X1464310Y0981670
X1458759Y0978481
X1462460Y0978481
X1477263Y0876434
X1473562Y0876434
X1482814Y0879623
X1473562Y0908324
X1469861Y0908324
X1469861Y0895568
X1473562Y0895568
X1477263Y0889190
X1475413Y0886001
X1473562Y0940213
X1469861Y0940213
X1469861Y0921079
X1473562Y0921079
X1469861Y0952969
X1473562Y0952969
X1469861Y0984859
X1469861Y0978481
X1473562Y0978481
X1471712Y0981670
X1469861Y0965725
X1473562Y0965725
X1488365Y0876434
X1484665Y0876434
X0483798Y1034434
X0390122Y0984860
X0388272Y0981671
X0382721Y0984860
X0380870Y0981671
X0390122Y1003994
X0388272Y1007183
X0382721Y1003994
X0380870Y1007183
X0388272Y1000805
X0390122Y0991238
X0388272Y0988049
X0390122Y0997616
X0388272Y0994427
X0380870Y1000805
X0382721Y0991238
X0382721Y0997616
X0380870Y0994427
X0380870Y0988049
X0395673Y1000805
X0395673Y0988049
X0395673Y0994427
X0397524Y0991238
X1459940Y1034433
X1364414Y1000804
X1357012Y1000804
X1364414Y0994426
X1364414Y0988048
X1358863Y0991237
X1357012Y0994426
X1358863Y0997615
X1357012Y0988048
X1358863Y0984859
X1364414Y0981670
X1357012Y0981670
X1364414Y1007182
X1358863Y1003993
X1357012Y1007182
X1366264Y1003993
X1366264Y0991237
X1366264Y0997615
X1371815Y1000804
R02Y-0006378
X1373666Y0991237
X1366264Y0984859
X0404256Y1050379
X0406107Y1047190
X0398705Y1047190
X0398705Y1040812
X0404256Y1044001
X0406104Y1040820
X0419059Y1050379
X0420910Y1047190
X0413508Y1047190
X0420897Y1040820
X0413496Y1040820
X0433862Y1050379
X0435713Y1047190
X0428311Y1047190
X0428299Y1040820
X0450491Y1047190
X0459743Y1050379
X0465294Y1047190
X0457893Y1047190
X0465307Y1040820
X0457905Y1040820
X0474546Y1050379
X0480097Y1047190
X0472696Y1047190
X0480097Y1040812
X0481948Y1037623
X0481948Y1044001
X0472708Y1040820
X0489349Y1050379
X0487499Y1047190
X0494901Y1047190
X0496751Y1037623
X0496751Y1044001
X0489349Y1037623
X0487499Y1040812
X0489349Y1044001
X0494901Y1040812
X0502302Y1040812
X0502302Y1066324
X0513405Y1066324
X0513405Y1047190
X0502302Y1053568
X0502302Y1047190
X0502302Y1079080
X0513405Y1085458
X0500452Y1101403
X0502302Y1091836
X0513405Y1104592
X0502302Y1123726
X0513405Y1123726
X0502302Y1110970
X0502302Y1136481
X0513405Y1142859
X0515255Y1037623
R02Y0019134
X0515255Y1114159
X0515255Y1095025
X0515255Y1133293
X0515255Y1152426
X0539310Y1066324
X0539310Y1047190
X0541160Y1056757
X0539310Y1104592
X0541160Y1095025
X0541160Y1075891
X0539310Y1085458
X0541160Y1133293
X0539310Y1123726
X0541160Y1114159
X0541160Y1152426
X0539310Y1142859
X0567066Y1075891
X0565215Y1085458
X0565215Y1066324
X0567066Y1056757
X0565215Y1123726
X0567066Y1133293
R02Y-0019134
X0565215Y1104592
X0567066Y1152426
X0563365Y1158804
X0565215Y1142859
X1374847Y1040811
X1374847Y1047189
X1380398Y1050378
X1389650Y1047189
X1382249Y1047189
X1389638Y1040819
X1382246Y1040819
X1380398Y1044000
X1404441Y1040819
X1397039Y1040819
X1395201Y1050378
X1404453Y1047189
X1397052Y1047189
X1410004Y1050378
X1411855Y1047189
X1435885Y1050378
X1426633Y1047189
X1434035Y1047189
X1434047Y1040819
X1450688Y1050378
X1448838Y1047189
X1441436Y1047189
X1448850Y1040819
X1441449Y1040819
X1465491Y1050378
X1456239Y1047189
X1463641Y1047189
X1456239Y1040811
X1463641Y1040811
X1465491Y1044000
X1465491Y1037622
X1458090Y1044000
X1458090Y1037622
X1472893Y1044000
X1472893Y1037622
X1471043Y1040811
X1478444Y1040811
X1478444Y1066323
X1478444Y1053567
X1471043Y1047189
X1478444Y1047189
X1476594Y1101402
X1478444Y1091835
X1478444Y1079079
X1478444Y1110969
X1478444Y1123725
X1478444Y1136480
X1491397Y1056756
X1489547Y1047189
X1491397Y1037622
X1489547Y1066323
X1489547Y1085457
X1491397Y1075890
X1489547Y1104591
X1491397Y1095024
X1491397Y1114158
X1489547Y1123725
X1491397Y1133292
X1491397Y1152425
X1489547Y1142858
X1515452Y1066323
X1515452Y1047189
X1517302Y1056756
X1517302Y1095024
X1515452Y1104591
X1517302Y1075890
X1515452Y1085457
X1515452Y1123725
X1517302Y1133292
X1517302Y1114158
X1517302Y1152425
X1515452Y1142858
X1541357Y1066323
X1543208Y1056756
X1543208Y1075890
X1541357Y1085457
X1543208Y1095024
X1541357Y1104591
X1541357Y1123725
X1543208Y1133292
X1543208Y1114158
X1543208Y1152425
X1539507Y1158803
X1541357Y1142858
X0483798Y1155615
X1459940Y1155614
X0470845Y1088647
X0470845Y1095025
X0470845Y1082269
X0459743Y1088647
R02Y0006378
X0459743Y1082269
X0450491Y1098214
X0450491Y1091836
X0493050Y1088647
X0493050Y1095025
X0493050Y1082269
X0481948Y1088647
X0481948Y1095025
X0481948Y1082269
X0450491Y1085458
X0474546Y1088647
X0474546Y1095025
X0474546Y1082269
X0463444Y1088647
R02Y0006378
X0463444Y1082269
X0454192Y1098214
X0454192Y1091836
X0496751Y1088647
X0496751Y1095025
X0496751Y1082269
X0485649Y1088647
X0485649Y1095025
X0485649Y1082269
X0454192Y1085458
X0496422Y1519698
X0485649Y1133293
X0491698Y1519698
X0474546Y1139670
X0486973Y1519698
X0474546Y1146048
X0482249Y1519698
X0474546Y1133293
X0477525Y1519698
X0463444Y1139670
X0472800Y1519698
X0463444Y1146048
X0468076Y1519698
X0463444Y1133293
X0463351Y1519698
X0454192Y1142859
X0458627Y1519698
X0454192Y1136481
X0524769Y1519698
X0496751Y1126915
X0520044Y1519698
X0496751Y1139670
X0515320Y1519698
X0496751Y1146048
X0510595Y1519698
X0496751Y1133293
X0505871Y1519698
X0485649Y1139670
X0501147Y1519698
X0485649Y1146048
X0453903Y1519698
X0454192Y1130103
X0494847Y1516970
X0481948Y1133293
X0490123Y1516970
X0470845Y1139670
X0485399Y1516970
X0470845Y1146048
X0480674Y1516970
X0470845Y1133293
X0475950Y1516970
X0459743Y1139670
X0471225Y1516970
X0459743Y1146048
X0466501Y1516970
X0459743Y1133293
X0461777Y1516970
X0450491Y1142859
X0457052Y1516970
X0450491Y1136481
X0523194Y1516970
X0493050Y1126915
X0518470Y1516970
X0493050Y1139670
X0513745Y1516970
X0493050Y1146048
X0509021Y1516970
X0493050Y1133293
X0504296Y1516970
X0481948Y1139670
X0499572Y1516970
X0481948Y1146048
X0452328Y1516970
X0450491Y1130103
X0470845Y1069513
X0470845Y1075891
X0470845Y1063135
X0459743Y1069513
X0459743Y1075891
X0459743Y1063135
X0450491Y1072702
X0450491Y1079080
X0450491Y1066324
X0493050Y1069513
X0493050Y1075891
X0493050Y1063135
X0481948Y1069513
X0481948Y1075891
X0481948Y1063135
X0450491Y1059946
X0474546Y1069513
X0474546Y1075891
X0474546Y1063135
X0463444Y1069513
X0463444Y1075891
X0463444Y1063135
X0454192Y1072702
X0454192Y1079080
X0454192Y1066324
X0496751Y1069513
X0496751Y1075891
X0496751Y1063135
X0485649Y1069513
X0485649Y1075891
X0485649Y1063135
X0454192Y1059946
X0624484Y1519698
X0485649Y1107781
X0619760Y1519698
X0474546Y1120537
X0615035Y1519698
X0474546Y1126915
X0610311Y1519698
X0474546Y1114159
X0605587Y1519698
X0463444Y1120537
X0600862Y1519698
X0463444Y1126915
X0596138Y1519698
X0463444Y1114159
X0591413Y1519698
X0454192Y1123726
X0586689Y1519698
X0454192Y1117348
X0652831Y1519698
X0496751Y1114159
X0648106Y1519698
X0496751Y1120537
X0643382Y1519698
X0496751Y1107781
X0638657Y1519698
X0485649Y1114159
X0633933Y1519698
X0485649Y1120537
X0629209Y1519698
X0485649Y1126915
X0581965Y1519698
X0454192Y1110970
X0622909Y1516970
X0481948Y1107781
X0618185Y1516970
X0470845Y1120537
X0613461Y1516970
X0470845Y1126915
X0608736Y1516970
X0470845Y1114159
X0604012Y1516970
X0459743Y1120537
X0599287Y1516970
X0459743Y1126915
X0594563Y1516970
X0459743Y1114159
X0589839Y1516970
X0450491Y1123726
X0585114Y1516970
X0450491Y1117348
X0651256Y1516970
X0493050Y1114159
X0646532Y1516970
X0493050Y1120537
X0641807Y1516970
X0493050Y1107781
X0637083Y1516970
X0481948Y1114159
X0632358Y1516970
X0481948Y1120537
X0627634Y1516970
X0481948Y1126915
X0580390Y1516970
X0450491Y1110970
X0407957Y1133293
X0407957Y1146048
X0407957Y1139670
X0396855Y1133293
X0396855Y1146048
X0396855Y1139670
X0385752Y1133293
X0385752Y1146048
X0385752Y1139670
X0428311Y1130103
R02Y0006378
X0419059Y1133293
X0419059Y1146048
X0419059Y1139670
X0385752Y1126915
X0411658Y1133293
X0411658Y1146048
X0411658Y1139670
X0400555Y1133293
X0400555Y1146048
X0400555Y1139670
X0389453Y1133293
X0389453Y1146048
X0389453Y1139670
X0432012Y1130103
R02Y0006378
X0422760Y1133293
X0422760Y1146048
X0422760Y1139670
X0389453Y1126915
X0422760Y1088647
X0360311Y1519698
X0411658Y1082269
X0355587Y1519698
X0411658Y1095025
X0350862Y1519698
X0411658Y1088647
X0346138Y1519698
X0400555Y1082269
X0341414Y1519698
X0400555Y1095025
X0336689Y1519698
X0400555Y1088647
X0331965Y1519698
X0389453Y1082269
X0327240Y1519698
X0389453Y1095025
X0322516Y1519698
X0432012Y1085458
X0388658Y1519698
X0432012Y1091836
X0383933Y1519698
X0432012Y1098214
X0379209Y1519698
X0422760Y1082269
X0374484Y1519698
X0422760Y1101403
X0369760Y1519698
X0422760Y1095025
X0365036Y1519698
X0389453Y1088647
X0317792Y1519698
X0419059Y1088647
X0358736Y1516970
X0407957Y1082269
X0354012Y1516970
X0407957Y1095025
X0349288Y1516970
X0407957Y1088647
X0344563Y1516970
X0396855Y1082269
X0339839Y1516970
X0396855Y1095025
X0335114Y1516970
X0396855Y1088647
X0330390Y1516970
X0385752Y1082269
X0325666Y1516970
X0385752Y1095025
X0320941Y1516970
X0428311Y1085458
X0387083Y1516970
X0428311Y1091836
X0382359Y1516970
X0428311Y1098214
X0377634Y1516970
X0419059Y1082269
X0372910Y1516970
X0419059Y1101403
X0368185Y1516970
X0419059Y1095025
X0363461Y1516970
X0385752Y1088647
X0316217Y1516970
X0407957Y1114159
X0407957Y1126915
X0407957Y1120537
X0396855Y1107781
X0396855Y1126915
X0396855Y1120537
X0396855Y1114159
X0385752Y1107781
X0385752Y1120537
X0428311Y1110970
R02Y0006378
X0419059Y1114159
X0419059Y1126915
X0419059Y1120537
X0385752Y1114159
X0411658Y1114159
X0411658Y1126915
X0411658Y1120537
X0400555Y1107781
X0400555Y1126915
X0400555Y1120537
X0400555Y1114159
X0389453Y1107781
X0389453Y1120537
X0432012Y1110970
R02Y0006378
X0422760Y1114159
X0422760Y1126915
X0422760Y1120537
X0389453Y1114159
X0422760Y1069513
X0232249Y1519698
X0411658Y1063135
X0227525Y1519698
X0411658Y1075891
X0222800Y1519698
X0411658Y1069513
X0218076Y1519698
X0400555Y1063135
X0213352Y1519698
X0400555Y1075891
X0208627Y1519698
X0400555Y1069513
X0203903Y1519698
X0389453Y1063135
X0199178Y1519698
X0389453Y1075891
X0194454Y1519698
X0432012Y1059946
X0260596Y1519698
X0432012Y1066324
X0255871Y1519698
X0432012Y1079080
X0251147Y1519698
X0432012Y1072702
X0246422Y1519698
X0422760Y1063135
X0241698Y1519698
X0422760Y1075891
X0236974Y1519698
X0389453Y1069513
X0189730Y1519698
X0419059Y1069513
X0230674Y1516970
X0407957Y1063135
X0225950Y1516970
X0407957Y1075891
X0221226Y1516970
X0407957Y1069513
X0216501Y1516970
X0396855Y1063135
X0211777Y1516970
X0396855Y1075891
X0207052Y1516970
X0396855Y1069513
X0202328Y1516970
X0385752Y1063135
X0197604Y1516970
X0385752Y1075891
X0192879Y1516970
X0428311Y1059946
X0259021Y1516970
X0428311Y1066324
X0254297Y1516970
X0428311Y1079080
X0249572Y1516970
X0428311Y1072702
X0244848Y1516970
X0419059Y1063135
X0240123Y1516970
X0419059Y1075891
X0235399Y1516970
X0385752Y1069513
X0188155Y1516970
X1446987Y1082268
X1435885Y1088646
R02Y0006378
X1450688Y1082268
X1439586Y1088646
R02Y0006378
X1494847Y1552698
X1450688Y1146047
X1490123Y1552698
X1450688Y1133292
X1485399Y1552698
X1439586Y1139669
X1480674Y1552698
X1439586Y1146047
X1493273Y1549970
X1446987Y1146047
X1488548Y1549970
X1446987Y1133292
X1483824Y1549970
X1435885Y1139669
X1479099Y1549970
X1435885Y1146047
X1446987Y1069512
X1446987Y1075890
X1446987Y1063134
X1435885Y1069512
X1435885Y1075890
X1435885Y1063134
X1426633Y1072701
X1426633Y1079079
X1426633Y1066323
X1469192Y1069512
X1469192Y1075890
X1469192Y1063134
X1458090Y1069512
X1458090Y1075890
X1458090Y1063134
X1426633Y1059945
X1450688Y1069512
X1450688Y1075890
X1450688Y1063134
X1439586Y1069512
X1439586Y1075890
X1439586Y1063134
X1430334Y1072701
X1430334Y1079079
X1430334Y1066323
X1472893Y1069512
X1472893Y1075890
X1472893Y1063134
X1461791Y1069512
X1461791Y1075890
X1461791Y1063134
X1430334Y1059945
X1632358Y1552698
X1461791Y1107780
X1627634Y1552698
X1450688Y1120536
X1622909Y1552698
X1450688Y1126914
X1618185Y1552698
X1450688Y1114158
X1613461Y1552698
X1439586Y1120536
X1608736Y1552698
X1439586Y1126914
X1604012Y1552698
X1439586Y1114158
X1599287Y1552698
X1430334Y1123725
X1594563Y1552698
X1430334Y1117347
X1660705Y1552698
X1472893Y1114158
X1655980Y1552698
X1472893Y1120536
X1651256Y1552698
X1472893Y1107780
X1646531Y1552698
X1461791Y1114158
X1641807Y1552698
X1461791Y1120536
X1637083Y1552698
X1461791Y1126914
X1589839Y1552698
X1430334Y1110969
X1630783Y1549970
X1458090Y1107780
X1626059Y1549970
X1446987Y1120536
X1621335Y1549970
X1446987Y1126914
X1616610Y1549970
X1446987Y1114158
X1611886Y1549970
X1435885Y1120536
X1607161Y1549970
X1435885Y1126914
X1602437Y1549970
X1435885Y1114158
X1597713Y1549970
X1426633Y1123725
X1592988Y1549970
X1426633Y1117347
X1659130Y1549970
X1469192Y1114158
X1654406Y1549970
X1469192Y1120536
X1649681Y1549970
X1469192Y1107780
X1644957Y1549970
X1458090Y1114158
X1640232Y1549970
X1458090Y1120536
X1635508Y1549970
X1458090Y1126914
X1588264Y1549970
X1426633Y1110969
X1384099Y1133292
X1384099Y1146047
X1384099Y1139669
X1372997Y1133292
X1372997Y1146047
X1372997Y1139669
X1361894Y1133292
X1361894Y1146047
X1361894Y1139669
X1404453Y1130102
R02Y0006378
X1395201Y1133292
X1395201Y1146047
X1395201Y1139669
X1361894Y1126914
X1387800Y1133292
X1387800Y1146047
X1387800Y1139669
X1376697Y1133292
X1376697Y1146047
X1376697Y1139669
X1365595Y1133292
X1365595Y1146047
X1365595Y1139669
X1408154Y1130102
R02Y0006378
X1398902Y1133292
X1398902Y1146047
X1398902Y1139669
X1365595Y1126914
X1398902Y1088646
X1368184Y1552698
X1387800Y1082268
X1363460Y1552698
X1387800Y1095024
X1358735Y1552698
X1387800Y1088646
X1354011Y1552698
X1376697Y1082268
X1349287Y1552698
X1376697Y1095024
X1344562Y1552698
X1376697Y1088646
X1339838Y1552698
X1365595Y1082268
X1335113Y1552698
X1365595Y1095024
X1330389Y1552698
X1408154Y1085457
X1396531Y1552698
X1408154Y1091835
X1391806Y1552698
X1408154Y1098213
X1387082Y1552698
X1398902Y1082268
X1382357Y1552698
X1398902Y1101402
X1377633Y1552698
X1398902Y1095024
X1372909Y1552698
X1365595Y1088646
X1325665Y1552698
X1395201Y1088646
X1366609Y1549970
X1384099Y1082268
X1361885Y1549970
X1384099Y1095024
X1357161Y1549970
X1384099Y1088646
X1352436Y1549970
X1372997Y1082268
X1347712Y1549970
X1372997Y1095024
X1342987Y1549970
X1372997Y1088646
X1338263Y1549970
X1361894Y1082268
X1333539Y1549970
X1361894Y1095024
X1328814Y1549970
X1404453Y1085457
X1394956Y1549970
X1404453Y1091835
X1390232Y1549970
X1404453Y1098213
X1385507Y1549970
X1395201Y1082268
X1380783Y1549970
X1395201Y1101402
X1376058Y1549970
X1395201Y1095024
X1371334Y1549970
X1361894Y1088646
X1324090Y1549970
X1384099Y1114158
X1384099Y1126914
X1384099Y1120536
X1372997Y1107780
X1372997Y1126914
X1372997Y1120536
X1372997Y1114158
X1361894Y1107780
X1361894Y1120536
X1404453Y1110969
R02Y0006378
X1395201Y1114158
X1395201Y1126914
X1395201Y1120536
X1361894Y1114158
X1387800Y1114158
X1387800Y1126914
X1387800Y1120536
X1376697Y1107780
X1376697Y1126914
X1376697Y1120536
X1376697Y1114158
X1365595Y1107780
X1365595Y1120536
X1408154Y1110969
R02Y0006378
X1398902Y1114158
X1398902Y1126914
X1398902Y1120536
X1365595Y1114158
X1398902Y1069512
X1240122Y1552698
X1387800Y1063134
X1235398Y1552698
X1387800Y1075890
X1230673Y1552698
X1387800Y1069512
X1225949Y1552698
X1376697Y1063134
X1221225Y1552698
X1376697Y1075890
X1216500Y1552698
X1376697Y1069512
X1211776Y1552698
X1365595Y1063134
X1207051Y1552698
X1365595Y1075890
X1202327Y1552698
X1408154Y1059945
X1268469Y1552698
X1408154Y1066323
X1263744Y1552698
X1408154Y1079079
X1259020Y1552698
X1408154Y1072701
X1254295Y1552698
X1398902Y1063134
X1249571Y1552698
X1398902Y1075890
X1244847Y1552698
X1365595Y1069512
X1197603Y1552698
X1395201Y1069512
X1238547Y1549970
X1384099Y1063134
X1233823Y1549970
X1384099Y1075890
X1229099Y1549970
X1384099Y1069512
X1224374Y1549970
X1372997Y1063134
X1219650Y1549970
X1372997Y1075890
X1214925Y1549970
X1372997Y1069512
X1210201Y1549970
X1361894Y1063134
X1205477Y1549970
X1361894Y1075890
X1200752Y1549970
X1404453Y1059945
X1266894Y1549970
X1404453Y1066323
X1262170Y1549970
X1404453Y1079079
X1257445Y1549970
X1404453Y1072701
X1252721Y1549970
X1395201Y1063134
X1247996Y1549970
X1395201Y1075890
X1243272Y1549970
X1361894Y1069512
X1196028Y1549970
X1449507Y0924268
X1449507Y0911512
X1449507Y0917890
X1460609Y0930646
X1460609Y0911512
X1460609Y0917890
X1460609Y0924268
X1471712Y0930646
X1471712Y0917890
X1429153Y0927457
R02Y-0006378
X1438405Y0924268
X1438405Y0911512
X1438405Y0917890
X1471712Y0924268
X1445806Y0924268
X1445806Y0911512
X1445806Y0917890
X1456909Y0930646
X1456909Y0911512
X1456909Y0917890
X1456909Y0924268
X1468011Y0930646
X1468011Y0917890
X1425452Y0927457
R02Y-0006378
X1434704Y0924268
X1434704Y0911512
X1434704Y0917890
X1468011Y0924268
X1434704Y0968914
X1445806Y0975292
X1445806Y0962536
X1445806Y0968914
X1456909Y0975292
X1456909Y0962536
X1456909Y0968914
X1468011Y0975292
X1468011Y0962536
X1425452Y0978481
X1425452Y0972103
X1425452Y0959347
X1425452Y0965725
X1434704Y0975292
X1434704Y0962536
X1468011Y0968914
X1438405Y0968914
X1449507Y0975292
X1449507Y0962536
X1449507Y0968914
X1460609Y0975292
X1460609Y0962536
X1460609Y0968914
X1471712Y0975292
X1471712Y0962536
X1429153Y0978481
X1429153Y0972103
X1429153Y0959347
X1429153Y0965725
X1438405Y0975292
X1438405Y0962536
X1471712Y0968914
X1504296Y1552698
X1461791Y1133292
X1499572Y1552698
X1450688Y1139669
X1513745Y1552698
X1461791Y1139669
X1509021Y1552698
X1461791Y1146047
X1502721Y1549970
X1458090Y1133292
X1497997Y1549970
X1446987Y1139669
X1512170Y1549970
X1458090Y1139669
X1507446Y1549970
X1458090Y1146047
X1460202Y1549970
X1426633Y1130102
X1461777Y1552698
X1430334Y1130102
X1472893Y1050378
X0367248Y1158804
X0365398Y1161993
X0352445Y1165182
X0350595Y1161993
X0324689Y1161993
X0326539Y1165182
X0341343Y1165182
X0339492Y1161993
X0469664Y0886002
X0473365Y0886002
X0473365Y0879624
X0477066Y0879624
X0484467Y0879624
X0488168Y0879624
X0480767Y0886002
X0484467Y0886002
X0357996Y1161993
X0359847Y1165182
X0333941Y1165182
X0332091Y1161993
X0477066Y0873246
X0473365Y0873246
X0484467Y0873246
X0488168Y0873246
X0432012Y1161993
X0433862Y1158804
X0491869Y0886002
X0495570Y0886002
X0557814Y1161993
X0464113Y0882813
X0462263Y0873246
X0458562Y0873246
X0460412Y0882813
X0458562Y0879624
X0454861Y0873246
X0462263Y0879624
X1440255Y0882812
X1438405Y0873245
X1434704Y0873245
X1436554Y0882812
X1434704Y0879623
X1431003Y0873245
X1438405Y0879623
X0550412Y1053568
X0544861Y1044001
X0550412Y1066324
X0543011Y1149237
X0543011Y1130103
X0543011Y1110970
R02Y-0019134
X0550412Y1142859
X0550412Y1123726
X0550412Y1104592
X0550412Y1085458
X0548562Y1069513
X0544861Y1146048
X0544861Y1126915
X0544861Y1107781
R02Y-0019134
X0548562Y1146048
X0548562Y1126915
X0548562Y1107781
X0548562Y1088647
X0544861Y1101403
X0550412Y1098214
X0543011Y1098214
X0548562Y1095025
X0544861Y1095025
X0550412Y1091836
X0543011Y1085458
X0550412Y1155615
X0548562Y1152426
X0548562Y1082269
X0544861Y1152426
X0550412Y1149237
X0543011Y1142859
X0548562Y1139670
X0544861Y1139670
X0550412Y1136481
X0543011Y1136481
X0548562Y1133293
X0544861Y1133293
X0550412Y1130103
X0544861Y1082269
X0543011Y1123726
X0548562Y1120537
X0544861Y1120537
X0550412Y1117348
X0543011Y1117348
X0548562Y1114159
X0544861Y1114159
X0550412Y1110970
X0543011Y1104592
X0548562Y1101403
X0550412Y1079080
X0548562Y1050379
X0543011Y1047190
X0543011Y1066324
X0548562Y1063135
X0544861Y1063135
X0550412Y1059946
X0543011Y1079080
X0548562Y1075891
X0544861Y1075891
X0550412Y1072702
X0550412Y1040812
X0543011Y1040812
X0544861Y1037623
X0548562Y1037623
X0550412Y1034434
X0543011Y1034434
X0544861Y1031245
X0544861Y1050379
X0543680Y1007183
X0543680Y0975293
X0543680Y0956159
R02Y-0019134
X0543680Y0898758
X0547381Y0968915
R03Y-0019134
X0547381Y0892380
X0541830Y0972104
R03Y-0019134
X0541830Y0895569
X0549231Y0972104
R03Y-0019134
X0549231Y0895569
X0541830Y0908325
X0547381Y0905135
X0543680Y0905135
X0549231Y0901947
X0541830Y0901947
X0547381Y0898758
X0543680Y0892380
X0543680Y0962537
X0549231Y0959348
X0549231Y0889191
X0541830Y0959348
X0547381Y0956159
X0543680Y0949781
X0549231Y0946592
X0541830Y0946592
X0547381Y0943403
X0543680Y0943403
X0549231Y0940214
X0541830Y0940214
X0547381Y0937025
X0541830Y0889191
X0543680Y0930647
X0549231Y0927458
X0541830Y0927458
X0547381Y0924269
X0543680Y0924269
X0549231Y0921080
X0541830Y0921080
X0547381Y0917891
X0543680Y0911513
X0549231Y0908325
X0547381Y0886002
X0541830Y0991238
X0547381Y0988049
X0543680Y0981671
X0549231Y0978482
X0541830Y0978482
X0547381Y0975293
X0543680Y0968915
X0549231Y0965726
X0541830Y0965726
X0547381Y0962537
X0541830Y1003994
X0549231Y1003994
X0547381Y1000805
X0543680Y1000805
X0541830Y0997616
X0549231Y0997616
X0547381Y0994427
X0543680Y0988049
X0547381Y1007183
X0549231Y1010372
X0541830Y0984860
X1526554Y1053567
X1521003Y1044000
X1526554Y1066323
X1519153Y1149236
X1519153Y1130102
X1519153Y1110969
R02Y-0019134
X1526554Y1142858
X1526554Y1123725
X1526554Y1104591
X1526554Y1085457
X1524704Y1069512
X1521003Y1146047
X1521003Y1126914
X1521003Y1107780
R02Y-0019134
X1524704Y1146047
X1524704Y1126914
X1524704Y1107780
X1524704Y1088646
X1521003Y1101402
X1526554Y1098213
X1519153Y1098213
X1524704Y1095024
X1521003Y1095024
X1526554Y1091835
X1519153Y1085457
X1526554Y1155614
X1524704Y1152425
X1524704Y1082268
X1521003Y1152425
X1526554Y1149236
X1519153Y1142858
X1524704Y1139669
X1521003Y1139669
X1526554Y1136480
X1519153Y1136480
X1524704Y1133292
X1521003Y1133292
X1526554Y1130102
X1521003Y1082268
X1519153Y1123725
X1524704Y1120536
X1521003Y1120536
X1526554Y1117347
X1519153Y1117347
X1524704Y1114158
X1521003Y1114158
X1526554Y1110969
X1519153Y1104591
X1524704Y1101402
X1526554Y1079079
X1524704Y1050378
X1519153Y1047189
X1519153Y1066323
X1524704Y1063134
X1521003Y1063134
X1526554Y1059945
X1519153Y1079079
X1524704Y1075890
X1521003Y1075890
X1526554Y1072701
X1526554Y1040811
X1519153Y1040811
X1521003Y1037622
X1524704Y1037622
X1526554Y1034433
X1519153Y1034433
X1521003Y1031244
X1521003Y1050378
X1519822Y1007182
X1519822Y0975292
X1519822Y0956158
R02Y-0019134
X1519822Y0898757
X1523523Y0968914
R03Y-0019134
X1523523Y0892379
X1517972Y0972103
R03Y-0019134
X1517972Y0895568
X1525373Y0972103
R03Y-0019134
X1525373Y0895568
X1517972Y0908324
X1523523Y0905134
X1519822Y0905134
X1525373Y0901946
X1517972Y0901946
X1523523Y0898757
X1519822Y0892379
X1519822Y0962536
X1525373Y0959347
X1525373Y0889190
X1517972Y0959347
X1523523Y0956158
X1519822Y0949780
X1525373Y0946591
X1517972Y0946591
X1523523Y0943402
X1519822Y0943402
X1525373Y0940213
X1517972Y0940213
X1523523Y0937024
X1517972Y0889190
X1519822Y0930646
X1525373Y0927457
X1517972Y0927457
X1523523Y0924268
X1519822Y0924268
X1525373Y0921079
X1517972Y0921079
X1523523Y0917890
X1519822Y0911512
X1525373Y0908324
X1523523Y0886001
X1517972Y0991237
X1523523Y0988048
X1519822Y0981670
X1525373Y0978481
X1517972Y0978481
X1523523Y0975292
X1519822Y0968914
X1525373Y0965725
X1517972Y0965725
X1523523Y0962536
X1517972Y1003993
X1525373Y1003993
X1523523Y1000804
X1519822Y1000804
X1517972Y0997615
X1525373Y0997615
X1523523Y0994426
X1519822Y0988048
X1523523Y1007182
X1525373Y1010371
X1517972Y0984859
X0561515Y1053568
X0555964Y1044001
X0561515Y1066324
X0557814Y1149237
X0557814Y1130103
X0557814Y1110970
R02Y-0019134
X0561515Y1142859
X0561515Y1123726
X0561515Y1104592
X0561515Y1085458
X0563365Y1069513
X0555964Y1146048
X0555964Y1126915
X0555964Y1107781
R02Y-0019134
X0563365Y1146048
X0563365Y1126915
X0563365Y1107781
X0563365Y1088647
X0555964Y1101403
X0561515Y1098214
X0557814Y1098214
X0563365Y1095025
X0555964Y1095025
X0561515Y1091836
X0557814Y1085458
X0557814Y1155615
X0563365Y1152426
X0563365Y1082269
X0555964Y1152426
X0561515Y1149237
X0557814Y1142859
X0563365Y1139670
X0555964Y1139670
X0561515Y1136481
X0557814Y1136481
X0563365Y1133293
X0555964Y1133293
X0561515Y1130103
X0555964Y1082269
X0557814Y1123726
X0563365Y1120537
X0555964Y1120537
X0561515Y1117348
X0557814Y1117348
X0563365Y1114159
X0555964Y1114159
X0561515Y1110970
X0557814Y1104592
X0563365Y1101403
X0561515Y1079080
X0563365Y1050379
X0557814Y1047190
X0557814Y1066324
X0563365Y1063135
X0555964Y1063135
X0561515Y1059946
X0557814Y1079080
X0563365Y1075891
X0555964Y1075891
X0561515Y1072702
X0561515Y1040812
X0557814Y1040812
X0555964Y1037623
X0563365Y1037623
X0561515Y1034434
X0557814Y1034434
X0555964Y1031245
X0555964Y1050379
X0554783Y1007183
X0554783Y0975293
X0554783Y0956159
R02Y-0019134
X0554783Y0898758
X0562184Y0968915
R03Y-0019134
X0562184Y0892380
X0556633Y0972104
R03Y-0019134
X0556633Y0895569
X0560334Y0972104
R03Y-0019134
X0560334Y0895569
X0556633Y0908325
X0562184Y0905135
X0554783Y0905135
X0560334Y0901947
X0556633Y0901947
X0562184Y0898758
X0554783Y0892380
X0554783Y0962537
X0560334Y0959348
X0560334Y0889191
X0556633Y0959348
X0562184Y0956159
X0554783Y0949781
X0560334Y0946592
X0556633Y0946592
X0562184Y0943403
X0554783Y0943403
X0560334Y0940214
X0556633Y0940214
X0562184Y0937025
X0556633Y0889191
X0554783Y0930647
X0560334Y0927458
X0556633Y0927458
X0562184Y0924269
X0554783Y0924269
X0560334Y0921080
X0556633Y0921080
X0562184Y0917891
X0554783Y0911513
X0560334Y0908325
X0562184Y0886002
X0556633Y0991238
X0562184Y0988049
X0554783Y0981671
X0560334Y0978482
X0556633Y0978482
X0562184Y0975293
X0554783Y0968915
X0560334Y0965726
X0556633Y0965726
X0562184Y0962537
X0556633Y1003994
X0560334Y1003994
X0562184Y1000805
X0554783Y1000805
X0556633Y0997616
X0560334Y0997616
X0562184Y0994427
X0554783Y0988049
X0562184Y1007183
X0560334Y1010372
X0556633Y0984860
X1537657Y1053567
X1532106Y1044000
X1537657Y1066323
X1533956Y1149236
X1533956Y1130102
X1533956Y1110969
R02Y-0019134
X1537657Y1142858
X1537657Y1123725
X1537657Y1104591
X1537657Y1085457
X1539507Y1069512
X1532106Y1146047
X1532106Y1126914
X1532106Y1107780
R02Y-0019134
X1539507Y1146047
X1539507Y1126914
X1539507Y1107780
X1539507Y1088646
X1532106Y1101402
X1537657Y1098213
X1533956Y1098213
X1539507Y1095024
X1532106Y1095024
X1537657Y1091835
X1533956Y1085457
X1533956Y1155614
X1539507Y1152425
X1539507Y1082268
X1532106Y1152425
X1537657Y1149236
X1533956Y1142858
X1539507Y1139669
X1532106Y1139669
X1537657Y1136480
X1533956Y1136480
X1539507Y1133292
X1532106Y1133292
X1537657Y1130102
X1532106Y1082268
X1533956Y1123725
X1539507Y1120536
X1532106Y1120536
X1537657Y1117347
X1533956Y1117347
X1539507Y1114158
X1532106Y1114158
X1537657Y1110969
X1533956Y1104591
X1539507Y1101402
X1537657Y1079079
X1539507Y1050378
X1533956Y1047189
X1533956Y1066323
X1539507Y1063134
X1532106Y1063134
X1537657Y1059945
X1533956Y1079079
X1539507Y1075890
X1532106Y1075890
X1537657Y1072701
X1537657Y1040811
X1533956Y1040811
X1532106Y1037622
X1539507Y1037622
X1537657Y1034433
X1533956Y1034433
X1532106Y1031244
X1532106Y1050378
X1530925Y1007182
X1530925Y0975292
X1530925Y0956158
R02Y-0019134
X1530925Y0898757
X1538326Y0968914
R03Y-0019134
X1538326Y0892379
X1532775Y0972103
R03Y-0019134
X1532775Y0895568
X1536476Y0972103
R03Y-0019134
X1536476Y0895568
X1532775Y0908324
X1538326Y0905134
X1530925Y0905134
X1536476Y0901946
X1532775Y0901946
X1538326Y0898757
X1530925Y0892379
X1530925Y0962536
X1536476Y0959347
X1536476Y0889190
X1532775Y0959347
X1538326Y0956158
X1530925Y0949780
X1536476Y0946591
X1532775Y0946591
X1538326Y0943402
X1530925Y0943402
X1536476Y0940213
X1532775Y0940213
X1538326Y0937024
X1532775Y0889190
X1530925Y0930646
X1536476Y0927457
X1532775Y0927457
X1538326Y0924268
X1530925Y0924268
X1536476Y0921079
X1532775Y0921079
X1538326Y0917890
X1530925Y0911512
X1536476Y0908324
X1538326Y0886001
X1532775Y0991237
X1538326Y0988048
X1530925Y0981670
X1536476Y0978481
X1532775Y0978481
X1538326Y0975292
X1530925Y0968914
X1536476Y0965725
X1532775Y0965725
X1538326Y0962536
X1532775Y1003993
X1536476Y1003993
X1538326Y1000804
X1530925Y1000804
X1532775Y0997615
X1536476Y0997615
X1538326Y0994426
X1530925Y0988048
X1538326Y1007182
X1536476Y1010371
X1532775Y0984859
X0524507Y1053568
X0518956Y1044001
X0524507Y1066324
X0517105Y1149237
X0517105Y1130103
X0517105Y1110970
R02Y-0019134
X0524507Y1142859
X0524507Y1123726
X0524507Y1104592
X0524507Y1085458
X0522657Y1069513
X0518956Y1146048
X0518956Y1126915
X0518956Y1107781
R02Y-0019134
X0522657Y1146048
X0522657Y1126915
X0522657Y1107781
X0522657Y1088647
X0518956Y1101403
X0524507Y1098214
X0517105Y1098214
X0522657Y1095025
X0518956Y1095025
X0524507Y1091836
X0517105Y1085458
X0524507Y1155615
X0522657Y1152426
X0522657Y1082269
X0518956Y1152426
X0524507Y1149237
X0517105Y1142859
X0522657Y1139670
X0518956Y1139670
X0524507Y1136481
X0517105Y1136481
X0522657Y1133293
X0518956Y1133293
X0524507Y1130103
X0518956Y1082269
X0517105Y1123726
X0522657Y1120537
X0518956Y1120537
X0524507Y1117348
X0517105Y1117348
X0522657Y1114159
X0518956Y1114159
X0524507Y1110970
X0517105Y1104592
X0522657Y1101403
X0524507Y1079080
X0522657Y1050379
X0517105Y1047190
X0517105Y1066324
X0522657Y1063135
X0518956Y1063135
X0524507Y1059946
X0517105Y1079080
X0522657Y1075891
X0518956Y1075891
X0524507Y1072702
X0524507Y1040812
X0517105Y1040812
X0518956Y1037623
X0522657Y1037623
X0524507Y1034434
X0517105Y1034434
X0518956Y1031245
X0518956Y1050379
X0517775Y1007183
X0517775Y0975293
X0517775Y0956159
R02Y-0019134
X0517775Y0898758
X0521475Y0968915
R03Y-0019134
X0521475Y0892380
X0515924Y0972104
R03Y-0019134
X0515924Y0895569
X0523326Y0972104
R03Y-0019134
X0523326Y0895569
X0515924Y0908325
X0521475Y0905135
X0517775Y0905135
X0523326Y0901947
X0515924Y0901947
X0521475Y0898758
X0517775Y0892380
X0517775Y0962537
X0523326Y0959348
X0523326Y0889191
X0515924Y0959348
X0521475Y0956159
X0517775Y0949781
X0523326Y0946592
X0515924Y0946592
X0521475Y0943403
X0517775Y0943403
X0523326Y0940214
X0515924Y0940214
X0521475Y0937025
X0515924Y0889191
X0517775Y0930647
X0523326Y0927458
X0515924Y0927458
X0521475Y0924269
X0517775Y0924269
X0523326Y0921080
X0515924Y0921080
X0521475Y0917891
X0517775Y0911513
X0523326Y0908325
X0521475Y0886002
X0515924Y0991238
X0521475Y0988049
X0517775Y0981671
X0523326Y0978482
X0515924Y0978482
X0521475Y0975293
X0517775Y0968915
X0523326Y0965726
X0515924Y0965726
X0521475Y0962537
X0515924Y1003994
X0523326Y1003994
X0521475Y1000805
X0517775Y1000805
X0515924Y0997616
X0523326Y0997616
X0521475Y0994427
X0517775Y0988049
X0521475Y1007183
X0523326Y1010372
X0515924Y0984860
X1500649Y1053567
X1495098Y1044000
X1500649Y1066323
X1493247Y1149236
X1493247Y1130102
X1493247Y1110969
R02Y-0019134
X1500649Y1142858
X1500649Y1123725
X1500649Y1104591
X1500649Y1085457
X1498799Y1069512
X1495098Y1146047
X1495098Y1126914
X1495098Y1107780
R02Y-0019134
X1498799Y1146047
X1498799Y1126914
X1498799Y1107780
X1498799Y1088646
X1495098Y1101402
X1500649Y1098213
X1493247Y1098213
X1498799Y1095024
X1495098Y1095024
X1500649Y1091835
X1493247Y1085457
X1500649Y1155614
X1498799Y1152425
X1498799Y1082268
X1495098Y1152425
X1500649Y1149236
X1493247Y1142858
X1498799Y1139669
X1495098Y1139669
X1500649Y1136480
X1493247Y1136480
X1498799Y1133292
X1495098Y1133292
X1500649Y1130102
X1495098Y1082268
X1493247Y1123725
X1498799Y1120536
X1495098Y1120536
X1500649Y1117347
X1493247Y1117347
X1498799Y1114158
X1495098Y1114158
X1500649Y1110969
X1493247Y1104591
X1498799Y1101402
X1500649Y1079079
X1498799Y1050378
X1493247Y1047189
X1493247Y1066323
X1498799Y1063134
X1495098Y1063134
X1500649Y1059945
X1493247Y1079079
X1498799Y1075890
X1495098Y1075890
X1500649Y1072701
X1500649Y1040811
X1493247Y1040811
X1495098Y1037622
X1498799Y1037622
X1500649Y1034433
X1493247Y1034433
X1495098Y1031244
X1495098Y1050378
X1493917Y1007182
X1493917Y0975292
X1493917Y0956158
R02Y-0019134
X1493917Y0898757
X1497617Y0968914
R03Y-0019134
X1497617Y0892379
X1492066Y0972103
R03Y-0019134
X1492066Y0895568
X1499468Y0972103
R03Y-0019134
X1499468Y0895568
X1492066Y0908324
X1497617Y0905134
X1493917Y0905134
X1499468Y0901946
X1492066Y0901946
X1497617Y0898757
X1493917Y0892379
X1493917Y0962536
X1499468Y0959347
X1499468Y0889190
X1492066Y0959347
X1497617Y0956158
X1493917Y0949780
X1499468Y0946591
X1492066Y0946591
X1497617Y0943402
X1493917Y0943402
X1499468Y0940213
X1492066Y0940213
X1497617Y0937024
X1492066Y0889190
X1493917Y0930646
X1499468Y0927457
X1492066Y0927457
X1497617Y0924268
X1493917Y0924268
X1499468Y0921079
X1492066Y0921079
X1497617Y0917890
X1493917Y0911512
X1499468Y0908324
X1497617Y0886001
X1492066Y0991237
X1497617Y0988048
X1493917Y0981670
X1499468Y0978481
X1492066Y0978481
X1497617Y0975292
X1493917Y0968914
X1499468Y0965725
X1492066Y0965725
X1497617Y0962536
X1492066Y1003993
X1499468Y1003993
X1497617Y1000804
X1493917Y1000804
X1492066Y0997615
X1499468Y0997615
X1497617Y0994426
X1493917Y0988048
X1497617Y1007182
X1499468Y1010371
X1492066Y0984859
X0509704Y1053568
X0504153Y1044001
X0509704Y1066324
X0506003Y1149237
X0506003Y1130103
X0506003Y1110970
R02Y-0019134
X0509704Y1142859
X0509704Y1123726
X0509704Y1104592
X0509704Y1085458
X0511554Y1069513
X0504153Y1146048
X0504153Y1126915
X0504153Y1107781
R02Y-0019134
X0511554Y1146048
X0511554Y1126915
X0511554Y1107781
X0511554Y1088647
X0504153Y1101403
X0509704Y1098214
X0506003Y1098214
X0511554Y1095025
X0504153Y1095025
X0509704Y1091836
X0506003Y1085458
X0506003Y1155615
X0511554Y1152426
X0511554Y1082269
X0504153Y1152426
X0509704Y1149237
X0506003Y1142859
X0511554Y1139670
X0504153Y1139670
X0509704Y1136481
X0506003Y1136481
X0511554Y1133293
X0504153Y1133293
X0509704Y1130103
X0504153Y1082269
X0506003Y1123726
X0511554Y1120537
X0504153Y1120537
X0509704Y1117348
X0506003Y1117348
X0511554Y1114159
X0504153Y1114159
X0509704Y1110970
X0506003Y1104592
X0511554Y1101403
X0509704Y1079080
X0511554Y1050379
X0506003Y1047190
X0506003Y1066324
X0511554Y1063135
X0504153Y1063135
X0509704Y1059946
X0506003Y1079080
X0511554Y1075891
X0504153Y1075891
X0509704Y1072702
X0509704Y1040812
X0506003Y1040812
X0504153Y1037623
X0511554Y1037623
X0509704Y1034434
X0506003Y1034434
X0504153Y1031245
X0504153Y1050379
X0502971Y1007183
X0502971Y0975293
X0502971Y0956159
R02Y-0019134
X0502971Y0898758
X0510373Y0968915
R03Y-0019134
X0510373Y0892380
X0504822Y0972104
R03Y-0019134
X0504822Y0895569
X0508523Y0972104
R03Y-0019134
X0508523Y0895569
X0504822Y0908325
X0510373Y0905135
X0502971Y0905135
X0508523Y0901947
X0504822Y0901947
X0510373Y0898758
X0502971Y0892380
X0502971Y0962537
X0508523Y0959348
X0508523Y0889191
X0504822Y0959348
X0510373Y0956159
X0502971Y0949781
X0508523Y0946592
X0504822Y0946592
X0510373Y0943403
X0502971Y0943403
X0508523Y0940214
X0504822Y0940214
X0510373Y0937025
X0504822Y0889191
X0502971Y0930647
X0508523Y0927458
X0504822Y0927458
X0510373Y0924269
X0502971Y0924269
X0508523Y0921080
X0504822Y0921080
X0510373Y0917891
X0502971Y0911513
X0508523Y0908325
X0510373Y0886002
X0504822Y0991238
X0510373Y0988049
X0502971Y0981671
X0508523Y0978482
X0504822Y0978482
X0510373Y0975293
X0502971Y0968915
X0508523Y0965726
X0504822Y0965726
X0510373Y0962537
X0504822Y1003994
X0508523Y1003994
X0510373Y1000805
X0502971Y1000805
X0504822Y0997616
X0508523Y0997616
X0510373Y0994427
X0502971Y0988049
X0510373Y1007183
X0508523Y1010372
X0504822Y0984860
X1485846Y1053567
X1480295Y1044000
X1485846Y1066323
X1482145Y1149236
X1482145Y1130102
X1482145Y1110969
R02Y-0019134
X1485846Y1142858
X1485846Y1123725
X1485846Y1104591
X1485846Y1085457
X1487696Y1069512
X1480295Y1146047
X1480295Y1126914
X1480295Y1107780
R02Y-0019134
X1487696Y1146047
X1487696Y1126914
X1487696Y1107780
X1487696Y1088646
X1480295Y1101402
X1485846Y1098213
X1482145Y1098213
X1487696Y1095024
X1480295Y1095024
X1485846Y1091835
X1482145Y1085457
X1482145Y1155614
X1487696Y1152425
X1487696Y1082268
X1480295Y1152425
X1485846Y1149236
X1482145Y1142858
X1487696Y1139669
X1480295Y1139669
X1485846Y1136480
X1482145Y1136480
X1487696Y1133292
X1480295Y1133292
X1485846Y1130102
X1480295Y1082268
X1482145Y1123725
X1487696Y1120536
X1480295Y1120536
X1485846Y1117347
X1482145Y1117347
X1487696Y1114158
X1480295Y1114158
X1485846Y1110969
X1482145Y1104591
X1487696Y1101402
X1485846Y1079079
X1487696Y1050378
X1482145Y1047189
X1482145Y1066323
X1487696Y1063134
X1480295Y1063134
X1485846Y1059945
X1482145Y1079079
X1487696Y1075890
X1480295Y1075890
X1485846Y1072701
X1485846Y1040811
X1482145Y1040811
X1480295Y1037622
X1487696Y1037622
X1485846Y1034433
X1482145Y1034433
X1480295Y1031244
X1480295Y1050378
X1479113Y1007182
X1479113Y0975292
X1479113Y0956158
R02Y-0019134
X1479113Y0898757
X1486515Y0968914
R03Y-0019134
X1486515Y0892379
X1480964Y0972103
R03Y-0019134
X1480964Y0895568
X1484665Y0972103
R03Y-0019134
X1484665Y0895568
X1480964Y0908324
X1486515Y0905134
X1479113Y0905134
X1484665Y0901946
X1480964Y0901946
X1486515Y0898757
X1479113Y0892379
X1479113Y0962536
X1484665Y0959347
X1484665Y0889190
X1480964Y0959347
X1486515Y0956158
X1479113Y0949780
X1484665Y0946591
X1480964Y0946591
X1486515Y0943402
X1479113Y0943402
X1484665Y0940213
X1480964Y0940213
X1486515Y0937024
X1480964Y0889190
X1479113Y0930646
X1484665Y0927457
X1480964Y0927457
X1486515Y0924268
X1479113Y0924268
X1484665Y0921079
X1480964Y0921079
X1486515Y0917890
X1479113Y0911512
X1484665Y0908324
X1486515Y0886001
X1480964Y0991237
X1486515Y0988048
X1479113Y0981670
X1484665Y0978481
X1480964Y0978481
X1486515Y0975292
X1479113Y0968914
X1484665Y0965725
X1480964Y0965725
X1486515Y0962536
X1480964Y1003993
X1484665Y1003993
X1486515Y1000804
X1479113Y1000804
X1480964Y0997615
X1484665Y0997615
X1486515Y0994426
X1479113Y0988048
X1486515Y1007182
X1484665Y1010371
X1480964Y0984859
X0535609Y1053568
X0530058Y1044001
X0535609Y1066324
X0531908Y1149237
X0531908Y1130103
X0531908Y1110970
R02Y-0019134
X0535609Y1142859
X0535609Y1123726
X0535609Y1104592
X0535609Y1085458
X0537460Y1069513
X0530058Y1146048
X0530058Y1126915
X0530058Y1107781
R02Y-0019134
X0537460Y1146048
X0537460Y1126915
X0537460Y1107781
X0537460Y1088647
X0530058Y1101403
X0535609Y1098214
X0531908Y1098214
X0537460Y1095025
X0530058Y1095025
X0535609Y1091836
X0531908Y1085458
X0531908Y1155615
X0537460Y1152426
X0537460Y1082269
X0530058Y1152426
X0535609Y1149237
X0531908Y1142859
X0537460Y1139670
X0530058Y1139670
X0535609Y1136481
X0531908Y1136481
X0537460Y1133293
X0530058Y1133293
X0535609Y1130103
X0530058Y1082269
X0531908Y1123726
X0537460Y1120537
X0530058Y1120537
X0535609Y1117348
X0531908Y1117348
X0537460Y1114159
X0530058Y1114159
X0535609Y1110970
X0531908Y1104592
X0537460Y1101403
X0535609Y1079080
X0537460Y1050379
X0531908Y1047190
X0531908Y1066324
X0537460Y1063135
X0530058Y1063135
X0535609Y1059946
X0531908Y1079080
X0537460Y1075891
X0530058Y1075891
X0535609Y1072702
X0535609Y1040812
X0531908Y1040812
X0530058Y1037623
X0537460Y1037623
X0535609Y1034434
X0531908Y1034434
X0530058Y1031245
X0530058Y1050379
X0528877Y1007183
X0528877Y0975293
X0528877Y0956159
R02Y-0019134
X0528877Y0898758
X0536279Y0968915
R03Y-0019134
X0536279Y0892380
X0530727Y0972104
R03Y-0019134
X0530727Y0895569
X0534428Y0972104
R03Y-0019134
X0534428Y0895569
X0530727Y0908325
X0536279Y0905135
X0528877Y0905135
X0534428Y0901947
X0530727Y0901947
X0536279Y0898758
X0528877Y0892380
X0528877Y0962537
X0534428Y0959348
X0534428Y0889191
X0530727Y0959348
X0536279Y0956159
X0528877Y0949781
X0534428Y0946592
X0530727Y0946592
X0536279Y0943403
X0528877Y0943403
X0534428Y0940214
X0530727Y0940214
X0536279Y0937025
X0530727Y0889191
X0528877Y0930647
X0534428Y0927458
X0530727Y0927458
X0536279Y0924269
X0528877Y0924269
X0534428Y0921080
X0530727Y0921080
X0536279Y0917891
X0528877Y0911513
X0534428Y0908325
X0536279Y0886002
X0530727Y0991238
X0536279Y0988049
X0528877Y0981671
X0534428Y0978482
X0530727Y0978482
X0536279Y0975293
X0528877Y0968915
X0534428Y0965726
X0530727Y0965726
X0536279Y0962537
X0530727Y1003994
X0534428Y1003994
X0536279Y1000805
X0528877Y1000805
X0530727Y0997616
X0534428Y0997616
X0536279Y0994427
X0528877Y0988049
X0536279Y1007183
X0534428Y1010372
X0530727Y0984860
X1511751Y1053567
X1506200Y1044000
X1511751Y1066323
X1508050Y1149236
X1508050Y1130102
X1508050Y1110969
R02Y-0019134
X1511751Y1142858
X1511751Y1123725
X1511751Y1104591
X1511751Y1085457
X1513602Y1069512
X1506200Y1146047
X1506200Y1126914
X1506200Y1107780
R02Y-0019134
X1513602Y1146047
X1513602Y1126914
X1513602Y1107780
X1513602Y1088646
X1506200Y1101402
X1511751Y1098213
X1508050Y1098213
X1513602Y1095024
X1506200Y1095024
X1511751Y1091835
X1508050Y1085457
X1508050Y1155614
X1513602Y1152425
X1513602Y1082268
X1506200Y1152425
X1511751Y1149236
X1508050Y1142858
X1513602Y1139669
X1506200Y1139669
X1511751Y1136480
X1508050Y1136480
X1513602Y1133292
X1506200Y1133292
X1511751Y1130102
X1506200Y1082268
X1508050Y1123725
X1513602Y1120536
X1506200Y1120536
X1511751Y1117347
X1508050Y1117347
X1513602Y1114158
X1506200Y1114158
X1511751Y1110969
X1508050Y1104591
X1513602Y1101402
X1511751Y1079079
X1513602Y1050378
X1508050Y1047189
X1508050Y1066323
X1513602Y1063134
X1506200Y1063134
X1511751Y1059945
X1508050Y1079079
X1513602Y1075890
X1506200Y1075890
X1511751Y1072701
X1511751Y1040811
X1508050Y1040811
X1506200Y1037622
X1513602Y1037622
X1511751Y1034433
X1508050Y1034433
X1506200Y1031244
X1506200Y1050378
X1505019Y1007182
X1505019Y0975292
X1505019Y0956158
R02Y-0019134
X1505019Y0898757
X1512421Y0968914
R03Y-0019134
X1512421Y0892379
X1506869Y0972103
R03Y-0019134
X1506869Y0895568
X1510570Y0972103
R03Y-0019134
X1510570Y0895568
X1506869Y0908324
X1512421Y0905134
X1505019Y0905134
X1510570Y0901946
X1506869Y0901946
X1512421Y0898757
X1505019Y0892379
X1505019Y0962536
X1510570Y0959347
X1510570Y0889190
X1506869Y0959347
X1512421Y0956158
X1505019Y0949780
X1510570Y0946591
X1506869Y0946591
X1512421Y0943402
X1505019Y0943402
X1510570Y0940213
X1506869Y0940213
X1512421Y0937024
X1506869Y0889190
X1505019Y0930646
X1510570Y0927457
X1506869Y0927457
X1512421Y0924268
X1505019Y0924268
X1510570Y0921079
X1506869Y0921079
X1512421Y0917890
X1505019Y0911512
X1510570Y0908324
X1512421Y0886001
X1506869Y0991237
X1512421Y0988048
X1505019Y0981670
X1510570Y0978481
X1506869Y0978481
X1512421Y0975292
X1505019Y0968914
X1510570Y0965725
X1506869Y0965725
X1512421Y0962536
X1506869Y1003993
X1510570Y1003993
X1512421Y1000804
X1505019Y1000804
X1506869Y0997615
X1510570Y0997615
X1512421Y0994426
X1505019Y0988048
X1512421Y1007182
X1510570Y1010371
X1506869Y0984859
X0332091Y1053568
X0333941Y1044001
X0332091Y1066324
X0339492Y1149237
X0339492Y1130103
X0339492Y1110970
R02Y-0019134
X0332091Y1142859
X0332091Y1123726
X0332091Y1104592
X0332091Y1085458
X0333941Y1069513
X0337642Y1146048
X0337642Y1126915
X0337642Y1107781
R02Y-0019134
X0333941Y1146048
X0333941Y1126915
X0333941Y1107781
X0333941Y1088647
X0337642Y1101403
X0332091Y1098214
X0339492Y1098214
X0333941Y1095025
X0337642Y1095025
X0332091Y1091836
X0339492Y1085458
X0332091Y1155615
X0333941Y1152426
X0333941Y1082269
X0337642Y1152426
X0332091Y1149237
X0339492Y1142859
X0333941Y1139670
X0337642Y1139670
X0332091Y1136481
X0339492Y1136481
X0333941Y1133293
X0337642Y1133293
X0332091Y1130103
X0337642Y1082269
X0339492Y1123726
X0333941Y1120537
X0337642Y1120537
X0332091Y1117348
X0339492Y1117348
X0333941Y1114159
X0337642Y1114159
X0332091Y1110970
X0339492Y1104592
X0333941Y1101403
X0332091Y1079080
X0333941Y1050379
X0339492Y1047190
X0339492Y1066324
X0333941Y1063135
X0337642Y1063135
X0332091Y1059946
X0339492Y1079080
X0333941Y1075891
X0337642Y1075891
X0332091Y1072702
X0332091Y1040812
X0339492Y1040812
X0337642Y1037623
X0333941Y1037623
X0332091Y1034434
X0339492Y1034434
X0337642Y1031245
X0337642Y1050379
X0336461Y1007183
X0336461Y0975293
X0336461Y0956159
R02Y-0019134
X0336461Y0898758
X0332760Y0968915
R03Y-0019134
X0332760Y0892380
X0338311Y0972104
R03Y-0019134
X0338311Y0895569
X0330910Y0972104
R03Y-0019134
X0330910Y0895569
X0338311Y0908325
X0332760Y0905135
X0336461Y0905135
X0330910Y0901947
X0338311Y0901947
X0332760Y0898758
X0336461Y0892380
X0336461Y0962537
X0330910Y0959348
X0330910Y0889191
X0338311Y0959348
X0332760Y0956159
X0336461Y0949781
X0330910Y0946592
X0338311Y0946592
X0332760Y0943403
X0336461Y0943403
X0330910Y0940214
X0338311Y0940214
X0332760Y0937025
X0338311Y0889191
X0336461Y0930647
X0330910Y0927458
X0338311Y0927458
X0332760Y0924269
X0336461Y0924269
X0330910Y0921080
X0338311Y0921080
X0332760Y0917891
X0336461Y0911513
X0330910Y0908325
X0332760Y0886002
X0336461Y0994427
X0330910Y0991238
X0336461Y0981671
X0330910Y0978482
X0338311Y0978482
X0332760Y0975293
X0336461Y0968915
X0330910Y0965726
X0338311Y0965726
X0332760Y0962537
X0338311Y1003994
X0330910Y1003994
X0332760Y1000805
X0336461Y1000805
X0338311Y0997616
X0330910Y0997616
X0332760Y0994427
X0336461Y0988049
X0332760Y1007183
X0330910Y1010372
X0338311Y0984860
X1308233Y1053567
X1310083Y1044000
X1308233Y1066323
X1315634Y1149236
X1315634Y1130102
X1315634Y1110969
R02Y-0019134
X1308233Y1142858
X1308233Y1123725
X1308233Y1104591
X1308233Y1085457
X1310083Y1069512
X1313784Y1146047
X1313784Y1126914
X1313784Y1107780
R02Y-0019134
X1310083Y1146047
X1310083Y1126914
X1310083Y1107780
X1310083Y1088646
X1313784Y1101402
X1308233Y1098213
X1315634Y1098213
X1310083Y1095024
X1313784Y1095024
X1308233Y1091835
X1315634Y1085457
X1308233Y1155614
X1310083Y1152425
X1310083Y1082268
X1313784Y1152425
X1308233Y1149236
X1315634Y1142858
X1310083Y1139669
X1313784Y1139669
X1308233Y1136480
X1315634Y1136480
X1310083Y1133292
X1313784Y1133292
X1308233Y1130102
X1313784Y1082268
X1315634Y1123725
X1310083Y1120536
X1313784Y1120536
X1308233Y1117347
X1315634Y1117347
X1310083Y1114158
X1313784Y1114158
X1308233Y1110969
X1315634Y1104591
X1310083Y1101402
X1308233Y1079079
X1310083Y1050378
X1315634Y1047189
X1315634Y1066323
X1310083Y1063134
X1313784Y1063134
X1308233Y1059945
X1315634Y1079079
X1310083Y1075890
X1313784Y1075890
X1308233Y1072701
X1308233Y1040811
X1315634Y1040811
X1313784Y1037622
X1310083Y1037622
X1308233Y1034433
X1315634Y1034433
X1313784Y1031244
X1313784Y1050378
X1312603Y1007182
X1312603Y0975292
X1312603Y0956158
R02Y-0019134
X1312603Y0898757
X1308902Y0968914
R03Y-0019134
X1308902Y0892379
X1314453Y0972103
R03Y-0019134
X1314453Y0895568
X1307052Y0972103
R03Y-0019134
X1307052Y0895568
X1314453Y0908324
X1308902Y0905134
X1312603Y0905134
X1307052Y0901946
X1314453Y0901946
X1308902Y0898757
X1312603Y0892379
X1312603Y0962536
X1307052Y0959347
X1307052Y0889190
X1314453Y0959347
X1308902Y0956158
X1312603Y0949780
X1307052Y0946591
X1314453Y0946591
X1308902Y0943402
X1312603Y0943402
X1307052Y0940213
X1314453Y0940213
X1308902Y0937024
X1314453Y0889190
X1312603Y0930646
X1307052Y0927457
X1314453Y0927457
X1308902Y0924268
X1312603Y0924268
X1307052Y0921079
X1314453Y0921079
X1308902Y0917890
X1312603Y0911512
X1307052Y0908324
X1308902Y0886001
X1312603Y0994426
X1307052Y0991237
X1312603Y0981670
X1307052Y0978481
X1314453Y0978481
X1308902Y0975292
X1312603Y0968914
X1307052Y0965725
X1314453Y0965725
X1308902Y0962536
X1314453Y1003993
X1307052Y1003993
X1308902Y1000804
X1312603Y1000804
X1314453Y0997615
X1307052Y0997615
X1308902Y0994426
X1312603Y0988048
X1308902Y1007182
X1307052Y1010371
X1314453Y0984859
X0320988Y1053568
X0319138Y1044001
X0320988Y1066324
X0324689Y1149237
X0324689Y1130103
X0324689Y1110970
R02Y-0019134
X0320988Y1142859
X0320988Y1123726
X0320988Y1104592
X0320988Y1085458
X0319138Y1069513
X0326539Y1146048
X0326539Y1126915
X0326539Y1107781
R02Y-0019134
X0319138Y1146048
X0319138Y1126915
X0319138Y1107781
X0319138Y1088647
X0326539Y1101403
X0320988Y1098214
X0324689Y1098214
X0319138Y1095025
X0326539Y1095025
X0320988Y1091836
X0324689Y1085458
X0324689Y1155615
X0319138Y1152426
X0319138Y1082269
X0326539Y1152426
X0320988Y1149237
X0324689Y1142859
X0319138Y1139670
X0326539Y1139670
X0320988Y1136481
X0324689Y1136481
X0319138Y1133293
X0326539Y1133293
X0320988Y1130103
X0326539Y1082269
X0324689Y1123726
X0319138Y1120537
X0326539Y1120537
X0320988Y1117348
X0324689Y1117348
X0319138Y1114159
X0326539Y1114159
X0320988Y1110970
X0324689Y1104592
X0319138Y1101403
X0320988Y1079080
X0319138Y1050379
X0324689Y1047190
X0324689Y1066324
X0319138Y1063135
X0326539Y1063135
X0320988Y1059946
X0324689Y1079080
X0319138Y1075891
X0326539Y1075891
X0320988Y1072702
X0320988Y1040812
X0324689Y1040812
X0326539Y1037623
X0319138Y1037623
X0320988Y1034434
X0324689Y1034434
X0326539Y1031245
X0326539Y1050379
X0325358Y1007183
X0325358Y0975293
X0325358Y0956159
R02Y-0019134
X0325358Y0898758
X0317957Y0968915
R03Y-0019134
X0317957Y0892380
X0323508Y0972104
R03Y-0019134
X0323508Y0895569
X0319807Y0972104
R03Y-0019134
X0319807Y0895569
X0323508Y0908325
X0317957Y0905135
X0325358Y0905135
X0319807Y0901947
X0323508Y0901947
X0317957Y0898758
X0325358Y0892380
X0325358Y0962537
X0319807Y0959348
X0319807Y0889191
X0323508Y0959348
X0317957Y0956159
X0325358Y0949781
X0319807Y0946592
X0323508Y0946592
X0317957Y0943403
X0325358Y0943403
X0319807Y0940214
X0323508Y0940214
X0317957Y0937025
X0323508Y0889191
X0325358Y0930647
X0319807Y0927458
X0323508Y0927458
X0317957Y0924269
X0325358Y0924269
X0319807Y0921080
X0323508Y0921080
X0317957Y0917891
X0325358Y0911513
X0319807Y0908325
X0317957Y0886002
X0325358Y0994427
X0319807Y0991238
X0325358Y0981671
X0319807Y0978482
X0323508Y0978482
X0317957Y0975293
X0325358Y0968915
X0319807Y0965726
X0323508Y0965726
X0317957Y0962537
X0323508Y1003994
X0319807Y1003994
X0317957Y1000805
X0325358Y1000805
X0323508Y0997616
X0319807Y0997616
X0317957Y0994427
X0325358Y0988049
X0317957Y1007183
X0319807Y1010372
X0323508Y0984860
X1297130Y1053567
X1295280Y1044000
X1297130Y1066323
X1300831Y1149236
X1300831Y1130102
X1300831Y1110969
R02Y-0019134
X1297130Y1142858
X1297130Y1123725
X1297130Y1104591
X1297130Y1085457
X1295280Y1069512
X1302681Y1146047
X1302681Y1126914
X1302681Y1107780
R02Y-0019134
X1295280Y1146047
X1295280Y1126914
X1295280Y1107780
X1295280Y1088646
X1302681Y1101402
X1297130Y1098213
X1300831Y1098213
X1295280Y1095024
X1302681Y1095024
X1297130Y1091835
X1300831Y1085457
X1300831Y1155614
X1295280Y1152425
X1295280Y1082268
X1302681Y1152425
X1297130Y1149236
X1300831Y1142858
X1295280Y1139669
X1302681Y1139669
X1297130Y1136480
X1300831Y1136480
X1295280Y1133292
X1302681Y1133292
X1297130Y1130102
X1302681Y1082268
X1300831Y1123725
X1295280Y1120536
X1302681Y1120536
X1297130Y1117347
X1300831Y1117347
X1295280Y1114158
X1302681Y1114158
X1297130Y1110969
X1300831Y1104591
X1295280Y1101402
X1297130Y1079079
X1295280Y1050378
X1300831Y1047189
X1300831Y1066323
X1295280Y1063134
X1302681Y1063134
X1297130Y1059945
X1300831Y1079079
X1295280Y1075890
X1302681Y1075890
X1297130Y1072701
X1297130Y1040811
X1300831Y1040811
X1302681Y1037622
X1295280Y1037622
X1297130Y1034433
X1300831Y1034433
X1302681Y1031244
X1302681Y1050378
X1301500Y1007182
X1301500Y0975292
X1301500Y0956158
R02Y-0019134
X1301500Y0898757
X1294099Y0968914
R03Y-0019134
X1294099Y0892379
X1299650Y0972103
R03Y-0019134
X1299650Y0895568
X1295949Y0972103
R03Y-0019134
X1295949Y0895568
X1299650Y0908324
X1294099Y0905134
X1301500Y0905134
X1295949Y0901946
X1299650Y0901946
X1294099Y0898757
X1301500Y0892379
X1301500Y0962536
X1295949Y0959347
X1295949Y0889190
X1299650Y0959347
X1294099Y0956158
X1301500Y0949780
X1295949Y0946591
X1299650Y0946591
X1294099Y0943402
X1301500Y0943402
X1295949Y0940213
X1299650Y0940213
X1294099Y0937024
X1299650Y0889190
X1301500Y0930646
X1295949Y0927457
X1299650Y0927457
X1294099Y0924268
X1301500Y0924268
X1295949Y0921079
X1299650Y0921079
X1294099Y0917890
X1301500Y0911512
X1295949Y0908324
X1294099Y0886001
X1301500Y0994426
X1295949Y0991237
X1301500Y0981670
X1295949Y0978481
X1299650Y0978481
X1294099Y0975292
X1301500Y0968914
X1295949Y0965725
X1299650Y0965725
X1294099Y0962536
X1299650Y1003993
X1295949Y1003993
X1294099Y1000804
X1301500Y1000804
X1299650Y0997615
X1295949Y0997615
X1294099Y0994426
X1301500Y0988048
X1294099Y1007182
X1295949Y1010371
X1299650Y0984859
X0357996Y1053568
X0359847Y1044001
X0357996Y1066324
X0365398Y1149237
X0365398Y1130103
X0365398Y1110970
R02Y-0019134
X0357996Y1142859
X0357996Y1123726
X0357996Y1104592
X0357996Y1085458
X0359847Y1069513
X0363547Y1146048
X0363547Y1126915
X0363547Y1107781
R02Y-0019134
X0359847Y1146048
X0359847Y1126915
X0359847Y1107781
X0359847Y1088647
X0363547Y1101403
X0357996Y1098214
X0365398Y1098214
X0359847Y1095025
X0363547Y1095025
X0357996Y1091836
X0365398Y1085458
X0357996Y1155615
X0359847Y1152426
X0359847Y1082269
X0363547Y1152426
X0357996Y1149237
X0365398Y1142859
X0359847Y1139670
X0363547Y1139670
X0357996Y1136481
X0365398Y1136481
X0359847Y1133293
X0363547Y1133293
X0357996Y1130103
X0363547Y1082269
X0365398Y1123726
X0359847Y1120537
X0363547Y1120537
X0357996Y1117348
X0365398Y1117348
X0359847Y1114159
X0363547Y1114159
X0357996Y1110970
X0365398Y1104592
X0359847Y1101403
X0357996Y1079080
X0359847Y1050379
X0365398Y1047190
X0365398Y1066324
X0359847Y1063135
X0363547Y1063135
X0357996Y1059946
X0365398Y1079080
X0359847Y1075891
X0363547Y1075891
X0357996Y1072702
X0357996Y1040812
X0365398Y1040812
X0363547Y1037623
X0359847Y1037623
X0357996Y1034434
X0365398Y1034434
X0363547Y1031245
X0363547Y1050379
X0362366Y1007183
X0362366Y0975293
X0362366Y0956159
R02Y-0019134
X0362366Y0898758
X0358665Y0968915
R03Y-0019134
X0358665Y0892380
X0364217Y0972104
R03Y-0019134
X0364217Y0895569
X0356815Y0972104
R03Y-0019134
X0356815Y0895569
X0364217Y0908325
X0358665Y0905135
X0362366Y0905135
X0356815Y0901947
X0364217Y0901947
X0358665Y0898758
X0362366Y0892380
X0362366Y0962537
X0356815Y0959348
X0356815Y0889191
X0364217Y0959348
X0358665Y0956159
X0362366Y0949781
X0356815Y0946592
X0364217Y0946592
X0358665Y0943403
X0362366Y0943403
X0356815Y0940214
X0364217Y0940214
X0358665Y0937025
X0364217Y0889191
X0362366Y0930647
X0356815Y0927458
X0364217Y0927458
X0358665Y0924269
X0362366Y0924269
X0356815Y0921080
X0364217Y0921080
X0358665Y0917891
X0362366Y0911513
X0356815Y0908325
X0358665Y0886002
X0362366Y0994427
X0356815Y0991238
X0362366Y0981671
X0356815Y0978482
X0364217Y0978482
X0358665Y0975293
X0362366Y0968915
X0356815Y0965726
X0364217Y0965726
X0358665Y0962537
X0364217Y1003994
X0356815Y1003994
X0358665Y1000805
X0362366Y1000805
X0364217Y0997616
X0356815Y0997616
X0358665Y0994427
X0362366Y0988049
X0358665Y1007183
X0356815Y1010372
X0364217Y0984860
X1334138Y1053567
X1335989Y1044000
X1334138Y1066323
X1341540Y1149236
X1341540Y1130102
X1341540Y1110969
R02Y-0019134
X1334138Y1142858
X1334138Y1123725
X1334138Y1104591
X1334138Y1085457
X1335989Y1069512
X1339689Y1146047
X1339689Y1126914
X1339689Y1107780
R02Y-0019134
X1335989Y1146047
X1335989Y1126914
X1335989Y1107780
X1335989Y1088646
X1339689Y1101402
X1334138Y1098213
X1341540Y1098213
X1335989Y1095024
X1339689Y1095024
X1334138Y1091835
X1341540Y1085457
X1334138Y1155614
X1335989Y1152425
X1335989Y1082268
X1339689Y1152425
X1334138Y1149236
X1341540Y1142858
X1335989Y1139669
X1339689Y1139669
X1334138Y1136480
X1341540Y1136480
X1335989Y1133292
X1339689Y1133292
X1334138Y1130102
X1339689Y1082268
X1341540Y1123725
X1335989Y1120536
X1339689Y1120536
X1334138Y1117347
X1341540Y1117347
X1335989Y1114158
X1339689Y1114158
X1334138Y1110969
X1341540Y1104591
X1335989Y1101402
X1334138Y1079079
X1335989Y1050378
X1341540Y1047189
X1341540Y1066323
X1335989Y1063134
X1339689Y1063134
X1334138Y1059945
X1341540Y1079079
X1335989Y1075890
X1339689Y1075890
X1334138Y1072701
X1334138Y1040811
X1341540Y1040811
X1339689Y1037622
X1335989Y1037622
X1334138Y1034433
X1341540Y1034433
X1339689Y1031244
X1339689Y1050378
X1338508Y1007182
X1338508Y0975292
X1338508Y0956158
R02Y-0019134
X1338508Y0898757
X1334807Y0968914
R03Y-0019134
X1334807Y0892379
X1340359Y0972103
R03Y-0019134
X1340359Y0895568
X1332957Y0972103
R03Y-0019134
X1332957Y0895568
X1340359Y0908324
X1334807Y0905134
X1338508Y0905134
X1332957Y0901946
X1340359Y0901946
X1334807Y0898757
X1338508Y0892379
X1338508Y0962536
X1332957Y0959347
X1332957Y0889190
X1340359Y0959347
X1334807Y0956158
X1338508Y0949780
X1332957Y0946591
X1340359Y0946591
X1334807Y0943402
X1338508Y0943402
X1332957Y0940213
X1340359Y0940213
X1334807Y0937024
X1340359Y0889190
X1338508Y0930646
X1332957Y0927457
X1340359Y0927457
X1334807Y0924268
X1338508Y0924268
X1332957Y0921079
X1340359Y0921079
X1334807Y0917890
X1338508Y0911512
X1332957Y0908324
X1334807Y0886001
X1338508Y0994426
X1332957Y0991237
X1338508Y0981670
X1332957Y0978481
X1340359Y0978481
X1334807Y0975292
X1338508Y0968914
X1332957Y0965725
X1340359Y0965725
X1334807Y0962536
X1340359Y1003993
X1332957Y1003993
X1334807Y1000804
X1338508Y1000804
X1340359Y0997615
X1332957Y0997615
X1334807Y0994426
X1338508Y0988048
X1334807Y1007182
X1332957Y1010371
X1340359Y0984859
X0372799Y1053568
X0370949Y1044001
X0372799Y1066324
X0376500Y1149237
X0376500Y1130103
X0376500Y1110970
R02Y-0019134
X0372799Y1142859
X0372799Y1123726
X0372799Y1104592
X0372799Y1085458
X0370949Y1069513
X0378351Y1146048
X0378351Y1126915
X0378351Y1107781
R02Y-0019134
X0370949Y1146048
X0370949Y1126915
X0370949Y1107781
X0370949Y1088647
X0378351Y1101403
X0372799Y1098214
X0376500Y1098214
X0370949Y1095025
X0378351Y1095025
X0372799Y1091836
X0376500Y1085458
X0376500Y1155615
X0370949Y1152426
X0370949Y1082269
X0378351Y1152426
X0372799Y1149237
X0376500Y1142859
X0370949Y1139670
X0378351Y1139670
X0372799Y1136481
X0376500Y1136481
X0370949Y1133293
X0378351Y1133293
X0372799Y1130103
X0378351Y1082269
X0376500Y1123726
X0370949Y1120537
X0378351Y1120537
X0372799Y1117348
X0376500Y1117348
X0370949Y1114159
X0378351Y1114159
X0372799Y1110970
X0376500Y1104592
X0370949Y1101403
X0372799Y1079080
X0370949Y1050379
X0376500Y1047190
X0376500Y1066324
X0370949Y1063135
X0378351Y1063135
X0372799Y1059946
X0376500Y1079080
X0370949Y1075891
X0378351Y1075891
X0372799Y1072702
X0372799Y1040812
X0376500Y1040812
X0378351Y1037623
X0370949Y1037623
X0372799Y1034434
X0376500Y1034434
X0378351Y1031245
X0378351Y1050379
X0377169Y1007183
X0377169Y0975293
X0377169Y0956159
R02Y-0019134
X0377169Y0898758
X0369768Y0968915
R03Y-0019134
X0369768Y0892380
X0375319Y0972104
R03Y-0019134
X0375319Y0895569
X0371618Y0972104
R03Y-0019134
X0371618Y0895569
X0375319Y0908325
X0369768Y0905135
X0377169Y0905135
X0371618Y0901947
X0375319Y0901947
X0369768Y0898758
X0377169Y0892380
X0377169Y0962537
X0371618Y0959348
X0371618Y0889191
X0375319Y0959348
X0369768Y0956159
X0377169Y0949781
X0371618Y0946592
X0375319Y0946592
X0369768Y0943403
X0377169Y0943403
X0371618Y0940214
X0375319Y0940214
X0369768Y0937025
X0375319Y0889191
X0377169Y0930647
X0371618Y0927458
X0375319Y0927458
X0369768Y0924269
X0377169Y0924269
X0371618Y0921080
X0375319Y0921080
X0369768Y0917891
X0377169Y0911513
X0371618Y0908325
X0369768Y0886002
X0377169Y0994427
X0371618Y0991238
X0377169Y0981671
X0371618Y0978482
X0375319Y0978482
X0369768Y0975293
X0377169Y0968915
X0371618Y0965726
X0375319Y0965726
X0369768Y0962537
X0375319Y1003994
X0371618Y1003994
X0369768Y1000805
X0377169Y1000805
X0375319Y0997616
X0371618Y0997616
X0369768Y0994427
X0377169Y0988049
X0369768Y1007183
X0371618Y1010372
X0375319Y0984860
X1348941Y1053567
X1347091Y1044000
X1348941Y1066323
X1352642Y1149236
X1352642Y1130102
X1352642Y1110969
R02Y-0019134
X1348941Y1142858
X1348941Y1123725
X1348941Y1104591
X1348941Y1085457
X1347091Y1069512
X1354493Y1146047
X1354493Y1126914
X1354493Y1107780
R02Y-0019134
X1347091Y1146047
X1347091Y1126914
X1347091Y1107780
X1347091Y1088646
X1354493Y1101402
X1348941Y1098213
X1352642Y1098213
X1347091Y1095024
X1354493Y1095024
X1348941Y1091835
X1352642Y1085457
X1352642Y1155614
X1347091Y1152425
X1347091Y1082268
X1354493Y1152425
X1348941Y1149236
X1352642Y1142858
X1347091Y1139669
X1354493Y1139669
X1348941Y1136480
X1352642Y1136480
X1347091Y1133292
X1354493Y1133292
X1348941Y1130102
X1354493Y1082268
X1352642Y1123725
X1347091Y1120536
X1354493Y1120536
X1348941Y1117347
X1352642Y1117347
X1347091Y1114158
X1354493Y1114158
X1348941Y1110969
X1352642Y1104591
X1347091Y1101402
X1348941Y1079079
X1347091Y1050378
X1352642Y1047189
X1352642Y1066323
X1347091Y1063134
X1354493Y1063134
X1348941Y1059945
X1352642Y1079079
X1347091Y1075890
X1354493Y1075890
X1348941Y1072701
X1348941Y1040811
X1352642Y1040811
X1354493Y1037622
X1347091Y1037622
X1348941Y1034433
X1352642Y1034433
X1354493Y1031244
X1354493Y1050378
X1353311Y1007182
X1353311Y0975292
X1353311Y0956158
R02Y-0019134
X1353311Y0898757
X1345910Y0968914
R03Y-0019134
X1345910Y0892379
X1351461Y0972103
R03Y-0019134
X1351461Y0895568
X1347760Y0972103
R03Y-0019134
X1347760Y0895568
X1351461Y0908324
X1345910Y0905134
X1353311Y0905134
X1347760Y0901946
X1351461Y0901946
X1345910Y0898757
X1353311Y0892379
X1353311Y0962536
X1347760Y0959347
X1347760Y0889190
X1351461Y0959347
X1345910Y0956158
X1353311Y0949780
X1347760Y0946591
X1351461Y0946591
X1345910Y0943402
X1353311Y0943402
X1347760Y0940213
X1351461Y0940213
X1345910Y0937024
X1351461Y0889190
X1353311Y0930646
X1347760Y0927457
X1351461Y0927457
X1345910Y0924268
X1353311Y0924268
X1347760Y0921079
X1351461Y0921079
X1345910Y0917890
X1353311Y0911512
X1347760Y0908324
X1345910Y0886001
X1353311Y0994426
X1347760Y0991237
X1353311Y0981670
X1347760Y0978481
X1351461Y0978481
X1345910Y0975292
X1353311Y0968914
X1347760Y0965725
X1351461Y0965725
X1345910Y0962536
X1351461Y1003993
X1347760Y1003993
X1345910Y1000804
X1353311Y1000804
X1351461Y0997615
X1347760Y0997615
X1345910Y0994426
X1353311Y0988048
X1345910Y1007182
X1347760Y1010371
X1351461Y0984859
X0346894Y1053568
X0345043Y1044001
X0346894Y1066324
X0350595Y1149237
X0350595Y1130103
X0350595Y1110970
R02Y-0019134
X0346894Y1142859
X0346894Y1123726
X0346894Y1104592
X0346894Y1085458
X0345043Y1069513
X0352445Y1146048
X0352445Y1126915
X0352445Y1107781
R02Y-0019134
X0345043Y1146048
X0345043Y1126915
X0345043Y1107781
X0345043Y1088647
X0352445Y1101403
X0346894Y1098214
X0350595Y1098214
X0345043Y1095025
X0352445Y1095025
X0346894Y1091836
X0350595Y1085458
X0350595Y1155615
X0345043Y1152426
X0345043Y1082269
X0352445Y1152426
X0346894Y1149237
X0350595Y1142859
X0345043Y1139670
X0352445Y1139670
X0346894Y1136481
X0350595Y1136481
X0345043Y1133293
X0352445Y1133293
X0346894Y1130103
X0352445Y1082269
X0350595Y1123726
X0345043Y1120537
X0352445Y1120537
X0346894Y1117348
X0350595Y1117348
X0345043Y1114159
X0352445Y1114159
X0346894Y1110970
X0350595Y1104592
X0345043Y1101403
X0346894Y1079080
X0345043Y1050379
X0350595Y1047190
X0350595Y1066324
X0345043Y1063135
X0352445Y1063135
X0346894Y1059946
X0350595Y1079080
X0345043Y1075891
X0352445Y1075891
X0346894Y1072702
X0346894Y1040812
X0350595Y1040812
X0352445Y1037623
X0345043Y1037623
X0346894Y1034434
X0350595Y1034434
X0352445Y1031245
X0352445Y1050379
X0351264Y1007183
X0351264Y0975293
X0351264Y0956159
R02Y-0019134
X0351264Y0898758
X0343862Y0968915
R03Y-0019134
X0343862Y0892380
X0349414Y0972104
R03Y-0019134
X0349414Y0895569
X0345713Y0972104
R03Y-0019134
X0345713Y0895569
X0349414Y0908325
X0343862Y0905135
X0351264Y0905135
X0345713Y0901947
X0349414Y0901947
X0343862Y0898758
X0351264Y0892380
X0351264Y0962537
X0345713Y0959348
X0345713Y0889191
X0349414Y0959348
X0343862Y0956159
X0351264Y0949781
X0345713Y0946592
X0349414Y0946592
X0343862Y0943403
X0351264Y0943403
X0345713Y0940214
X0349414Y0940214
X0343862Y0937025
X0349414Y0889191
X0351264Y0930647
X0345713Y0927458
X0349414Y0927458
X0343862Y0924269
X0351264Y0924269
X0345713Y0921080
X0349414Y0921080
X0343862Y0917891
X0351264Y0911513
X0345713Y0908325
X0343862Y0886002
X0351264Y0994427
X0345713Y0991238
X0351264Y0981671
X0345713Y0978482
X0349414Y0978482
X0343862Y0975293
X0351264Y0968915
X0345713Y0965726
X0349414Y0965726
X0343862Y0962537
X0349414Y1003994
X0345713Y1003994
X0343862Y1000805
X0351264Y1000805
X0349414Y0997616
X0345713Y0997616
X0343862Y0994427
X0351264Y0988049
X0343862Y1007183
X0345713Y1010372
X0349414Y0984860
X1323036Y1053567
X1321185Y1044000
X1323036Y1066323
X1326737Y1149236
X1326737Y1130102
X1326737Y1110969
R02Y-0019134
X1323036Y1142858
X1323036Y1123725
X1323036Y1104591
X1323036Y1085457
X1321185Y1069512
X1328587Y1146047
X1328587Y1126914
X1328587Y1107780
R02Y-0019134
X1321185Y1146047
X1321185Y1126914
X1321185Y1107780
X1321185Y1088646
X1328587Y1101402
X1323036Y1098213
X1326737Y1098213
X1321185Y1095024
X1328587Y1095024
X1323036Y1091835
X1326737Y1085457
X1326737Y1155614
X1321185Y1152425
X1321185Y1082268
X1328587Y1152425
X1323036Y1149236
X1326737Y1142858
X1321185Y1139669
X1328587Y1139669
X1323036Y1136480
X1326737Y1136480
X1321185Y1133292
X1328587Y1133292
X1323036Y1130102
X1328587Y1082268
X1326737Y1123725
X1321185Y1120536
X1328587Y1120536
X1323036Y1117347
X1326737Y1117347
X1321185Y1114158
X1328587Y1114158
X1323036Y1110969
X1326737Y1104591
X1321185Y1101402
X1323036Y1079079
X1321185Y1050378
X1326737Y1047189
X1326737Y1066323
X1321185Y1063134
X1328587Y1063134
X1323036Y1059945
X1326737Y1079079
X1321185Y1075890
X1328587Y1075890
X1323036Y1072701
X1323036Y1040811
X1326737Y1040811
X1328587Y1037622
X1321185Y1037622
X1323036Y1034433
X1326737Y1034433
X1328587Y1031244
X1328587Y1050378
X1327406Y1007182
X1327406Y0975292
X1327406Y0956158
R02Y-0019134
X1327406Y0898757
X1320004Y0968914
R03Y-0019134
X1320004Y0892379
X1325556Y0972103
R03Y-0019134
X1325556Y0895568
X1321855Y0972103
R03Y-0019134
X1321855Y0895568
X1325556Y0908324
X1320004Y0905134
X1327406Y0905134
X1321855Y0901946
X1325556Y0901946
X1320004Y0898757
X1327406Y0892379
X1327406Y0962536
X1321855Y0959347
X1321855Y0889190
X1325556Y0959347
X1320004Y0956158
X1327406Y0949780
X1321855Y0946591
X1325556Y0946591
X1320004Y0943402
X1327406Y0943402
X1321855Y0940213
X1325556Y0940213
X1320004Y0937024
X1325556Y0889190
X1327406Y0930646
X1321855Y0927457
X1325556Y0927457
X1320004Y0924268
X1327406Y0924268
X1321855Y0921079
X1325556Y0921079
X1320004Y0917890
X1327406Y0911512
X1321855Y0908324
X1320004Y0886001
X1327406Y0994426
X1321855Y0991237
X1327406Y0981670
X1321855Y0978481
X1325556Y0978481
X1320004Y0975292
X1327406Y0968914
X1321855Y0965725
X1325556Y0965725
X1320004Y0962536
X1325556Y1003993
X1321855Y1003993
X1320004Y1000804
X1327406Y1000804
X1325556Y0997615
X1321855Y0997615
X1320004Y0994426
X1327406Y0988048
X1320004Y1007182
X1321855Y1010371
X1325556Y0984859
X0517775Y0873246
X0521475Y0873246
X0517775Y0879624
X0519625Y0876435
X0514074Y0879624
X0521475Y0879624
X1490216Y0879623
X0452341Y1165182
X0562184Y0873246
X0554783Y0879624
X1522854Y1130103
X1521673Y0908323
X1399571Y0908323
X1503169Y0908323
X1504350Y1130103
X0367917Y0908324
X0334610Y0908324
X0401225Y0908324
X0527027Y0908324
X1311933Y1130103
X0335792Y1130105
X0386461Y1235718
X0386303Y1240751
X0310957Y1219126
X0311115Y1214093
X0388647Y1223453
X0388805Y1218420
X0367697Y1216624
X0372730Y1216782
X0513405Y1130104
X1344059Y0908323
X0354296Y1130105
X0490019Y0908324
X1479199Y1575641
X1465026Y1575641
X0592988Y1536063
X0594662Y1542641
X1374483Y1569063
X0608836Y1542641
X0616610Y1536063
X0618284Y1542641
X0623009Y1542641
X1457735Y1552195
X1529773Y1547243
X1526443Y1540295
X1520324Y1547243
X1516994Y1540295
X1515600Y1547243
X1512270Y1540295
X1510875Y1547243
X1507545Y1540295
X1506151Y1547243
X1501427Y1547243
X1498096Y1540295
X1496702Y1547243
X1493372Y1540295
X1491978Y1547243
X1487253Y1547243
X1483923Y1540295
X1482529Y1547243
X1479199Y1540295
X1477805Y1547243
X1474474Y1540295
X1473080Y1547243
X1469750Y1540295
X1468356Y1547243
X1465026Y1540295
X1463631Y1547243
X1460301Y1540295
X1458907Y1547243
X1454994Y1540512
X1458626Y1569063
X1460301Y1575641
X1463351Y1569063
X1468076Y1569063
X1472800Y1569063
X1474474Y1575641
X1483923Y1575641
X1486973Y1569063
X1496422Y1569063
X1502821Y1575641
X1510595Y1569063
X1520044Y1569063
X1521718Y1575641
X1529493Y1569063
X1531167Y1575641
X1534824Y1569063
X1662886Y1569063
X1659229Y1575641
X1657555Y1569063
X1654505Y1575641
X1621434Y1575641
X1583160Y1575425
X1577688Y1561725
X1659229Y1540295
X1585797Y1552195
X1657835Y1547243
X1654505Y1540295
X1649780Y1540295
X1648386Y1547243
X1645056Y1540295
X1643662Y1547243
X1640332Y1540295
X1638937Y1547243
X1635607Y1540295
X1634213Y1547243
X1630883Y1540295
X1629489Y1547243
X1626158Y1540295
X1624764Y1547243
X1621434Y1540295
X1620040Y1547243
X1616710Y1540295
X1615315Y1547243
X1611985Y1540295
X1610591Y1547243
X1607261Y1540295
X1605867Y1547243
X1602536Y1540295
X1601142Y1547243
X1597812Y1540295
X1596418Y1547243
X1593088Y1540295
X1591693Y1547243
X1588363Y1540295
X1586969Y1547243
X1583056Y1540514
X1577688Y1556810
X1586688Y1569063
X1588363Y1575641
X1591413Y1569063
X1593088Y1575641
X1596138Y1569063
X1597812Y1575641
X1600862Y1569063
X1602536Y1575641
X1607261Y1575641
X1611985Y1575641
X1615035Y1569063
X1616710Y1575641
X1624484Y1569063
X1626158Y1575641
X1630883Y1575641
X1635607Y1575641
X1638657Y1569063
X1640332Y1575641
X1645056Y1575641
X1648106Y1569063
X1649780Y1575641
X1455098Y1575425
X1449626Y1561725
X1449626Y1556810
X1488648Y1540295
X1502821Y1540295
X1521718Y1540295
X1531167Y1540295
X1376158Y1575641
X0599387Y1542641
X0604111Y1542641
X0607161Y1536063
X1398712Y1569063
X1395055Y1575641
X1393381Y1569063
X1390331Y1575641
X1357260Y1575641
X1318986Y1575425
X1313514Y1561725
X1395055Y1540295
X1321623Y1552195
X1393661Y1547243
X1390331Y1540295
X1385606Y1540295
X1384212Y1547243
X1380882Y1540295
X1379488Y1547243
X1376158Y1540295
X1374763Y1547243
X1371433Y1540295
X1370039Y1547243
X1366709Y1540295
X1365315Y1547243
X1361984Y1540295
X1360590Y1547243
X1357260Y1540295
X1355866Y1547243
X1352536Y1540295
X1351141Y1547243
X1347811Y1540295
X1346417Y1547243
X1343087Y1540295
X1341693Y1547243
X1338362Y1540295
X1336968Y1547243
X1333638Y1540295
X1332244Y1547243
X1328914Y1540295
X1327519Y1547243
X1324189Y1540295
X1322795Y1547243
X1318882Y1540514
X1313514Y1556810
X1322514Y1569063
X1324189Y1575641
X1327239Y1569063
X1328914Y1575641
X1331964Y1569063
X1333638Y1575641
X1336688Y1569063
X1338362Y1575641
X1343087Y1575641
X1347811Y1575641
X1350861Y1569063
X1352536Y1575641
X1360310Y1569063
X1361984Y1575641
X1366709Y1575641
X1371433Y1575641
X0627733Y1542641
X0630783Y1536063
X0632458Y1542641
X0637182Y1542641
X0640232Y1536063
X0641906Y1542641
X0655012Y1536063
X0651355Y1542641
X0649681Y1536063
X0646631Y1542641
X0613560Y1542641
X0575286Y1542425
X0569814Y1528725
X0651355Y1507295
X0577923Y1519195
X0649961Y1514243
X0646631Y1507295
X0641906Y1507295
X0640512Y1514243
X0637182Y1507295
X0635788Y1514243
X0632458Y1507295
X0631063Y1514243
X0627733Y1507295
X0626339Y1514243
X0623009Y1507295
X0621615Y1514243
X0618284Y1507295
X0616890Y1514243
X0613560Y1507295
X0612166Y1514243
X0608836Y1507295
X0607441Y1514243
X0604111Y1507295
X0602717Y1514243
X0599387Y1507295
X0597993Y1514243
X0594662Y1507295
X0593268Y1514243
X0589938Y1507295
X0588544Y1514243
X0585214Y1507295
X0583819Y1514243
X0580489Y1507295
X0579095Y1514243
X0575182Y1507514
X0569814Y1523810
X0578814Y1536063
X0580489Y1542641
X0583539Y1536063
X0585214Y1542641
X0588264Y1536063
X0589938Y1542641
X0518569Y1542641
X0509120Y1542641
X0504396Y1542641
X0499671Y1542641
X0490222Y1542641
X0485498Y1542641
X0480774Y1542641
X0471325Y1542641
X0461876Y1542641
X0457152Y1542641
X0447224Y1542425
X0441752Y1528725
X0441752Y1523810
X0480774Y1507295
X0494947Y1507295
X0513844Y1507295
X0523293Y1507295
X0449861Y1519195
X0521899Y1514243
X0518569Y1507295
X0512450Y1514243
X0509120Y1507295
X0507726Y1514243
X0504396Y1507295
X0503001Y1514243
X0499671Y1507295
X0498277Y1514243
X0493553Y1514243
X0490222Y1507295
X0488828Y1514243
X0485498Y1507295
X0484104Y1514243
X0479379Y1514243
X0476049Y1507295
X0474655Y1514243
X0471325Y1507295
X0469931Y1514243
X0466600Y1507295
X0465206Y1514243
X0461876Y1507295
X0460482Y1514243
X0457152Y1507295
X0455757Y1514243
X0452427Y1507295
X0451033Y1514243
X0447120Y1507512
X0450752Y1536063
X0452427Y1542641
X0455477Y1536063
X0460202Y1536063
X0464926Y1536063
X0466600Y1542641
X0476049Y1542641
X1262269Y1575641
X1252820Y1575641
X1248096Y1575641
X1243371Y1575641
X1233922Y1575641
R02X-0004724
X1215025Y1575641
X1205576Y1575641
X1200852Y1575641
X1190924Y1575425
X1185452Y1561725
X1185452Y1556810
X1224474Y1540295
X1238647Y1540295
X1257544Y1540295
X1266993Y1540295
X1193561Y1552195
X1265599Y1547243
X1262269Y1540295
X1256150Y1547243
X1252820Y1540295
X1251426Y1547243
X1248096Y1540295
X1246701Y1547243
X1243371Y1540295
X1241977Y1547243
X1237253Y1547243
X1233922Y1540295
X1232528Y1547243
X1229198Y1540295
X1227804Y1547243
X1223079Y1547243
X1219749Y1540295
X1218355Y1547243
X1215025Y1540295
X1213631Y1547243
X1210300Y1540295
X1208906Y1547243
X1205576Y1540295
X1204182Y1547243
X1200852Y1540295
X1199457Y1547243
X1196127Y1540295
X1194733Y1547243
X1190820Y1540512
X1194452Y1569063
X1196127Y1575641
X1199177Y1569063
X1203902Y1569063
X1208626Y1569063
X1210300Y1575641
X1219749Y1575641
X1222799Y1569063
X1232248Y1569063
X1238647Y1575641
X1246421Y1569063
X1255870Y1569063
X1257544Y1575641
X1265319Y1569063
X1266993Y1575641
X1270650Y1569063
X0523293Y1542641
X0526950Y1536063
X0488548Y1536063
X0494947Y1542641
X0502721Y1536063
X0512170Y1536063
X0513844Y1542641
X0521619Y1536063
X0479099Y1536063
X1469750Y1575641
X1380882Y1575641
X1383932Y1569063
X1526443Y1575641
X1516994Y1575641
X1512270Y1575641
X1507545Y1575641
X1498096Y1575641
R02X-0004724
X1385606Y1575641
X1400752Y1130103
X0314641Y1536063
X0177579Y1523810
X0177579Y1528725
X0305641Y1523810
X0305641Y1528725
X0183051Y1542425
X1310752Y0908323
X1329256Y0908323
X0192979Y1542641
X1466161Y0908323
X0216601Y1542641
X0221325Y1542641
X0545531Y0908324
X0186579Y1536063
X0387182Y1542641
X0382458Y1542641
X0390839Y1536063
X0385508Y1536063
X0385788Y1514243
X0387182Y1507295
X0382458Y1507295
X0373009Y1542641
X0368285Y1542641
X0377733Y1542641
X0366610Y1536063
X0376059Y1536063
X0371615Y1514243
X0366890Y1514243
X0376339Y1514243
X0373009Y1507295
X0368285Y1507295
X0377733Y1507295
X0363560Y1542641
X0358836Y1542641
X0354111Y1542641
X0352437Y1536063
X0362166Y1514243
X0357442Y1514243
X0352717Y1514243
X0363560Y1507295
X0358836Y1507295
X0354111Y1507295
X0349387Y1542641
X0344663Y1542641
X0339938Y1542641
X0342988Y1536063
X0347993Y1514243
X0343268Y1514243
X0338544Y1514243
X0349387Y1507295
X0344663Y1507295
X0339938Y1507295
X0335214Y1542641
X0330489Y1542641
X0325765Y1542641
X0328815Y1536063
X0324091Y1536063
X0333820Y1514243
X0329095Y1514243
X0324371Y1514243
X0325765Y1507295
X0335214Y1507295
X0330489Y1507295
X0321041Y1542641
X0316316Y1542641
X0311113Y1542425
X0319366Y1536063
X0319646Y1514243
X0314922Y1514243
X0313750Y1519195
X0321041Y1507295
X0316316Y1507295
X0311009Y1507514
X0262777Y1536063
X0247997Y1536063
X0257446Y1536063
X0257726Y1514243
X0248277Y1514243
X0254396Y1507295
X0249671Y1507295
X0259120Y1507295
X0238548Y1536063
X0188254Y1542641
X0243553Y1514243
X0207152Y1542641
X0238828Y1514243
X0202427Y1542641
X0234104Y1514243
X0244947Y1507295
X0240223Y1507295
X0235498Y1507295
X0230774Y1542641
X0249671Y1542641
X0224375Y1536063
X0259120Y1542641
X0254396Y1542641
X0197703Y1542641
X0229380Y1514243
X0224655Y1514243
X0219931Y1514243
X0230774Y1507295
X0226049Y1507295
X0221325Y1507295
X0211876Y1542641
X0214926Y1536063
X0244947Y1542641
X0235498Y1542641
X0240223Y1542641
X0210482Y1514243
X0215206Y1514243
X0205758Y1514243
X0216601Y1507295
X0211876Y1507295
X0207152Y1507295
X0202427Y1507295
X0191304Y1536063
X0200753Y1536063
X0196029Y1536063
X0226049Y1542641
X0191584Y1514243
X0201033Y1514243
X0196309Y1514243
X0197703Y1507295
X0192979Y1507295
X0188254Y1507295
X0186860Y1514243
X0185688Y1519195
X0182947Y1507512
X1652743Y1647292
X1652743Y1635380
X1646713Y1657292
X1638913Y1657292
X1634653Y1657292
X1644953Y1647292
X1640673Y1647292
X1644953Y1635380
X1640673Y1635286
X1646713Y1625380
X1638923Y1625380
X1634653Y1625380
X1626853Y1657292
X1622593Y1657292
X1632893Y1647292
X1620833Y1647292
X1628613Y1647292
X1632893Y1635380
X1620833Y1635380
X1628613Y1635380
X1626853Y1625380
X1622593Y1625380
X1610533Y1657292
X1614793Y1657292
X1608773Y1647292
X1616553Y1647292
X1604493Y1647292
X1608773Y1635380
X1616553Y1635380
X1604493Y1635380
X1614793Y1625380
X1610533Y1625380
X1602733Y1657292
X1598473Y1657292
X1590673Y1657292
X1596713Y1647292
X1592433Y1647292
X1596713Y1635380
X1592433Y1635380
X1598473Y1625380
X1602733Y1625380
X1590673Y1625380
X1586413Y1657292
X1578613Y1657292
X1574353Y1657292
X1584653Y1647292
X1580373Y1647292
X1584653Y1635380
X1580373Y1635380
X1586413Y1625380
X1578613Y1625380
X1574353Y1625380
X1566553Y1657292
X1562293Y1657292
X1572593Y1647292
X1560533Y1647292
X1568313Y1647292
X1572593Y1635380
X1560533Y1635380
X1568313Y1635380
X1566553Y1625380
X1562293Y1625380
X1550233Y1657292
X1554493Y1657292
X1548473Y1647292
X1556253Y1647292
X1544193Y1647292
X1548473Y1635380
X1556253Y1635380
X1544193Y1635380
X1554493Y1625380
X1550233Y1625380
X1538173Y1657292
X1542433Y1657292
X1530373Y1657292
X1536413Y1647292
X1532133Y1647292
X1536413Y1635380
X1532133Y1635380
X1538173Y1625380
X1542433Y1625380
X1530373Y1625380
X1526113Y1657292
X1514053Y1657292
X1518313Y1657292
X1524353Y1647292
X1520073Y1647292
X1524353Y1635380
X1520073Y1635380
X1526113Y1625380
X1518313Y1625380
X1514053Y1625380
X1506253Y1657292
X1501993Y1657292
X1512293Y1647292
X1500233Y1647292
X1508013Y1647292
X1512293Y1635380
X1500233Y1635380
X1508013Y1635380
X1506253Y1625380
X1501993Y1625380
X1489933Y1657292
X1494193Y1657292
X1488173Y1647292
X1495953Y1647292
X1488173Y1635380
X1495953Y1635380
X1494193Y1625380
X1489933Y1625380
X1482133Y1657292
X1477873Y1657292
X1470073Y1657292
X1476113Y1647292
X1483893Y1647292
X1471833Y1647292
X1476113Y1635380
X1483893Y1635380
X1471833Y1635380
X1477873Y1625380
X1482133Y1625380
X1470073Y1625380
X1458013Y1657292
X1465813Y1657292
X1464053Y1647292
X1464053Y1635380
X1465813Y1625380
X1458013Y1625380
X1382539Y1657292
X1388569Y1647292
X1380779Y1647292
X1380779Y1635380
X1388569Y1635380
X1382539Y1625380
X1374739Y1657292
X1370479Y1657292
X1376499Y1647292
X1368719Y1647292
X1376499Y1635286
X1368719Y1635380
X1374740Y1625380
X1370479Y1625380
X1362679Y1657292
X1350619Y1657292
X1358419Y1657292
X1364439Y1647292
X1352379Y1647292
X1356659Y1647292
X1364439Y1635380
X1356659Y1635380
X1352379Y1635380
X1362679Y1625380
X1358419Y1625380
X1350619Y1625380
X1346359Y1657292
X1338559Y1657292
X1344599Y1647292
X1340319Y1647292
X1344599Y1635380
X1340319Y1635380
X1346359Y1625380
X1338559Y1625380
X1334299Y1657292
X1326499Y1657292
X1322239Y1657292
X1332539Y1647292
X1320479Y1647292
X1328259Y1647292
X1332539Y1635380
X1328259Y1635380
X1320479Y1635380
X1334299Y1625380
X1322239Y1625380
X1326499Y1625380
X1314439Y1657292
X1310179Y1657292
X1316199Y1647292
X1308419Y1647292
X1316199Y1635380
X1308419Y1635380
X1314439Y1625380
X1310179Y1625380
X1302379Y1657292
X1290319Y1657292
X1298119Y1657292
X1304139Y1647292
X1292079Y1647292
X1296359Y1647292
X1304139Y1635380
X1296359Y1635380
X1292079Y1635380
X1302379Y1625380
X1290319Y1625380
X1298119Y1625380
X1286059Y1657292
X1278259Y1657292
X1284299Y1647292
X1280019Y1647292
X1284299Y1635380
X1280019Y1635380
X1286059Y1625380
X0423429Y0908324
X1278259Y1625380
X1273999Y1657292
X1261939Y1657292
X1266199Y1657292
X1272239Y1647292
X1267959Y1647292
X1272239Y1635380
X1267959Y1635380
X1273999Y1625380
X1261939Y1625380
X1266199Y1625380
X1249879Y1657292
X1254139Y1657292
X1260179Y1647292
X1255899Y1647292
X1248119Y1647292
X1260179Y1635380
X1255899Y1635380
X1248119Y1635380
X1254139Y1625380
X1249879Y1625380
X1242079Y1657292
X1237819Y1657292
X1243839Y1647292
X1231779Y1647292
X1236059Y1647292
X1243839Y1635380
X1236059Y1635380
X1231779Y1635380
X1242079Y1625380
X1237819Y1625380
X1225759Y1657292
X1230019Y1657292
X1217959Y1657292
X1219719Y1647292
X1223999Y1647292
X1219719Y1635380
X1223999Y1635380
X1230019Y1625380
X1225759Y1625380
X1217959Y1625380
X1213699Y1657292
X1205899Y1657292
X1201639Y1657292
X1211939Y1647292
X1207659Y1647292
X1211939Y1635380
X1207659Y1635380
X1213699Y1625380
X1201639Y1625380
X1205899Y1625380
X1193839Y1657292
X1199879Y1647292
X1199879Y1635380
X1193839Y1625380
X0637079Y1614292
X0638839Y1624292
X0644869Y1614292
X0637079Y1602380
X0644869Y1602380
X0638839Y1592380
X0625019Y1614292
X0620739Y1614292
X0626779Y1624292
X0632799Y1614292
X0631039Y1624292
X0625019Y1602380
X0620739Y1602380
X0632799Y1602286
X0626779Y1592380
X0631039Y1592380
X0612959Y1614292
X0614719Y1624292
X0606919Y1624292
X0608679Y1614292
X0618979Y1624292
X0612959Y1602380
X0608679Y1602380
X0606919Y1592380
X0614719Y1592380
X0618979Y1592380
X0600899Y1614292
X0590599Y1624292
X0594859Y1624292
X0596619Y1614292
X0602659Y1624292
X0600899Y1602380
X0596619Y1602380
X0594859Y1592380
X0590599Y1592380
X0602659Y1592380
X0576779Y1614292
X0588839Y1614292
X0578539Y1624292
X0582799Y1624292
X0584559Y1614292
X0576779Y1602380
X0588839Y1602380
X0584559Y1602380
X0582799Y1592380
X0578539Y1592380
X0564719Y1614292
X0566479Y1624292
X0560439Y1614292
X0570739Y1624292
X0572499Y1614292
X0564719Y1602380
X0560439Y1602380
X0572499Y1602380
X0566479Y1592380
X0570739Y1592380
X0552659Y1614292
X0554419Y1624292
X0546619Y1624292
X0548379Y1614292
X0558679Y1624292
X0552659Y1602380
X0548379Y1602380
X0554419Y1592380
X0546619Y1592380
X0558679Y1592380
X0540599Y1614292
X0534559Y1624292
X0530299Y1624292
X0536319Y1614292
X0542359Y1624292
X0540599Y1602380
X0536319Y1602380
X0534559Y1592380
X0530299Y1592380
X0542359Y1592380
X0516479Y1614292
X0528539Y1614292
X0522499Y1624292
X0518239Y1624292
X0524259Y1614292
X0516479Y1602380
X0528539Y1602380
X0524259Y1602380
X0522499Y1592380
X0518239Y1592380
X0504419Y1614292
X0510439Y1624292
X0506179Y1624292
X0500139Y1614292
X0512199Y1614292
X0504419Y1602380
X0500139Y1602380
X0512199Y1602380
X0506179Y1592380
X0510439Y1592380
X0492359Y1614292
X0494119Y1624292
X0486319Y1624292
X0488079Y1614292
X0498379Y1624292
X0492359Y1602380
X0488079Y1602380
X0494119Y1592380
X0486319Y1592380
X0498379Y1592380
X0480299Y1614292
X0474259Y1624292
X0476019Y1614292
X0482059Y1624292
X0480299Y1602380
X0476019Y1602380
X0474259Y1592380
X0482059Y1592380
X0462199Y1624292
X0469999Y1624292
X0468239Y1614292
X0456179Y1614292
X0463959Y1614292
X0468239Y1602380
X0456179Y1602380
X0463959Y1602380
X0462199Y1592380
X0457939Y1592380
X0469999Y1592380
X0450139Y1624292
X0450139Y1592380
X0366866Y1624292
X0368626Y1614292
X0372906Y1614292
X0380696Y1614292
X0374666Y1624292
X0372906Y1602380
X0368626Y1602286
X0380696Y1602380
X0366866Y1592380
X0374666Y1592380
X0362606Y1624292
X0356566Y1614292
X0360846Y1614292
X0354806Y1624292
X0360846Y1602380
X0356566Y1602380
X0354806Y1592380
X0362606Y1592380
X0336726Y1614292
X0344506Y1614292
X0348786Y1614292
X0338486Y1624292
X0342746Y1624292
X0350546Y1624292
X0348786Y1602380
X0344506Y1602380
X0336726Y1602380
X0350546Y1592380
X0342746Y1592380
X0338486Y1592380
X0324666Y1614292
X0332446Y1614292
X0330686Y1624292
X0326426Y1624292
X0332446Y1602380
X0324666Y1602380
X0326426Y1592380
X0330686Y1592380
X0308326Y1614292
X0312606Y1614292
X0320386Y1614292
X0306566Y1624292
X0318626Y1624292
X0314366Y1624292
X0320386Y1602380
X0312606Y1602380
X0308326Y1602380
X0314366Y1592380
X0306566Y1592380
X0318626Y1592380
X0296266Y1614292
X0300546Y1614292
X0294516Y1624292
X0302306Y1624292
X0300546Y1602380
X0296266Y1602380
X0294506Y1592380
X0302306Y1592380
X0276426Y1614292
X0284206Y1614292
X0288486Y1614292
X0278186Y1624292
X0282446Y1624292
X0290236Y1624292
X0288486Y1602380
X0284206Y1602380
X0276426Y1602380
X0282446Y1592380
X0278186Y1592380
X0290246Y1592380
X0264366Y1614292
X0272146Y1614292
X0266126Y1624292
X0270386Y1624292
X0272146Y1602380
X0264366Y1602380
X0266126Y1592380
X0270386Y1592380
X0260086Y1614292
X0252306Y1614292
X0248026Y1614292
X0254066Y1624292
X0258326Y1624292
X0260086Y1602380
X0252306Y1602380
X0248026Y1602380
X0254066Y1592380
X0258326Y1592380
X0235966Y1614292
X0240246Y1614292
X0234206Y1624292
X0242006Y1624292
X0246266Y1624292
X0240246Y1602380
X0235966Y1602380
X0246266Y1592380
X0234206Y1592380
X0242006Y1592380
X0223906Y1614292
X0228186Y1614292
X0217886Y1624292
X0222146Y1624292
X0229946Y1624292
X0228186Y1602380
X0223906Y1602380
X0222146Y1592380
X0217886Y1592380
X0229946Y1592380
X0204066Y1614292
X0211846Y1614292
X0216126Y1614292
X0210086Y1624292
X0205826Y1624292
X0211846Y1602380
X0204066Y1602380
X0216126Y1602380
X0205826Y1592380
X0210086Y1592380
X0192006Y1614292
X0199786Y1614292
X0198026Y1624292
X0193766Y1624292
X0199786Y1602380
X0192006Y1602380
X0193766Y1592380
X0198026Y1592380
X0185966Y1624292
X0185966Y1592380
X0546712Y1130104
X0457893Y1130104
X1432854Y0908323
X0377523Y1222274
X1489547Y1130103
X1434035Y1130103
X1502499Y1133292
X0424611Y1130105
X0457939Y1624292
X0353114Y0908324
X0303594Y1151379
X0303594Y1157757
X0303594Y1145001
X0303594Y1138623
X0303594Y1132246
R08Y-0006378
X0303594Y1068466
X0303594Y1074844
X0303594Y1062088
X0303594Y1049332
X0303594Y1055710
X0303594Y1042954
X0303594Y1036576
X0303594Y1030198
X0302413Y1001852
X0302413Y1008230
X0302413Y0995474
R14Y-0006378
X0303154Y0898758
X0303154Y0892380
X0305004Y0882813
X0303154Y0886002
X0303154Y0879624
X0308705Y0882813
X0314256Y0873246
X0319807Y0876435
X0310555Y0879624
X0317957Y0879624
X0310555Y0873246
X0308705Y0940214
X0314256Y0937025
X0314256Y0930647
X0308705Y0933836
X0316107Y0927458
X0308705Y0927458
X0316107Y0921080
X0308705Y0921080
X0308705Y0914702
X0314256Y0917891
X0316107Y0908325
X0314256Y0911513
X0308705Y0908325
X0308705Y0901947
X0316107Y0901947
X0314256Y0898758
X0308705Y0895569
X0314256Y0892380
X0319807Y0882813
X0308705Y0889191
X0316107Y0889191
X0316107Y0882813
X0314256Y0886002
X0310555Y0886002
X0314256Y0968915
X0316107Y0965726
X0308705Y0965726
X0308705Y0959348
X0316107Y0959348
X0314256Y0956159
X0308705Y0952970
X0308705Y0946592
X0316107Y0946592
X0314256Y0949781
X0316107Y0940214
X0308705Y1003994
X0308705Y1010372
X0316107Y1010372
X0314256Y1007183
X0316107Y1003994
X0314256Y0994427
X0308705Y0997616
X0316107Y0997616
X0314256Y0988049
X0310555Y0988049
X0308705Y0991238
X0319807Y0984860
X0312406Y0984860
X0308705Y0984860
X0316107Y0984860
X0308705Y0972104
X0314256Y0975293
X0316107Y0978482
X0308705Y0978482
X0317957Y0981671
X0315437Y1069513
X0309886Y1066324
X0309886Y1072702
X0317288Y1072702
X0315437Y1063135
X0313587Y1059946
X0309886Y1059946
X0317288Y1059946
X0317288Y1053568
X0315437Y1050379
X0309886Y1053568
X0311736Y1056757
X0309886Y1047190
X0315437Y1044001
X0309886Y1034434
X0317288Y1034434
X0309886Y1040812
X0317288Y1040812
X0315437Y1031245
X0309886Y1028056
X0309886Y1098214
X0317288Y1098214
X0315437Y1101403
X0309886Y1104592
X0317288Y1091836
X0309886Y1091836
X0309886Y1085458
X0315437Y1088647
X0315437Y1082269
X0309886Y1079080
X0317288Y1079080
X0315437Y1146048
X0309886Y1149237
X0317288Y1149237
X0309886Y1142859
X0317288Y1136481
X0315437Y1139670
X0309886Y1136481
X0317288Y1130103
X0309886Y1130103
X0315437Y1126915
X0315437Y1120537
X0309886Y1123726
X0317288Y1117348
X0309886Y1117348
X0317288Y1110970
X0309886Y1110970
X0315437Y1107781
X0320988Y1161993
X0320988Y1155615
X0311736Y1165182
X0308036Y1158804
X0313587Y1155615
X0309886Y1155615
X0317288Y1155615
X0329059Y0892380
X0327209Y0895569
X0321658Y0892380
X0334610Y0895569
X0327209Y0889191
X0334610Y0889191
X0329059Y0886002
X0330910Y0882813
X0325358Y0886002
X0321658Y0886002
X0334610Y0882813
X0334598Y0872066
X0325358Y0879624
X0332760Y0879624
X0327209Y0876435
X0327209Y0921080
X0329059Y0924269
X0321658Y0924269
X0334610Y0921080
X0329059Y0917891
X0327209Y0914702
X0321658Y0917891
X0334610Y0914702
X0327209Y0908325
X0329059Y0911513
X0329059Y0905135
X0321658Y0911513
X0321658Y0905135
X0329059Y0898758
X0327209Y0901947
X0321658Y0898758
X0334610Y0901947
X0327209Y0952970
X0321658Y0956159
X0334610Y0952970
X0327209Y0946592
X0329059Y0949781
X0329059Y0943403
X0321658Y0949781
X0321658Y0943403
X0334610Y0946592
X0329059Y0937025
X0327209Y0940214
X0321658Y0937025
X0334610Y0940214
X0329059Y0930647
X0327209Y0933836
X0327209Y0927458
X0321658Y0930647
X0334610Y0933836
X0334610Y0927458
X0330910Y0984860
X0327209Y0984860
X0334610Y0984860
X0327209Y0978482
X0329059Y0981671
X0332760Y0981671
X0327209Y0972104
X0329059Y0975293
X0321658Y0981671
X0321658Y0975293
X0334610Y0978482
X0334610Y0972104
X0329059Y0968915
X0321658Y0968915
X0327209Y0959348
X0321658Y0962537
X0327209Y0965726
X0329059Y0962537
X0334610Y0965726
X0334610Y0959348
X0329059Y0956159
X0335791Y1028056
X0328390Y1028056
X0327209Y1003994
X0329059Y1007183
X0327209Y1010372
X0321658Y1007183
X0334610Y1010372
X0334610Y1003994
X0329059Y1000805
X0321658Y1000805
X0327209Y0997616
X0329059Y0994427
X0329059Y0988049
X0327209Y0991238
X0321658Y0994427
X0321658Y0988049
X0334610Y0997616
X0334610Y0991238
X0328390Y1066324
X0322839Y1069513
X0330240Y1063135
X0322839Y1063135
X0335791Y1059946
R02Y-0006378
X0330240Y1056757
X0330240Y1050379
X0324689Y1059946
X0328390Y1059946
X0328390Y1053568
X0326539Y1056757
X0322839Y1056757
X0322839Y1050379
X0328390Y1047190
X0335791Y1034434
X0335791Y1040812
X0330240Y1044001
R02Y-0006378
X0328390Y1034434
X0328390Y1040812
X0322839Y1044001
R02Y-0006378
X0335791Y1085458
X0335791Y1079080
X0330240Y1082269
X0322839Y1082269
X0330240Y1088647
X0328390Y1085458
X0322839Y1088647
X0328390Y1079080
X0330240Y1075891
X0322839Y1075891
X0335791Y1066324
X0335791Y1072702
X0330240Y1069513
X0328390Y1072702
X0335791Y1117348
X0335791Y1110970
X0322839Y1114159
X0330240Y1114159
X0328390Y1117348
X0328390Y1110970
X0330240Y1107781
X0322839Y1107781
X0335791Y1098214
X0335791Y1104592
X0335791Y1091836
X0330240Y1101403
X0322839Y1101403
X0328390Y1098214
X0328390Y1104592
X0330240Y1095025
X0322839Y1095025
X0328390Y1091836
X0335791Y1161993
X0335791Y1155615
X0330240Y1165182
X0328390Y1161993
X0322839Y1158804
X0333941Y1158804
X0330240Y1158804
X0326539Y1158804
X0322839Y1152426
X0330240Y1152426
X0328390Y1155615
X0335791Y1149237
R02Y-0006378
X0322839Y1146048
X0330240Y1146048
X0328390Y1149237
X0330240Y1139670
X0328390Y1136481
X0322839Y1139670
X0328390Y1142859
X0335791Y1123726
X0328390Y1130103
X0330240Y1133293
X0322839Y1133293
X0322839Y1120537
X0330240Y1120537
X0328390Y1123726
X0322839Y1126915
X0330240Y1126915
X0340162Y0892380
X0342012Y0889191
X0347563Y0892380
X0342012Y0882813
X0347563Y0886002
X0340162Y0886002
X0336461Y0886002
X0345713Y0882813
X0340162Y0879568
X0343862Y0879624
X0342012Y0921080
X0340162Y0917891
X0347563Y0924269
X0347563Y0917891
X0342012Y0908325
X0340162Y0911513
X0340162Y0898758
X0342012Y0901947
X0347563Y0911513
X0347563Y0905135
X0347563Y0898758
X0340162Y0956159
X0342012Y0946592
X0340162Y0949781
X0347563Y0956159
R02Y-0006378
X0340162Y0937025
X0342012Y0940214
X0340162Y0930647
X0342012Y0927458
X0347563Y0937025
X0347563Y0930647
X0340162Y0994427
X0342012Y0997616
X0340162Y0988049
X0347563Y1000805
R02Y-0006378
X0342012Y0984860
X0342012Y0978482
X0343862Y0981671
X0340162Y0975293
X0345713Y0984860
X0347563Y0981671
X0347563Y0975293
X0340162Y0968915
X0342012Y0965726
X0342012Y0959348
X0347563Y0968915
X0347563Y0962537
X0341343Y1044001
X0348744Y1044001
X0343193Y1034434
X0348744Y1037623
X0343193Y1040812
X0341343Y1031245
X0348744Y1031245
X0342012Y1003994
X0340162Y1007183
X0342012Y1010372
X0347563Y1007183
X0348744Y1088647
X0341343Y1088647
X0348744Y1082269
X0341343Y1082269
X0348744Y1075891
X0343193Y1079080
X0348744Y1069513
X0343193Y1072702
X0341343Y1069513
X0348744Y1063135
X0341343Y1063135
X0339492Y1059946
X0343193Y1059946
X0348744Y1050379
X0341343Y1050379
X0343193Y1053568
X0348744Y1056757
X0337642Y1056757
X0350595Y1059946
X0348744Y1114159
X0343193Y1117348
X0343193Y1110970
X0348744Y1107781
X0341343Y1107781
X0343193Y1098214
X0341343Y1101403
X0348744Y1101403
X0343193Y1091836
X0348744Y1095025
X0341343Y1146048
X0348744Y1146048
X0343193Y1149237
X0348744Y1139670
X0343193Y1136481
X0341343Y1139670
X0343193Y1130103
X0348744Y1133293
X0348744Y1126915
X0341343Y1126915
X0341343Y1120537
X0348744Y1120537
X0348744Y1165182
X0346894Y1161993
X0343193Y1161993
X0337642Y1165182
X0346894Y1155615
R02X-0003701
X0348744Y1158804
X0341343Y1158804
X0337642Y1158804
X0348744Y1152426
X0356803Y0872066
X0354965Y0879624
X0360516Y0876435
X0351265Y0879568
X0360516Y0908325
X0354965Y0905135
X0354965Y0911513
X0353114Y0901947
X0360516Y0901947
X0354965Y0898758
X0353114Y0895569
X0353114Y0889191
X0360516Y0895569
X0360516Y0889191
X0354965Y0892380
X0354965Y0886002
X0353114Y0882813
X0360516Y0882813
X0356815Y0882813
X0362366Y0886002
X0351264Y0886002
X0353114Y0921080
X0360516Y0921080
X0354965Y0924269
X0353114Y0914702
X0360516Y0914702
X0354965Y0917891
X0354965Y0949781
X0354965Y0943403
X0353114Y0940214
X0360516Y0940214
X0354965Y0937025
X0353114Y0927458
X0353114Y0933836
X0360516Y0933836
X0360516Y0927458
X0354965Y0930647
X0354965Y0968915
X0354965Y0962537
X0353114Y0965726
X0353114Y0959348
X0360516Y0965726
X0360516Y0959348
X0354965Y0956159
X0353114Y0952970
X0360516Y0952970
X0353114Y0946592
X0360516Y0946592
X0354965Y1000805
R02Y-0006378
X0353114Y0997616
X0353114Y0991238
X0360516Y0991238
X0360516Y0997616
X0353114Y0984860
R02X0003701
X0353114Y0978482
X0353114Y0972104
X0358665Y0981671
X0360516Y0978482
X0360516Y0972104
X0354965Y0981671
X0354965Y0975293
X0361697Y1034434
X0356146Y1037623
X0356146Y1031245
X0354295Y1034434
X0354295Y1040812
X0361697Y1028056
X0354295Y1028056
X0353114Y1010372
X0360516Y1010372
X0353114Y1003994
X0360516Y1003994
X0354965Y1007183
X0352445Y1056757
X0361697Y1059946
X0365398Y1059946
X0361697Y1053568
X0356146Y1050379
X0356146Y1056757
X0363547Y1056757
X0354295Y1059946
X0354295Y1053568
X0361697Y1047190
X0354295Y1047190
X0356146Y1044001
X0361697Y1040812
X0356146Y1082269
X0361697Y1085458
X0356146Y1088647
X0354295Y1085458
X0361697Y1079080
X0354295Y1079080
X0356146Y1075891
X0361697Y1072702
X0361697Y1066324
X0356146Y1069513
X0354295Y1066324
X0354295Y1072702
X0356146Y1063135
X0361697Y1098214
X0356146Y1101403
X0361697Y1104592
X0354295Y1098214
X0354295Y1104592
X0356146Y1095025
X0361697Y1091836
X0354295Y1091836
X0361697Y1130103
X0356146Y1133293
X0361697Y1123726
X0356146Y1120537
X0356146Y1126915
X0354295Y1123726
X0354295Y1117348
X0356146Y1114159
X0361697Y1117348
X0361697Y1110970
X0354295Y1110970
X0356146Y1107781
X0354295Y1161993
X0354295Y1155615
X0361697Y1155615
X0356146Y1152426
X0365398Y1155615
X0352445Y1158804
X0359847Y1158804
X0356146Y1158804
X0363547Y1158804
X0354295Y1149237
X0356146Y1146048
X0361697Y1149237
X0361697Y1142859
X0354295Y1142859
X0361697Y1136481
X0356146Y1139670
X0354295Y1136481
X0361697Y1161993
X0356146Y1165182
X0363547Y1165182
X0377169Y0879624
X0375319Y0876435
X0373469Y0879624
X0369768Y0879624
X0379020Y0895569
X0377169Y0886002
X0379020Y0882813
X0373469Y0886002
X0367917Y0882813
X0373469Y0892380
X0367917Y0889191
X0366067Y0892380
X0366067Y0886002
X0379020Y0921080
X0373469Y0924269
X0367917Y0921080
X0373469Y0917891
X0366067Y0917891
X0373469Y0905135
X0373469Y0911513
X0379020Y0908325
X0373469Y0898758
X0367917Y0901947
X0366067Y0911513
X0366067Y0898758
X0379020Y0940214
X0373469Y0937025
X0367917Y0940214
X0373469Y0930647
X0379020Y0933836
X0367917Y0927458
X0366067Y0937025
X0366067Y0930647
X0379020Y0965726
X0373469Y0968915
X0373469Y0962537
X0367917Y0965726
X0367917Y0959348
X0366067Y0968915
X0379020Y0952970
X0373469Y0956159
R02Y-0006378
X0367917Y0946592
X0366067Y0956159
X0366067Y0949781
X0379020Y0978482
X0371618Y0984860
X0379020Y0984860
X0367917Y0984860
X0373469Y0981671
X0373469Y0975293
X0367917Y0978482
X0369768Y0981671
X0366067Y0975293
X0380201Y1028056
X0367917Y1010372
X0379020Y1003994
X0367917Y1003994
X0373469Y1007183
X0366067Y1007183
X0373469Y1000805
X0373469Y0994427
X0379020Y0997616
X0373469Y0988049
X0379020Y0991238
X0367917Y0997616
X0366067Y0988049
X0366067Y0994427
X0376500Y1059946
X0380201Y1059946
X0374650Y1056757
X0374650Y1050379
X0378351Y1056757
X0380201Y1053568
X0369099Y1059946
X0369099Y1053568
X0380201Y1047190
X0367248Y1050379
X0374650Y1044001
X0374650Y1037623
X0380201Y1034434
X0380201Y1040812
X0374650Y1031245
X0369099Y1040812
X0369099Y1034434
X0367248Y1044001
X0367248Y1031245
X0374650Y1069513
X0380201Y1072702
X0369099Y1072702
X0374650Y1063135
X0367248Y1069513
X0367248Y1063135
X0374650Y1082269
X0374650Y1088647
X0380201Y1085458
X0369099Y1079080
X0374650Y1075891
X0367248Y1082269
X0367248Y1088647
X0374650Y1114159
X0380201Y1117348
X0369099Y1117348
X0369099Y1110970
X0374650Y1107781
X0367248Y1107781
X0374650Y1101403
X0380201Y1098214
X0380201Y1104592
X0369099Y1098214
X0374650Y1095025
X0369099Y1091836
X0367248Y1101403
X0369099Y1130103
X0374650Y1133293
X0380201Y1130103
X0374650Y1126915
X0374650Y1120537
X0367248Y1126915
X0367248Y1120537
X0376500Y1161993
X0374650Y1158804
X0378351Y1158804
X0374650Y1152426
X0372799Y1155615
X0369099Y1155615
X0380201Y1155615
X0374650Y1146048
X0369099Y1149237
X0369099Y1136481
X0374650Y1139670
X0380201Y1142859
X0367248Y1146048
X0367248Y1139670
X0393823Y0889191
X0386421Y0889191
X0390122Y0895569
X0391973Y0892380
X0390122Y0882813
X0388272Y0886002
X0393823Y0882813
X0386421Y0882813
X0384571Y0886002
X0380870Y0892380
X0382721Y0889191
X0382721Y0882813
X0384571Y0873246
X0388272Y0879624
X0386421Y0876435
X0390122Y0908325
X0391973Y0911513
X0391973Y0905135
X0386421Y0901947
X0390122Y0901947
X0391973Y0898758
X0393823Y0901947
X0380870Y0905135
X0380870Y0911513
X0380870Y0898758
X0382721Y0901947
X0390122Y0940214
X0390122Y0933836
X0391973Y0930647
X0393823Y0933836
X0390122Y0927458
X0393823Y0927458
X0386421Y0933836
X0386421Y0927458
X0380870Y0930647
X0382721Y0933836
X0382721Y0927458
X0391973Y0924269
X0390122Y0921080
X0390122Y0914702
X0393823Y0914702
X0391973Y0917891
X0386421Y0914702
X0380870Y0924269
X0380870Y0917891
X0382721Y0914702
X0390122Y0952970
X0391973Y0956159
X0390122Y0946592
X0393823Y0946592
X0391973Y0949781
X0391973Y0943403
X0386421Y0946592
X0380870Y0956159
R02Y-0006378
X0382721Y0946592
X0393823Y0984860
X0386421Y0972104
X0391973Y0975293
X0391973Y0981671
X0384571Y0981671
X0390122Y0978482
X0390122Y0972104
X0393823Y0972104
X0380870Y0975293
X0382721Y0972104
X0386421Y0984860
X0391973Y0968915
X0391973Y0962537
X0386421Y0959348
X0390122Y0965726
X0390122Y0959348
X0393823Y0959348
X0380870Y0968915
X0380870Y0962537
X0382721Y0959348
X0393154Y1050379
X0393154Y1056757
X0385752Y1050379
X0395004Y1053568
X0391303Y1059946
X0387603Y1053568
X0387603Y1047190
X0395004Y1047190
X0393154Y1037623
X0393154Y1031245
X0395004Y1034434
X0387603Y1040812
X0387603Y1034434
X0395004Y1040812
X0385752Y1044001
R02Y-0006378
X0393154Y1044001
X0395004Y1028056
X0387603Y1028056
X0384571Y1007183
X0395673Y1007183
X0393823Y1003994
X0391973Y1007183
X0390122Y1010372
X0382721Y1010372
X0386421Y1003994
X0393823Y0997616
X0384571Y1000805
X0391973Y1000805
X0386421Y0997616
X0386421Y0991238
X0393823Y0991238
X0391973Y0994427
X0384571Y0988049
X0384571Y0994427
X0391973Y0988049
X0393154Y1069513
X0391303Y1066324
X0391303Y1072702
X0383902Y1066324
X0387603Y1066324
X0395004Y1066324
X0393154Y1063135
X0382051Y1069513
X0382051Y1063135
X0383902Y1104592
X0387603Y1104592
X0395004Y1104592
X0391303Y1104592
X0391303Y1098214
X0387603Y1091836
X0395004Y1091836
X0391303Y1091836
X0393154Y1095025
X0383902Y1091836
X0382051Y1095025
X0393154Y1088647
X0391303Y1085458
X0393154Y1082269
X0395004Y1079080
X0391303Y1079080
X0383902Y1079080
X0387603Y1079080
X0393154Y1075891
X0382051Y1082269
X0382051Y1088647
X0382051Y1075891
X0393154Y1133293
X0393154Y1120537
X0395004Y1123726
X0391303Y1123726
X0393154Y1126915
X0387603Y1123726
X0383902Y1123726
X0382051Y1133293
X0382051Y1120537
X0382051Y1126915
X0393154Y1114159
X0391303Y1117348
X0395004Y1110970
X0391303Y1110970
X0393154Y1107781
X0387603Y1110970
X0383902Y1110970
X0382051Y1114159
X0382051Y1107781
X0387603Y1149237
X0383902Y1149237
X0395004Y1149237
X0393154Y1146048
X0391303Y1142859
X0387603Y1136481
X0383902Y1136481
X0391303Y1136481
X0395004Y1136481
X0393154Y1139670
X0382051Y1146048
X0382051Y1139670
X0387603Y1161993
X0387603Y1155615
X0383902Y1155615
X0395004Y1155615
X0391303Y1155615
X0389453Y1158804
X0403075Y0892380
X0404925Y0889191
X0408626Y0889191
X0401225Y0895569
X0404925Y0882813
X0408626Y0882813
X0401225Y0882813
X0397524Y0889191
X0397524Y0882813
X0399374Y0879624
X0399374Y0873246
X0397524Y0876435
X0410477Y0873246
X0401225Y0927458
X0397524Y0933836
X0397524Y0927458
X0403075Y0924269
X0401225Y0921080
X0404925Y0914702
X0403075Y0917891
X0408626Y0914702
X0401225Y0914702
X0397524Y0914702
X0403075Y0911513
X0403075Y0905135
X0403075Y0898758
X0404925Y0901947
X0408626Y0901947
X0401225Y0901947
X0397524Y0901947
X0403075Y0956159
X0401225Y0952970
X0404925Y0946592
X0403075Y0949781
X0408626Y0946592
X0403075Y0943403
X0401225Y0946592
X0397524Y0946592
X0401225Y0940214
X0403075Y0930647
X0404925Y0927458
X0408626Y0927458
X0401225Y0933836
X0404923Y1010366
X0410464Y1007175
X0401225Y1003994
X0399374Y1007183
X0397524Y1010372
X0408614Y0997608
X0399374Y1000805
X0401225Y0997616
X0401225Y0991238
X0406776Y0988049
X0399374Y0994427
X0399374Y0988049
X0408626Y0991238
X0408626Y0984860
X0401225Y0984860
X0403075Y0975293
X0401225Y0978482
X0406776Y0981671
X0399374Y0981671
X0404925Y0972104
X0408626Y0972104
X0401225Y0972104
X0397524Y0972104
X0403075Y0968915
X0403075Y0962537
X0404925Y0959348
X0408626Y0959348
X0401225Y0959348
X0401225Y0965726
X0397524Y0959348
X0407957Y1050379
X0400555Y1050379
X0400555Y1056757
X0409807Y1053568
X0402406Y1059946
X0407957Y1056757
X0402406Y1053568
X0409807Y1047190
X0402406Y1047190
X0409795Y1040820
X0409795Y1034442
X0400555Y1044001
R02Y-0006378
X0402406Y1040812
X0398705Y1034434
X0409795Y1028064
X0398705Y1028056
X0402406Y1066324
X0409807Y1066324
X0406107Y1066324
X0404256Y1069513
X0402406Y1072702
X0404256Y1063135
X0398705Y1066324
X0404256Y1082269
X0402406Y1085458
X0404256Y1088647
X0402406Y1079080
X0409807Y1079080
X0406107Y1079080
X0404256Y1075891
X0398705Y1079080
X0402406Y1104592
R02Y-0006378
X0409807Y1091836
X0406107Y1091836
X0404256Y1095025
X0398705Y1104592
X0398705Y1091836
X0402406Y1117348
X0404256Y1114159
X0402406Y1110970
X0409807Y1110970
X0406107Y1110970
X0404256Y1107781
X0398705Y1110970
X0402406Y1130103
X0404256Y1133293
X0404256Y1126915
X0402406Y1123726
X0404256Y1120537
X0409807Y1123726
X0406107Y1123726
X0398705Y1123726
X0400555Y1165182
X0409807Y1161993
X0400555Y1158804
X0402406Y1155615
X0409807Y1155615
X0406107Y1155615
X0398705Y1161993
X0398705Y1155615
X0409807Y1149237
X0406107Y1149237
X0404256Y1146048
X0402406Y1136481
X0409807Y1136481
X0406107Y1136481
X0404256Y1139670
X0402406Y1142859
X0398705Y1149237
X0398705Y1136481
X0425280Y0911513
X0425280Y0905135
X0416028Y0901947
X0419729Y0901947
X0425280Y0898758
X0423429Y0901947
X0412327Y0908325
X0414177Y0911513
X0414177Y0905135
X0414177Y0898758
X0412327Y0901947
X0419729Y0889191
X0416028Y0889191
X0425280Y0892380
X0423429Y0895569
X0416028Y0882813
X0419729Y0882813
X0414177Y0892380
X0412327Y0895569
X0412327Y0882813
X0421579Y0873246
X0423429Y0940214
X0425280Y0937025
X0416028Y0933836
X0416028Y0927458
X0419729Y0933836
X0425280Y0930647
X0423429Y0933836
X0419729Y0927458
X0423429Y0927458
X0414177Y0937025
X0412327Y0940214
X0414177Y0930647
X0412327Y0933836
X0412327Y0927458
X0423429Y0921080
X0425280Y0924269
X0425280Y0917891
X0416028Y0914702
X0419729Y0914702
X0423429Y0914702
X0412327Y0921080
X0414177Y0924269
X0412327Y0914702
X0414177Y0917891
X0425280Y0975293
X0421579Y0981671
X0423429Y0978482
X0412327Y0972104
X0414177Y0975293
X0414177Y0981671
X0412327Y0978482
X0425280Y0968915
X0425280Y0962537
X0419729Y0959348
X0423429Y0959348
X0416028Y0959348
X0423429Y0965726
X0414177Y0968915
X0414177Y0962537
X0412327Y0959348
X0412327Y0965726
X0425280Y0956159
X0423429Y0952970
X0419729Y0946592
X0423429Y0946592
X0425280Y0949781
X0425280Y0943403
X0416028Y0946592
X0414177Y0956159
X0412327Y0952970
X0414177Y0943403
X0412327Y0946592
X0414177Y0949781
X0422760Y1050379
X0415358Y1050379
X0415358Y1056757
X0417209Y1053568
X0424610Y1059946
X0422760Y1056757
X0424610Y1053568
X0424610Y1047190
X0417209Y1047190
X0413508Y1059946
X0417197Y1040820
X0424598Y1040820
X0416015Y0997608
X0423417Y0997608
X0416028Y0991238
X0423429Y0991238
X0421579Y0988049
X0414177Y0988049
X0423429Y0984860
X0416028Y0984860
X0419729Y0972104
X0423429Y0972104
X0416028Y0972104
X0415358Y1069513
X0417209Y1066324
X0420910Y1066324
X0424610Y1066324
X0424610Y1072702
X0415358Y1063135
X0413508Y1066324
X0413508Y1072702
X0415358Y1101403
X0417209Y1104592
X0424610Y1098214
X0424610Y1104592
X0420910Y1104592
X0417209Y1091836
X0424610Y1091836
X0420910Y1091836
X0415358Y1095025
X0413508Y1104592
R02Y-0006378
X0415358Y1082269
X0415358Y1088647
X0424610Y1085458
X0417209Y1079080
X0424610Y1079080
X0420910Y1079080
X0415358Y1075891
X0413508Y1085458
X0413508Y1079080
X0413508Y1130103
X0413508Y1123726
X0415358Y1114159
X0424610Y1117348
X0417209Y1110970
X0420910Y1110970
X0424610Y1110970
X0415358Y1107781
X0413508Y1117348
X0413508Y1110970
X0415358Y1146048
X0417209Y1149237
X0420910Y1149237
X0417209Y1136481
X0415358Y1139670
X0420910Y1136481
X0424610Y1136481
X0424610Y1142859
X0413508Y1136481
X0413508Y1142859
X0415358Y1133293
X0417209Y1123726
X0420910Y1123726
X0424610Y1123726
X0415358Y1126915
X0415358Y1120537
X0420910Y1161993
X0422760Y1165182
X0422760Y1158804
X0417209Y1155615
X0420910Y1155615
X0424610Y1155615
X0411658Y1158804
X0413508Y1155615
X0434532Y0908325
X0432681Y0905135
X0434532Y0901947
X0428981Y0905135
X0434532Y0889191
X0434532Y0895569
X0427130Y0889191
X0430831Y0889191
X0427130Y0882813
X0430831Y0882813
X0432681Y0879624
X0434532Y0876435
X0434532Y0952970
X0434532Y0946592
X0432681Y0949781
X0428981Y0949781
X0434532Y0940214
X0432681Y0937025
X0434532Y0933836
X0434532Y0927458
X0432681Y0930647
X0428981Y0937025
X0428981Y0930647
X0434532Y0921080
X0434532Y0914702
X0432681Y0917891
X0428981Y0917891
X0430819Y0997608
X0428981Y0988049
X0430831Y0991238
X0434532Y0978482
X0432681Y0975293
X0434532Y0972104
X0430831Y0984860
X0428981Y0975293
X0428981Y0981671
X0434532Y0965726
X0434532Y0959348
X0432681Y0962537
X0428981Y0962537
X0435713Y1059946
X0432012Y1053568
X0432012Y1047190
X0430162Y1050379
X0430162Y1056757
X0433862Y1088647
X0435713Y1085458
X0435713Y1079080
X0433862Y1075891
X0426461Y1082269
X0426461Y1088647
X0430162Y1088647
X0426461Y1075891
X0430162Y1075891
X0435713Y1066324
X0435713Y1072702
X0433862Y1063135
X0426461Y1069513
X0430162Y1063135
X0426461Y1063135
X0435713Y1117348
X0435713Y1110970
X0433862Y1107781
X0426461Y1114159
X0426461Y1107781
X0430162Y1107781
X0433862Y1101403
X0435713Y1104592
R02Y-0006378
X0426461Y1101403
X0430162Y1101403
X0426461Y1095025
X0435713Y1161993
X0435713Y1155615
X0430162Y1158804
X0432012Y1149237
X0435713Y1149237
X0435713Y1142859
X0435713Y1136481
X0428311Y1149237
X0426461Y1146048
X0426461Y1139670
X0433862Y1133293
X0435713Y1130103
X0433862Y1120537
X0435713Y1123726
X0426461Y1133293
X0430162Y1133293
X0426461Y1120537
X0430162Y1120537
X0426461Y1126915
X0447460Y0879624
X0445609Y0876435
X0451160Y0930647
X0447460Y0930647
X0445609Y0940214
R02Y-0006378
X0454861Y0924269
X0454861Y0917891
X0451160Y0917891
X0447460Y0917891
X0445609Y0921080
X0445609Y0914702
X0447460Y0905135
X0454861Y0911513
X0454861Y0905135
X0451160Y0905135
X0454861Y0898758
X0445609Y0908325
X0445609Y0901947
X0454861Y0892380
X0453011Y0889191
X0449310Y0889191
X0453011Y0882813
X0445609Y0895569
R02Y-0006378
X0454204Y1040820
X0453023Y0997608
X0445622Y0997608
X0447460Y0988049
X0454861Y0988049
X0453011Y0991238
X0445609Y0991238
X0453011Y0984860
X0454861Y0975293
X0447460Y0975293
X0451160Y0975293
X0454861Y0981671
X0447460Y0981671
X0445609Y0984860
R02Y-0006378
X0454861Y0968915
X0447460Y0962537
X0451160Y0962537
X0454861Y0962537
X0445609Y0965726
X0445609Y0959348
X0454861Y0956159
X0454861Y0949781
X0451160Y0949781
X0454861Y0943403
X0447460Y0949781
X0445609Y0952970
X0445609Y0946592
X0454861Y0937025
X0451160Y0937025
X0447460Y0937025
X0454861Y0930647
X0448641Y1063135
X0452341Y1063135
X0446790Y1072702
X0446790Y1066324
X0448641Y1050379
X0454192Y1053568
X0448641Y1056757
X0454192Y1047190
X0446790Y1059946
R02Y-0006378
X0448641Y1101403
X0452341Y1101403
X0446790Y1104592
R02Y-0006378
X0448641Y1088647
X0452341Y1088647
X0448641Y1075891
X0452341Y1075891
X0446790Y1085458
X0446790Y1079080
X0448641Y1133293
X0452341Y1133293
X0452341Y1120537
X0448641Y1120537
X0446790Y1130103
X0446790Y1123726
X0448641Y1107781
X0452341Y1107781
X0446790Y1117348
X0446790Y1110970
X0454192Y1155615
X0446790Y1161993
X0446790Y1155615
X0450491Y1149237
X0454192Y1149237
X0446790Y1149237
R02Y-0006378
X0465964Y0905135
X0467814Y0908325
X0464113Y0901947
X0467814Y0901947
X0465964Y0898758
X0460412Y0901947
X0456712Y0901947
X0464113Y0889191
X0467814Y0895569
X0465964Y0892380
X0467814Y0882813
X0456712Y0895569
X0460412Y0889191
X0469664Y0879624
X0460412Y0876435
X0465964Y0956159
X0467814Y0952970
X0465964Y0949781
X0465964Y0943403
X0464113Y0946592
X0467814Y0946592
X0456712Y0952970
X0456712Y0946592
X0460412Y0946592
X0465964Y0937025
X0467814Y0940214
X0464113Y0933836
X0464113Y0927458
X0467814Y0933836
X0467814Y0927458
X0456712Y0940214
X0460412Y0933836
X0456712Y0933836
X0456712Y0927458
X0460412Y0927458
X0465964Y0924269
X0467814Y0921080
X0465964Y0917891
X0464113Y0914702
X0467814Y0914702
X0456712Y0921080
X0456712Y0914702
X0460412Y0914702
X0465964Y0911513
X0463444Y1050379
X0463444Y1056757
X0468995Y1059946
R02Y-0006378
X0456042Y1050379
X0457893Y1059946
X0456042Y1056757
X0461593Y1053568
X0461593Y1047190
X0461606Y1040820
X0469007Y1040820
X0460425Y0997608
X0467826Y0997608
X0467814Y0991238
X0469664Y0988049
X0462263Y0988049
X0460412Y0991238
X0467814Y0984860
X0464113Y0972104
X0465964Y0975293
X0467814Y0972104
X0467814Y0978482
X0469664Y0981671
X0460412Y0984860
X0460412Y0972104
X0462263Y0981671
X0456712Y0978482
X0456712Y0972104
X0465964Y0968915
X0464113Y0959348
X0465964Y0962537
X0467814Y0959348
X0467814Y0965726
X0456712Y0959348
X0460412Y0959348
X0456712Y0965726
X0465294Y1066324
X0467145Y1069513
X0468995Y1066324
X0468995Y1072702
X0467145Y1063135
X0461593Y1066324
X0457893Y1066324
X0457893Y1072702
X0456042Y1069513
X0456042Y1063135
X0467145Y1101403
X0468995Y1098214
X0465294Y1104592
X0468995Y1104592
X0465294Y1091836
X0468995Y1091836
X0467145Y1095025
X0461593Y1104592
X0457893Y1104592
X0456042Y1101403
X0457893Y1098214
X0456042Y1095025
X0461593Y1091836
X0457893Y1091836
X0467145Y1082269
X0467145Y1088647
X0468995Y1085458
X0465294Y1079080
X0468995Y1079080
X0467145Y1075891
X0456042Y1082269
X0457893Y1085458
X0456042Y1088647
X0457893Y1079080
X0461593Y1079080
X0456042Y1075891
X0467145Y1133293
X0468995Y1130103
X0467145Y1126915
X0465294Y1123726
X0467145Y1120537
X0468995Y1123726
X0456042Y1133293
X0456042Y1120537
X0457893Y1123726
X0461593Y1123726
X0456042Y1126915
X0468995Y1117348
X0467145Y1114159
X0467145Y1107781
X0465294Y1110970
X0468995Y1110970
X0456042Y1114159
X0457893Y1117348
X0461593Y1110970
X0457893Y1110970
X0456042Y1107781
X0465294Y1155615
X0459743Y1152426
X0459743Y1158804
X0465294Y1149237
X0467145Y1146048
X0465294Y1136481
X0468995Y1136481
X0467145Y1139670
X0468995Y1142859
X0461593Y1149237
X0456042Y1146048
X0457893Y1142859
X0457893Y1136481
X0461593Y1136481
X0456042Y1139670
X0482617Y0889191
X0482617Y0882813
X0471515Y0889191
X0475215Y0889191
X0477066Y0892380
X0478916Y0895569
X0471515Y0882813
X0475215Y0882813
X0478916Y0882813
X0482617Y0876435
X0480767Y0879624
X0480767Y0873246
X0471515Y0876435
X0482617Y0933836
X0482617Y0927458
X0478916Y0940214
X0477066Y0930647
X0471515Y0927458
X0475215Y0927458
X0478916Y0933836
X0478916Y0927458
X0482617Y0914702
X0477066Y0924269
X0478916Y0921080
X0471515Y0914702
X0475215Y0914702
X0477066Y0917891
X0478916Y0914702
X0482617Y0901947
X0477066Y0911513
X0477066Y0905135
X0478916Y0908325
X0477066Y0898758
X0475215Y0901947
X0471515Y0901947
X0478916Y0901947
X0480097Y1028056
X0482617Y1003994
X0482617Y1010372
X0484467Y1007183
X0477066Y1007183
X0484467Y1000805
X0482617Y0997616
X0482617Y0991238
X0484467Y0988049
X0484467Y0994427
X0477066Y1000805
X0477066Y0988049
X0475215Y0991238
X0477066Y0994427
X0482617Y0984860
X0482617Y0972104
X0484467Y0981671
X0475215Y0984860
X0471515Y0972104
X0475215Y0972104
X0477066Y0975293
X0477066Y0981671
X0478916Y0972104
X0478916Y0978482
X0482617Y0959348
X0477066Y0968915
X0477066Y0962537
X0471515Y0959348
X0475215Y0959348
X0478916Y0959348
X0478916Y0965726
X0482617Y0946592
X0477066Y0956159
X0478916Y0952970
X0477066Y0949781
X0471515Y0946592
X0475215Y0946592
X0477066Y0943403
X0478916Y0946592
X0480097Y1059946
X0483798Y1053568
X0483798Y1047190
X0478247Y1050379
X0470845Y1050379
X0478247Y1056757
X0470845Y1056757
X0476397Y1053568
X0476397Y1047190
X0476400Y1040820
X0481948Y1031245
X0483798Y1040812
X0480097Y1034434
X0478247Y1044001
X0478247Y1037623
X0480097Y1066324
X0480097Y1072702
X0483798Y1066324
X0478247Y1069513
X0476397Y1066324
X0472696Y1066324
X0478247Y1063135
X0483798Y1091836
X0480097Y1091836
X0476397Y1091836
X0472696Y1091836
X0478247Y1095025
X0480097Y1085458
X0480097Y1079080
X0483798Y1079080
X0478247Y1082269
X0478247Y1088647
X0472696Y1079080
X0476397Y1079080
X0478247Y1075891
X0480097Y1117348
X0480097Y1110970
X0483798Y1110970
X0478247Y1114159
X0478247Y1107781
X0476397Y1110970
X0472696Y1110970
X0480097Y1098214
X0483798Y1104592
X0480097Y1104592
X0480097Y1130103
X0480097Y1123726
X0483798Y1123726
X0478247Y1133293
R02Y-0006378
X0472696Y1123726
X0476397Y1123726
X0481948Y1158804
X0470845Y1158804
X0474546Y1152426
X0476397Y1155615
X0483798Y1149237
X0480097Y1142859
X0480097Y1136481
X0483798Y1136481
X0478247Y1146048
X0472696Y1149237
X0476397Y1149237
X0472696Y1136481
X0476397Y1136481
X0478247Y1139670
X0499271Y0892380
X0497420Y0889191
X0488168Y0892380
X0490019Y0895569
X0486318Y0889191
X0493719Y0889191
X0486318Y0882813
X0490019Y0882813
X0493719Y0882813
X0491869Y0879624
X0493719Y0876435
X0499271Y0930647
X0497420Y0933836
X0497420Y0927458
X0490019Y0940214
X0488168Y0930647
X0486318Y0933836
X0490019Y0933836
X0493719Y0933836
X0490019Y0927458
X0486318Y0927458
X0493719Y0927458
X0499271Y0924269
X0497420Y0914702
X0499271Y0917891
X0488168Y0924269
X0490019Y0921080
X0486318Y0914702
X0490019Y0914702
X0488168Y0917891
X0493719Y0914702
X0499271Y0911513
X0499271Y0905135
X0499271Y0898758
X0497420Y0901947
X0488168Y0911513
X0488168Y0905135
X0488168Y0898758
X0490019Y0901947
X0486318Y0901947
X0493719Y0901947
X0499271Y1007183
X0497420Y1003994
X0497420Y1010372
X0490019Y1003994
X0490019Y1010372
X0491869Y1007183
X0499271Y1000805
R02Y-0006378
X0497420Y0997616
X0497420Y0991238
X0491869Y1000805
X0490019Y0991238
X0490019Y0997616
X0491869Y0988049
X0491869Y0994427
X0497420Y0984860
X0499271Y0981671
X0499271Y0975293
X0497420Y0972104
X0490019Y0984860
X0486318Y0972104
X0490019Y0972104
X0488168Y0975293
X0493719Y0972104
X0490019Y0978482
X0491869Y0981671
X0499271Y0968915
X0497420Y0959348
X0499271Y0962537
X0488168Y0968915
X0488168Y0962537
X0486318Y0959348
X0490019Y0959348
X0493719Y0959348
X0490019Y0965726
X0499271Y0956159
R02Y-0006378
X0497420Y0946592
X0488168Y0956159
X0490019Y0952970
X0488168Y0949781
X0486318Y0946592
X0490019Y0946592
X0493719Y0946592
X0488168Y0943403
X0498601Y1053568
X0498601Y1047190
X0485649Y1050379
X0493050Y1050379
X0485649Y1056757
X0491200Y1053568
X0491200Y1059946
X0493050Y1056757
X0491200Y1047190
X0498601Y1040812
X0496751Y1031245
X0493050Y1044001
X0485649Y1037623
X0493050Y1037623
X0489349Y1031245
X0487499Y1034434
X0491200Y1040812
X0494901Y1034434
X0485649Y1044001
X0487499Y1028056
X0494901Y1028056
X0489349Y1088647
X0491200Y1085458
X0491200Y1079080
X0487499Y1079080
X0489349Y1075891
X0494901Y1079080
X0498601Y1066324
X0489349Y1069513
X0491200Y1072702
X0487499Y1066324
R02X0003701
X0489349Y1063135
X0487499Y1110970
X0489349Y1107781
X0494901Y1110970
X0496751Y1101403
X0498601Y1104592
X0498601Y1091836
X0487499Y1104592
X0491200Y1104592
X0491200Y1098214
X0494901Y1104592
X0489349Y1095025
X0491200Y1091836
X0487499Y1091836
X0494901Y1091836
X0498601Y1079080
X0489349Y1082269
X0498601Y1123726
X0489349Y1133293
X0491200Y1130103
X0489349Y1120537
X0487499Y1123726
X0491200Y1123726
X0489349Y1126915
X0494901Y1123726
X0498601Y1110970
X0491200Y1117348
X0489349Y1114159
X0491200Y1110970
X0496751Y1152426
X0498601Y1155615
X0493050Y1158804
X0485649Y1152426
X0487499Y1155615
X0498601Y1149237
X0498601Y1136481
X0487499Y1149237
X0489349Y1146048
X0494901Y1149237
X0491200Y1142859
X0487499Y1136481
X0491200Y1136481
X0489349Y1139670
X0494901Y1136481
X0501133Y0872118
X0502971Y0879624
X0514074Y0892380
X0512223Y0889191
X0514074Y0886002
X0512223Y0882813
X0501121Y0895569
X0506672Y0892380
X0504822Y0882813
X0502971Y0886002
X0506672Y0886002
X0508523Y0882813
X0512223Y0921080
X0514074Y0917891
X0506672Y0924269
X0501121Y0921080
X0506672Y0917891
X0512223Y0908325
X0514074Y0911513
X0514074Y0898758
X0512223Y0901947
X0501121Y0908325
X0506672Y0911513
X0506672Y0905135
X0506672Y0898758
X0514074Y0937025
X0512223Y0940214
X0514074Y0930647
X0512223Y0927458
X0501121Y0940214
X0506672Y0937025
X0501121Y0933836
X0506672Y0930647
X0514074Y0956159
X0512223Y0946592
X0514074Y0949781
X0506672Y0956159
X0501121Y0952970
X0506672Y0949781
X0506672Y0943403
X0512223Y0984860
X0512223Y0978482
X0514074Y0975293
X0508523Y0984860
X0501121Y0978482
X0506672Y0981671
X0506672Y0975293
X0510373Y0981671
X0514074Y0968915
X0512223Y0965726
X0512223Y0959348
X0506672Y0968915
X0501121Y0965726
X0506672Y0962537
X0512223Y1003994
X0514074Y1007183
X0506672Y1007183
X0512223Y0997616
X0514074Y0994427
X0514074Y0988049
X0506672Y1000805
R02Y-0006378
X0513405Y1040812
X0513405Y1034434
X0507853Y1031245
X0500452Y1044001
X0507853Y1044001
X0502302Y1034434
X0500452Y1037623
X0507853Y1037623
X0513405Y1028056
X0502302Y1028056
X0513405Y1072702
X0502302Y1072702
X0500452Y1069513
X0507853Y1069513
X0500452Y1063135
X0507853Y1063135
X0513405Y1059946
X0513405Y1053568
X0506003Y1059946
X0502302Y1059946
X0500452Y1050379
X0504153Y1056757
X0500452Y1056757
X0507853Y1050379
X0507853Y1056757
X0513405Y1079080
X0500452Y1082269
X0507853Y1082269
X0502302Y1085458
X0500452Y1088647
X0507853Y1088647
X0500452Y1075891
X0507853Y1075891
X0513405Y1098214
X0513405Y1091836
X0502302Y1104592
X0507853Y1101403
X0502302Y1098214
X0500452Y1095025
X0507853Y1095025
X0502302Y1130103
X0500452Y1133293
X0507853Y1133293
X0500452Y1126915
X0507853Y1126915
X0500452Y1120537
X0507853Y1120537
X0513405Y1117348
X0513405Y1110970
X0500452Y1114159
X0502302Y1117348
X0507853Y1114159
X0500452Y1107781
X0507853Y1107781
X0513405Y1149237
X0513405Y1136481
X0500452Y1146048
X0507853Y1146048
X0502302Y1142859
X0500452Y1139670
X0507853Y1139670
X0513405Y1155615
X0504153Y1158804
X0507853Y1158804
X0502302Y1155615
X0507853Y1152426
X0509704Y1155615
X0511554Y1165182
X0528877Y0886002
X0519625Y0895569
X0519625Y0889191
X0525176Y0892380
X0527027Y0889191
X0527027Y0895569
X0519625Y0882813
X0517775Y0886002
X0523326Y0882813
X0525176Y0886002
X0525176Y0873246
X0515924Y0876435
X0525176Y0879624
X0519625Y0908325
X0525176Y0911513
X0525176Y0905135
X0519625Y0901947
X0525176Y0898758
X0527027Y0901947
X0519625Y0940214
X0527027Y0940214
X0519625Y0933836
X0519625Y0927458
X0525176Y0930647
X0527027Y0933836
X0527027Y0927458
X0519625Y0921080
X0525176Y0924269
X0527027Y0921080
X0527027Y0914702
X0519625Y0914702
X0525176Y0917891
X0519625Y0952970
X0525176Y0956159
X0527027Y0952970
X0525176Y0949781
X0525176Y0943403
X0519625Y0946592
X0527027Y0946592
X0525176Y0937025
X0519625Y0972104
X0525176Y0981671
X0525176Y0975293
X0527027Y0978482
X0527027Y0972104
X0525176Y0968915
X0519625Y0965726
X0519625Y0959348
X0525176Y0962537
X0527027Y0965726
X0527027Y0959348
X0525176Y1000805
X0519625Y0997616
X0519625Y0991238
X0525176Y0994427
X0525176Y0988049
X0527027Y0997616
X0527027Y0991238
X0519625Y0984860
R02X0003701
X0519625Y0978482
X0521475Y0981671
X0528208Y1034434
X0528208Y1040812
X0515255Y1044001
X0520806Y1034434
X0520806Y1040812
X0515255Y1031245
X0526357Y1031245
X0526357Y1044001
X0526357Y1037623
X0528208Y1028056
X0520806Y1028056
X0519625Y1003994
X0519625Y1010372
X0525176Y1007183
X0527027Y1003994
X0527027Y1010372
X0528208Y1072702
X0528208Y1066324
X0515255Y1069513
X0520806Y1072702
X0520806Y1066324
X0526357Y1069513
X0515255Y1063135
X0526357Y1063135
X0528208Y1059946
R02Y-0006378
X0517105Y1059946
X0520806Y1059946
X0518956Y1056757
X0515255Y1050379
X0520806Y1053568
X0526357Y1056757
X0526357Y1050379
X0520806Y1047190
X0528208Y1085458
X0528208Y1079080
X0515255Y1082269
X0515255Y1088647
X0520806Y1085458
X0526357Y1082269
X0526357Y1088647
X0520806Y1079080
X0526357Y1075891
X0528208Y1117348
X0528208Y1110970
X0520806Y1117348
X0526357Y1114159
X0515255Y1107781
X0520806Y1110970
X0526357Y1107781
X0528208Y1098214
X0528208Y1104592
X0528208Y1091836
X0515255Y1101403
X0520806Y1098214
X0520806Y1104592
X0526357Y1101403
X0520806Y1091836
X0526357Y1095025
X0528208Y1123726
X0520806Y1130103
X0526357Y1133293
X0515255Y1126915
X0515255Y1120537
X0520806Y1123726
X0526357Y1126915
X0526357Y1120537
X0522670Y1165290
R02X-0003701
X0526370Y1165290
X0528208Y1155615
X0517105Y1161993
X0515255Y1158804
X0522657Y1158804
X0517105Y1155615
X0520806Y1155615
X0526357Y1158804
X0526357Y1152426
X0528208Y1149237
R02Y-0006378
X0515255Y1146048
X0520806Y1149237
X0526357Y1146048
X0520806Y1136481
X0526357Y1139670
X0520806Y1142859
X0515255Y1139670
X0534428Y0882813
X0532578Y0886002
X0538129Y0882813
X0543680Y0879624
X0541830Y0876435
X0532578Y0879624
X0539979Y0879624
X0534428Y0876435
X0532578Y0924269
X0538129Y0921080
X0532578Y0917891
X0539979Y0917891
X0532578Y0911513
X0532578Y0905135
X0538129Y0908325
X0539979Y0911513
X0532578Y0898758
X0539979Y0898758
X0538129Y0901947
X0543680Y0886002
X0532578Y0892380
X0539979Y0892380
X0538129Y0889191
X0532578Y0956159
X0539979Y0956159
X0532578Y0949781
X0532578Y0943403
X0538129Y0946592
X0539979Y0949781
X0532578Y0937025
X0538129Y0940214
X0539979Y0937025
X0532578Y0930647
X0539979Y0930647
X0538129Y0927458
X0534428Y0984860
X0538129Y0984860
X0532578Y0981671
X0536279Y0981671
X0538129Y0978482
X0532578Y0975293
X0539979Y0975293
X0532578Y0968915
X0539979Y0968915
X0532578Y0962537
X0538129Y0965726
X0538129Y0959348
X0539310Y1028056
X0532578Y1007183
X0538129Y1003994
X0539978Y1007184
X0532578Y1000805
X0538129Y0997616
X0539979Y0994427
X0532578Y0988049
X0539979Y0988049
X0532578Y0994427
X0533759Y1069513
X0539310Y1072702
X0541160Y1069513
X0533759Y1063135
X0541160Y1063135
X0531908Y1059946
X0539310Y1059946
X0533759Y1056757
X0533759Y1050379
X0539310Y1053568
X0541160Y1050379
X0530058Y1056757
X0543011Y1059946
X0533759Y1044001
X0541160Y1044001
X0533759Y1037623
X0539310Y1040812
X0539310Y1034434
X0533759Y1031245
X0541160Y1031245
X0533759Y1101403
X0541160Y1101403
X0539310Y1098214
X0533759Y1095025
X0539310Y1091836
X0533759Y1082269
X0541160Y1082269
X0533759Y1088647
X0541160Y1088647
X0539310Y1079080
X0533759Y1075891
X0533759Y1133293
X0539310Y1130103
X0533759Y1126915
X0541160Y1126915
X0533759Y1120537
X0541160Y1120537
X0533759Y1114159
X0539310Y1117348
X0539310Y1110970
X0533759Y1107781
X0541160Y1107781
X0530071Y1165290
X0533772Y1165290
X0543011Y1161993
X0533759Y1152426
X0535609Y1155615
X0539310Y1155615
X0530058Y1158804
X0533759Y1158804
X0543011Y1155615
X0539310Y1149237
X0541160Y1146048
X0533759Y1146048
X0533759Y1139670
X0539310Y1136481
X0541160Y1139670
X0551082Y0886002
X0545531Y0882813
X0558483Y0886002
X0545543Y0872085
X0551082Y0879624
X0556633Y0876435
X0552932Y0876435
X0545531Y0876435
X0552932Y0908325
X0551082Y0911513
X0551082Y0905135
X0558483Y0911513
X0558483Y0905135
X0551082Y0898758
X0552932Y0901947
X0545531Y0901947
X0558483Y0898758
X0552932Y0895569
X0551082Y0892380
X0552932Y0889191
X0545531Y0895569
X0545531Y0889191
X0558483Y0892380
X0549231Y0882813
X0554783Y0886002
X0552932Y0940214
X0551082Y0937025
X0545531Y0940214
X0558483Y0937025
X0551082Y0930647
X0552932Y0933836
X0552932Y0927458
X0545531Y0933836
X0545531Y0927458
X0558483Y0930647
X0545531Y0921080
X0552932Y0921080
X0551082Y0924269
X0558483Y0924269
X0545531Y0914702
X0552932Y0914702
X0551082Y0917891
X0558483Y0917891
X0551082Y0968915
X0558483Y0968915
X0552932Y0965726
X0551082Y0962537
X0552932Y0959348
X0545531Y0965726
X0545531Y0959348
X0558483Y0962537
X0551082Y0956159
X0552932Y0952970
X0545531Y0952970
X0558483Y0956159
X0552932Y0946592
X0551082Y0949781
X0551082Y0943403
X0545531Y0946592
X0558483Y0949781
X0558483Y0943403
X0551082Y1000805
X0558483Y1000805
X0551082Y0988049
X0545531Y0997616
X0545531Y0991238
X0552932Y0997616
X0551082Y0994427
X0552932Y0991238
X0558483Y0994427
X0558483Y0988049
X0545531Y0984860
X0549231Y0984860
X0552932Y0984860
X0552932Y0978482
X0551082Y0981671
X0552932Y0972104
X0551082Y0975293
X0547381Y0981671
X0545531Y0978482
X0545531Y0972104
X0558483Y0981671
X0558483Y0975293
X0559664Y1044001
R02Y-0006378
X0552263Y1044001
X0554113Y1034434
X0552263Y1037623
X0554113Y1040812
X0552263Y1031245
X0546712Y1034434
X0546712Y1040812
X0546712Y1028056
X0554113Y1028056
X0552932Y1003994
X0551082Y1007183
X0552932Y1010372
X0545531Y1003994
X0545531Y1010372
X0558483Y1007183
X0559664Y1069513
X0559664Y1063135
X0554113Y1072702
X0554113Y1066324
X0552263Y1069513
X0546712Y1066324
X0546712Y1072702
X0552263Y1063135
X0559664Y1056757
X0559664Y1050379
X0557814Y1059946
X0554113Y1059946
X0552263Y1050379
X0554113Y1053568
X0555964Y1056757
X0552263Y1056757
X0546712Y1059946
X0546712Y1053568
X0544861Y1056757
X0554113Y1047190
X0546712Y1047190
X0559664Y1082269
X0559664Y1088647
X0559664Y1075891
X0552263Y1082269
X0554113Y1085458
X0552263Y1088647
X0546712Y1085458
X0554113Y1079080
X0546712Y1079080
X0552263Y1075891
X0559664Y1114159
X0559664Y1107781
X0546712Y1117348
X0552263Y1114159
X0554113Y1117348
X0546712Y1110970
X0554113Y1110970
X0552263Y1107781
X0559664Y1101403
X0559664Y1095025
X0554113Y1104592
X0546712Y1098214
X0546712Y1104592
X0554113Y1098214
X0552263Y1101403
X0552263Y1095025
X0554113Y1091836
X0546712Y1091836
X0559664Y1133293
R02Y-0006378
X0554113Y1130103
X0552263Y1133293
R02Y-0006378
X0554113Y1123726
X0546712Y1123726
X0559664Y1158804
X0559664Y1152426
X0554113Y1161993
X0546712Y1155615
X0548562Y1158804
R02X0003701
X0552263Y1152426
X0554113Y1155615
X0555964Y1165182
X0559664Y1146048
X0559664Y1139670
X0554113Y1149237
X0552263Y1146048
X0546712Y1149237
X0546712Y1142859
X0554113Y1142859
X0546712Y1136481
X0554113Y1136481
X0552263Y1139670
X0565885Y0911513
X0571436Y0908325
X0564034Y0908325
X0565885Y0898758
X0571436Y0901947
X0564034Y0901947
X0571436Y0895569
X0565885Y0892380
X0564034Y0889191
X0571436Y0889191
X0571436Y0882813
X0569586Y0886002
X0564034Y0882813
X0560334Y0882813
X0569586Y0873246
X0562184Y0879624
X0565885Y0956159
X0571436Y0952970
X0571436Y0946592
X0564034Y0946592
X0565885Y0949781
X0571436Y0940214
X0564034Y0940214
X0565885Y0937025
X0571436Y0933836
X0565885Y0930647
X0571436Y0927458
X0564034Y0927458
X0571436Y0921080
X0564034Y0921080
X0571436Y0914702
X0565885Y0917891
X0565885Y0988049
X0571436Y0984860
X0564034Y0984860
X0560334Y0984860
X0567735Y0984860
X0571436Y0978482
X0564034Y0978482
X0571436Y0972104
X0565885Y0975293
X0562184Y0981671
X0565885Y0968915
X0571436Y0965726
X0564034Y0965726
X0571436Y0959348
X0564034Y0959348
X0568916Y1059946
X0572617Y1059946
X0565215Y1053568
X0570767Y1056757
X0572617Y1053568
X0567066Y1050379
X0572617Y1047190
X0567066Y1044001
X0572617Y1040812
X0572617Y1034434
X0565215Y1040812
X0565215Y1034434
X0567066Y1031245
X0572617Y1028056
X0565216Y1028056
X0571436Y1003994
X0564034Y1003994
X0565885Y1007183
X0571436Y1010372
X0571436Y0997616
X0564034Y0997616
X0565885Y0994427
X0571436Y0991238
X0569586Y0988049
X0565215Y1098214
X0567066Y1101403
X0572617Y1098214
X0572617Y1104592
X0565215Y1091836
X0572617Y1091836
X0567066Y1082269
X0572617Y1085458
X0567066Y1088647
X0572617Y1079080
X0565215Y1079080
X0565215Y1072702
X0567066Y1069513
X0572617Y1072702
X0572617Y1066324
X0567066Y1063135
X0565215Y1059946
X0565215Y1136481
X0567066Y1139670
X0572617Y1142859
X0565215Y1130103
X0572617Y1130103
X0567066Y1126915
X0567066Y1120537
X0572617Y1123726
X0565215Y1117348
X0572617Y1117348
X0565215Y1110970
X0572617Y1110970
X0567066Y1107781
X0565215Y1161993
X0561515Y1155615
X0572617Y1155615
X0568916Y1155615
X0565215Y1155615
X0574467Y1158804
X0567066Y1146048
X0572617Y1149237
X0565215Y1149237
X0572617Y1136481
X0578168Y1158804
X0578909Y1151379
R02Y-0006378
X0578909Y1132246
R06Y-0006378
X0578909Y1081222
X0578909Y1087600
X0578909Y1068466
X0578909Y1074844
X0578909Y1062088
R05Y-0006378
X0577728Y1001852
X0577728Y1008230
X0577728Y0995474
R14Y-0006378
X0576987Y0898758
R02Y-0006378
X0575137Y0882813
X0576987Y0879624
X1278555Y0944449
X1284847Y0940213
X1278555Y0938071
X1278555Y0931693
X1284847Y0933835
X1284847Y0927457
X1278555Y0925315
X1284847Y0921079
X1278555Y0918937
X1284847Y0914701
X1278555Y0912559
X1278555Y0906181
X1284847Y0908324
X1279296Y0898757
X1284847Y0901946
X1279296Y0892379
X1284847Y0889190
X1279296Y0886001
X1281146Y0882812
X1286697Y0886001
X1284847Y0882812
X1284847Y0895568
X1279296Y0879623
X1286697Y0879623
X1286697Y0873245
X1286028Y1149236
X1279736Y1145000
X1286028Y1142858
X1286028Y1136480
X1279736Y1138622
X1279736Y1132245
X1286028Y1130102
X1286028Y1123725
X1279736Y1125867
X1286028Y1117347
X1279736Y1119489
X1279736Y1113111
X1286028Y1110969
X1279736Y1106733
X1286028Y1104591
X1286028Y1098213
X1279736Y1100355
X1286028Y1091835
X1279736Y1093977
X1286028Y1085457
X1279736Y1087599
X1279736Y1081221
X1286028Y1079079
R02Y-0006378
X1279736Y1074843
R02Y-0006378
X1279736Y1049331
X1279736Y1055709
X1286028Y1059945
X1289729Y1059945
X1287878Y1056756
X1286028Y1053567
X1286028Y1047189
X1279736Y1036575
X1279736Y1042953
X1286028Y1040811
R02Y-0006378
X1279736Y1030197
X1278555Y1001851
X1278555Y1008229
X1284847Y1003993
X1284847Y1010371
X1284847Y0997615
X1278555Y0989095
X1286697Y0988048
X1284847Y0991237
X1278555Y0995473
X1288548Y0984859
X1284847Y0984859
X1278555Y0982717
X1284847Y0978481
X1278555Y0976339
X1284847Y0972103
X1278555Y0969961
X1278555Y0963583
X1284847Y0965725
X1278555Y0957205
X1284847Y0959347
X1284847Y0952969
X1278555Y0950827
X1284847Y0946591
X1287878Y1165181
X1284178Y1158803
X1286028Y1155614
X1289729Y1155614
X1279736Y1157756
X1279736Y1151378
X1295949Y0876434
X1294099Y0879623
X1303351Y0876434
X1301500Y0879623
X1290398Y0873245
X1303351Y0908324
X1297800Y0911512
X1297800Y0905134
X1292249Y0908324
X1303351Y0901946
X1297800Y0898757
X1292249Y0901946
X1290398Y0911512
X1290398Y0898757
X1297800Y0892379
X1303351Y0889190
X1292249Y0889190
X1295949Y0882812
X1301500Y0886001
X1297800Y0886001
X1292249Y0882812
X1290398Y0892379
X1290398Y0886001
X1303351Y0895568
X1290398Y0937024
X1290398Y0930646
X1292249Y0921079
X1297800Y0924268
X1303351Y0921079
X1303351Y0914701
X1297800Y0917890
X1290398Y0917890
X1297800Y0956158
X1303351Y0952969
X1297800Y0943402
X1292249Y0946591
X1303351Y0946591
X1297800Y0949780
X1290398Y0956158
X1290398Y0949780
X1292249Y0940213
X1297800Y0937024
X1303351Y0940213
X1292249Y0927457
X1303351Y0933835
X1303351Y0927457
X1297800Y0930646
X1292249Y0984859
X1295949Y0984859
X1303351Y0984859
X1292249Y0978481
X1294099Y0981670
X1303351Y0978481
X1303351Y0972103
X1297800Y0975292
X1297800Y0981670
X1290398Y0975292
X1297800Y0968914
X1292249Y0965725
X1292249Y0959347
X1303351Y0965725
X1303351Y0959347
X1297800Y0962536
X1290398Y0968914
X1304532Y1028055
X1292249Y1003993
X1303351Y1003993
X1303351Y1010371
X1297800Y1007182
X1292249Y1010371
X1290398Y1007182
X1297800Y1000804
X1292249Y0997615
X1303351Y0997615
X1303351Y0991237
X1297800Y0988048
X1297800Y0994426
X1290398Y0994426
X1290398Y0988048
X1304532Y1059945
X1300831Y1059945
X1298981Y1056756
X1302681Y1056756
X1298981Y1050378
X1304532Y1053567
X1293430Y1059945
X1293430Y1053567
X1291579Y1050378
X1304532Y1047189
X1291579Y1044000
X1291579Y1031244
X1298981Y1031244
X1304532Y1040811
X1304532Y1034433
X1298981Y1037622
X1298981Y1044000
X1293430Y1040811
X1293430Y1034433
X1291579Y1088646
X1298981Y1082268
X1291579Y1082268
X1298981Y1088646
X1304532Y1085457
X1304532Y1079079
X1293430Y1079079
X1298981Y1075890
X1298981Y1069512
X1304532Y1066323
X1304532Y1072701
X1293430Y1072701
X1291579Y1069512
X1291579Y1063134
X1298981Y1063134
X1304532Y1117347
X1298981Y1114158
X1293430Y1117347
X1304532Y1110969
X1293430Y1110969
X1291579Y1107780
X1298981Y1107780
X1291579Y1101402
X1304532Y1104591
X1304532Y1098213
X1298981Y1101402
X1293430Y1098213
X1298981Y1095024
X1304532Y1091835
X1293430Y1091835
X1293430Y1130102
X1298981Y1133292
X1304532Y1130102
X1298981Y1126914
X1291579Y1126914
X1304532Y1123725
X1298981Y1120536
X1291579Y1120536
X1330439Y1130102
X1297130Y1161992
X1304532Y1161992
X1298981Y1158803
X1302681Y1158803
X1297130Y1155614
X1298981Y1152425
X1304532Y1155614
X1293430Y1155614
X1304532Y1149236
X1298981Y1146047
X1293430Y1149236
X1291579Y1146047
X1304532Y1142858
X1293430Y1136480
X1291579Y1139669
X1298981Y1139669
X1304532Y1136480
X1316304Y0892379
X1318154Y0889190
X1310752Y0889190
X1318154Y0882812
X1316304Y0886001
X1312603Y0886001
X1310752Y0882812
X1305201Y0892379
X1305201Y0886001
X1307052Y0882812
X1310752Y0895568
X1308902Y0879623
X1308902Y0873245
X1314453Y0876434
X1310752Y0921079
X1318154Y0921079
X1316304Y0917890
X1310752Y0914701
X1305201Y0924268
X1305201Y0917890
X1318154Y0908324
X1316304Y0911512
X1316304Y0898757
X1318154Y0901946
X1310752Y0901946
X1305201Y0911512
X1305201Y0905134
X1305201Y0898757
X1310752Y0965725
X1310752Y0959347
X1305201Y0968914
X1305201Y0962536
X1316304Y0956158
X1310752Y0952969
X1318154Y0946591
X1316304Y0949780
X1310752Y0946591
X1305201Y0956158
R02Y-0006378
X1318154Y0940213
X1310752Y0940213
X1316304Y0937024
X1316304Y0930646
X1318154Y0927457
X1310752Y0933835
X1310752Y0927457
X1305201Y0937024
X1305201Y0930646
X1316304Y0994426
X1318154Y0997615
X1316304Y0988048
X1310752Y0997615
X1310752Y0991237
X1305201Y1000804
R02Y-0006378
X1318154Y0984859
X1310752Y0984859
X1308902Y0981670
X1318154Y0978481
X1316304Y0975292
X1310752Y0978481
X1310752Y0972103
X1307052Y0984859
X1305201Y0981670
X1305201Y0975292
X1316304Y0968914
X1318154Y0965725
X1318154Y0959347
X1311933Y1053567
X1319335Y1053567
X1317485Y1050378
X1319335Y1059945
R02X-0003701
X1313784Y1056756
X1311933Y1047189
X1306382Y1056756
X1306382Y1050378
X1311933Y1034433
X1317485Y1044000
X1317485Y1031244
X1319335Y1040811
X1311933Y1040811
X1319335Y1034433
X1306382Y1031244
R02Y0006378
X1311933Y1028055
X1318154Y1003993
X1316304Y1007182
X1318154Y1010371
X1310752Y1010371
X1310752Y1003993
X1305201Y1007182
X1317485Y1082268
X1317485Y1088646
X1311933Y1085457
X1311933Y1079079
X1319335Y1079079
X1306382Y1082268
X1306382Y1088646
X1306382Y1075890
X1311933Y1072701
X1311933Y1066323
X1317485Y1069512
X1319335Y1072701
X1317485Y1063134
X1306382Y1069512
X1306382Y1063134
X1319335Y1117347
X1311933Y1117347
X1311933Y1110969
X1319335Y1110969
X1317485Y1107780
X1306382Y1114158
X1306382Y1107780
X1311933Y1104591
X1317485Y1101402
X1319335Y1098213
X1311933Y1098213
X1311933Y1091835
X1319335Y1091835
X1306382Y1101402
X1306382Y1095024
X1310083Y1158803
X1311933Y1155614
R02X0003701
X1306382Y1158803
X1306382Y1152425
X1311933Y1149236
X1319335Y1149236
X1317485Y1146047
X1311933Y1142858
X1311933Y1136480
X1317485Y1139669
X1319335Y1136480
X1306382Y1146047
X1306382Y1139669
X1319335Y1130102
X1317485Y1126914
X1311933Y1123725
X1317485Y1120536
X1306382Y1133292
R02Y-0006378
X1313784Y1165181
X1306382Y1165181
X1311933Y1161992
X1319335Y1161992
X1313784Y1158803
X1317485Y1158803
X1331107Y0879623
X1325556Y0876434
X1331107Y0873245
X1320004Y0879623
X1331107Y0905134
X1323705Y0905134
X1323705Y0911512
X1331107Y0911512
X1329256Y0901946
X1331107Y0898757
X1323705Y0898757
X1329256Y0895568
X1331107Y0892379
X1329256Y0889190
X1323705Y0892379
X1327406Y0886001
X1331107Y0886001
X1332957Y0882812
X1329256Y0882812
X1323705Y0886001
X1321855Y0882812
X1331107Y0924268
X1329256Y0921079
X1323705Y0924268
X1331107Y0917890
X1323705Y0917890
X1329256Y0914701
X1323705Y0956158
X1331107Y0956158
X1329256Y0952969
X1323705Y0949780
X1323705Y0943402
X1331107Y0949780
X1329256Y0946591
X1331107Y0943402
X1323705Y0937024
X1329256Y0940213
X1331107Y0937024
X1329256Y0927457
X1323705Y0930646
X1329256Y0933835
X1331107Y0930646
X1332957Y0984859
X1329256Y0984859
X1334807Y0981670
X1331107Y0981670
X1329256Y0978481
X1331107Y0975292
X1329256Y0972103
X1323705Y0981670
X1323705Y0975292
X1321855Y0984859
X1320004Y0981670
X1323705Y0968914
X1331107Y0968914
X1323705Y0962536
X1329256Y0965725
X1331107Y0962536
X1329256Y0959347
X1330437Y1028055
X1329256Y1010371
X1331107Y1007182
X1329256Y1003993
X1323705Y1007182
X1331107Y1000804
X1331107Y0994426
X1329256Y0991237
X1331107Y0988048
X1329256Y0997615
X1323705Y0994426
X1323705Y0988048
X1323705Y1000804
X1330437Y1059945
X1326737Y1059945
X1332288Y1056756
X1328587Y1056756
X1330437Y1053567
X1332288Y1050378
X1324886Y1056756
X1324886Y1050378
X1330437Y1047189
X1330437Y1040811
X1332288Y1037622
X1330437Y1034433
X1332288Y1044000
X1324886Y1037622
X1324886Y1044000
X1332288Y1031244
X1324886Y1031244
X1332288Y1082268
X1324886Y1082268
X1332288Y1088646
X1330437Y1085457
X1324886Y1088646
X1330437Y1079079
X1332288Y1075890
X1324886Y1075890
X1330437Y1072701
X1332288Y1069512
X1330437Y1066323
X1324886Y1069512
X1324886Y1063134
X1332288Y1063134
X1330437Y1117347
X1332288Y1114158
X1324886Y1114158
X1330437Y1110969
X1332288Y1107780
X1324886Y1107780
X1330437Y1104591
X1332288Y1101402
X1330437Y1098213
X1324886Y1101402
X1332288Y1095024
X1324886Y1095024
X1330437Y1091835
X1324886Y1165181
X1330437Y1161992
X1324886Y1158803
R02X0003701
X1324886Y1152425
X1330437Y1155614
X1332288Y1152425
X1323036Y1161992
X1323036Y1155614
X1324886Y1146047
X1330437Y1149236
X1332288Y1146047
X1330437Y1142858
X1332288Y1139669
X1330437Y1136480
X1324886Y1139669
X1332288Y1133292
X1324886Y1133292
X1332288Y1126914
X1324886Y1126914
X1330437Y1123725
X1332288Y1120536
X1324886Y1120536
X1332288Y1165181
X1349611Y0879623
X1345910Y0879623
X1336658Y0876434
X1349611Y0911512
X1342209Y0911512
X1349611Y0905134
X1344059Y0901946
X1349611Y0898757
X1342209Y0898757
X1336658Y0908324
X1336658Y0901946
X1349611Y0892379
X1342209Y0892379
X1344059Y0889190
X1344059Y0882812
X1349611Y0886001
X1342209Y0886001
X1336658Y0895568
R02Y-0006378
X1338508Y0886001
X1349611Y0924268
X1344059Y0921079
X1349611Y0917890
X1342209Y0917890
X1336658Y0921079
X1336658Y0914701
X1336658Y0952969
X1336658Y0946591
X1349611Y0937024
X1342209Y0937024
X1344059Y0940213
X1349611Y0930646
X1342209Y0930646
X1344059Y0927457
X1336658Y0940213
X1336658Y0927457
X1336658Y0933835
X1342209Y0968914
X1349611Y0968914
X1344059Y0965725
X1349611Y0962536
X1344059Y0959347
X1336658Y0959347
X1336658Y0965725
X1342209Y0956158
X1349611Y0956158
X1342209Y0949780
X1349611Y0949780
X1344059Y0946591
X1349611Y0943402
X1349611Y1000804
X1342209Y0988048
X1344059Y0997615
X1342209Y0994426
X1349611Y0994426
X1349611Y0988048
X1336658Y0991237
X1336658Y0997615
X1347760Y0984859
X1344059Y0984859
X1345910Y0981670
X1349611Y0981670
X1344059Y0978481
X1342209Y0975292
X1349611Y0975292
X1336658Y0984859
R02Y-0006378
X1337839Y1028055
X1349611Y1007182
X1342209Y1007182
X1344059Y1003993
X1336658Y1003993
X1344059Y1010371
X1336658Y1010371
X1345241Y1059945
X1341540Y1059945
X1345241Y1053567
X1343390Y1050378
X1339689Y1056756
X1337839Y1059945
R02Y-0006378
X1345241Y1034433
X1345241Y1040811
X1343390Y1044000
X1343390Y1031244
X1337839Y1034433
X1337839Y1040811
X1345241Y1072701
X1343390Y1069512
X1343390Y1063134
X1337839Y1066323
X1337839Y1072701
X1343390Y1082268
X1343390Y1088646
X1345241Y1079079
X1337839Y1085457
X1337839Y1079079
X1345241Y1117347
X1345241Y1110969
X1343390Y1107780
X1337839Y1117347
X1337839Y1110969
X1345241Y1098213
X1343390Y1101402
X1345241Y1091835
X1337839Y1104591
R02Y-0006378
X1345241Y1130102
X1343390Y1126914
X1343390Y1120536
X1337839Y1130102
X1337839Y1123725
X1339689Y1165181
X1345241Y1155614
X1348941Y1155614
X1339689Y1158803
X1341540Y1155614
X1337839Y1161992
X1335989Y1158803
X1337839Y1155614
X1343390Y1146047
X1345241Y1149236
X1345241Y1136480
X1343390Y1139669
X1337839Y1149236
R02Y-0006378
X1358863Y0889190
X1362563Y0889190
X1355162Y0895568
X1357012Y0892379
X1355162Y0882812
X1360713Y0886001
X1364414Y0886001
X1358863Y0882812
X1362563Y0882812
X1353311Y0886001
X1362563Y0876434
X1360713Y0873245
X1364414Y0879623
X1353311Y0879623
X1351461Y0876434
X1355162Y0908324
X1357012Y0911512
X1357012Y0905134
X1358863Y0901946
X1362563Y0901946
X1357012Y0898757
X1355162Y0940213
X1357012Y0930646
X1358863Y0927457
X1362563Y0927457
X1355162Y0933835
X1358863Y0933835
X1362563Y0933835
X1357012Y0924268
X1355162Y0921079
X1357012Y0917890
X1362563Y0914701
X1358863Y0914701
X1357012Y0968914
X1355162Y0965725
X1357012Y0962536
X1362563Y0959347
X1358863Y0959347
X1355162Y0952969
X1357012Y0956158
X1357012Y0949780
X1362563Y0946591
X1358863Y0946591
X1357012Y0943402
X1360713Y1000804
X1360713Y0988048
X1360713Y0994426
X1362563Y0997615
X1362563Y0991237
X1355162Y0997615
R02Y-0006378
X1362563Y0984859
X1355162Y0978481
X1360713Y0981670
X1357012Y0975292
X1362563Y0972103
X1358863Y0972103
X1363745Y1053567
X1356343Y1059945
X1361894Y1050378
X1356343Y1053567
X1363745Y1047189
X1356343Y1047189
X1352642Y1059945
X1350792Y1050378
X1350792Y1056756
X1354493Y1056756
X1361894Y1031244
R02Y0006378
X1363745Y1040811
X1363745Y1034433
X1356343Y1040811
X1356343Y1034433
X1350792Y1037622
X1350792Y1044000
X1350792Y1031244
X1363745Y1028055
X1356343Y1028055
X1355162Y1003993
X1362563Y1003993
X1360713Y1007182
X1358863Y1010371
X1360044Y1066323
X1358193Y1069512
X1363745Y1066323
X1356343Y1072701
X1358193Y1063134
X1350792Y1069512
X1350792Y1063134
X1358193Y1082268
X1358193Y1088646
X1356343Y1085457
X1360044Y1079079
X1363745Y1079079
X1358193Y1075890
X1350792Y1088646
R02Y-0006378
X1360044Y1104591
X1363745Y1104591
X1356343Y1098213
X1358193Y1095024
X1360044Y1091835
X1363745Y1091835
X1356343Y1104591
X1350792Y1101402
X1350792Y1095024
X1358193Y1114158
X1356343Y1117347
X1363745Y1110969
X1360044Y1110969
X1358193Y1107780
X1350792Y1114158
X1350792Y1107780
X1358193Y1146047
X1360044Y1149236
X1363745Y1149236
X1356343Y1142858
X1360044Y1136480
X1363745Y1136480
X1358193Y1139669
X1350792Y1146047
X1350792Y1139669
X1358193Y1133292
X1356343Y1130102
X1358193Y1120536
X1360044Y1123725
X1363745Y1123725
X1358193Y1126914
X1350792Y1133292
R02Y-0006378
X1363745Y1161992
X1360044Y1155614
X1363745Y1155614
X1356343Y1155614
X1352642Y1161992
X1350792Y1158803
X1350792Y1152425
X1354493Y1158803
X1379217Y0911512
X1377367Y0908324
X1379217Y0905134
X1373666Y0901946
X1377367Y0901946
X1379217Y0898757
X1366264Y0908324
X1368115Y0911512
X1368115Y0905134
X1366264Y0901946
X1369965Y0901946
X1368115Y0898757
X1373666Y0889190
X1377367Y0895568
X1379217Y0892379
X1377367Y0882812
X1373666Y0882812
X1366264Y0895568
X1368115Y0892379
X1369965Y0889190
X1366264Y0882812
X1369965Y0882812
X1375516Y0879623
X1375516Y0873245
X1373666Y0876434
X1379217Y0968914
X1379217Y0962536
X1377367Y0959347
X1377367Y0965725
X1373666Y0959347
X1368115Y0968914
X1366264Y0965725
X1368115Y0962536
X1369965Y0959347
X1366264Y0959347
X1379217Y0956158
X1377367Y0952969
X1379217Y0949780
X1377367Y0946591
X1373666Y0946591
X1379217Y0943402
X1366264Y0952969
X1368115Y0956158
X1366264Y0946591
X1368115Y0949780
X1369965Y0946591
X1368115Y0943402
X1377367Y0940213
X1373666Y0933835
X1377367Y0933835
X1379217Y0930646
X1373666Y0927457
X1377367Y0927457
X1366264Y0940213
X1366264Y0927457
X1369965Y0933835
X1368115Y0930646
X1369965Y0927457
X1366264Y0933835
X1379217Y0924268
X1377367Y0921079
X1379217Y0917890
X1373666Y0914701
X1377367Y0914701
X1366264Y0921079
X1368115Y0924268
X1366264Y0914701
X1368115Y0917890
X1369965Y0914701
X1378548Y1059945
X1371146Y1053567
X1376697Y1056756
X1378548Y1047189
X1371146Y1047189
X1369296Y1050378
X1369296Y1056756
X1367445Y1059945
X1376697Y1044000
X1376697Y1031244
X1374847Y1034433
X1371146Y1040811
X1378548Y1040811
X1376697Y1037622
X1371146Y1034433
X1369296Y1031244
R02Y0006378
X1374847Y1028055
X1371146Y1028055
X1377367Y1003993
X1371815Y1007182
X1375516Y1007182
X1373666Y1010371
X1366264Y1010371
X1368115Y1007182
X1369965Y1003993
X1375516Y1000804
X1375516Y0988048
X1377367Y0997615
X1377367Y0991237
X1375516Y0994426
X1368115Y1000804
X1368115Y0988048
X1368115Y0994426
X1369965Y0997615
X1369965Y0991237
X1377367Y0984859
X1377367Y0978481
X1375516Y0981670
X1379217Y0975292
X1377367Y0972103
X1373666Y0972103
X1369965Y0984859
X1366264Y0978481
X1366264Y0972103
X1368115Y0981670
X1368115Y0975292
X1369965Y0972103
X1378548Y1072701
X1374847Y1066323
X1378548Y1066323
X1371146Y1066323
X1367445Y1072701
X1367445Y1066323
X1369296Y1069512
X1369296Y1063134
X1376697Y1050378
X1378548Y1053567
X1378548Y1104591
X1378548Y1098213
X1374847Y1104591
X1371146Y1104591
X1374847Y1091835
X1378548Y1091835
X1371146Y1091835
X1367445Y1098213
X1367445Y1104591
X1369296Y1095024
X1367445Y1091835
X1378548Y1085457
X1374847Y1079079
X1378548Y1079079
X1371146Y1079079
X1369296Y1082268
X1367445Y1085457
X1369296Y1088646
X1367445Y1079079
X1369296Y1075890
X1378548Y1117347
X1374847Y1110969
X1378548Y1110969
X1371146Y1110969
X1367445Y1117347
X1369296Y1114158
X1367445Y1110969
X1369296Y1107780
X1378548Y1130102
X1378548Y1123725
X1371146Y1123725
X1374847Y1123725
X1369296Y1133292
X1367445Y1123725
X1369296Y1120536
X1369296Y1126914
X1374847Y1161992
X1376697Y1165181
X1376697Y1158803
X1374847Y1155614
X1378548Y1155614
X1371146Y1155614
X1365595Y1158803
X1367445Y1155614
X1374847Y1149236
X1371146Y1149236
X1378548Y1142858
X1378548Y1136480
X1371146Y1136480
X1374847Y1136480
X1369296Y1146047
X1367445Y1142858
X1367445Y1136480
X1369296Y1139669
X1390319Y0892379
X1392170Y0889190
X1388469Y0895568
X1388469Y0882812
X1392170Y0882812
X1384768Y0889190
X1381067Y0889190
X1381067Y0882812
X1384768Y0882812
X1394020Y0873245
X1384768Y0876434
X1382918Y0873245
X1386619Y0879623
X1390319Y0937024
X1388469Y0940213
X1392170Y0933835
X1390319Y0930646
X1392170Y0927457
X1388469Y0933835
X1388469Y0927457
X1384768Y0927457
X1381067Y0927457
X1390319Y0924268
X1388469Y0921079
X1392170Y0914701
X1388469Y0914701
X1390319Y0917890
X1384768Y0914701
X1381067Y0914701
X1390319Y0905134
X1390319Y0911512
X1388469Y0908324
X1392170Y0901946
X1390319Y0898757
X1388469Y0901946
R02X-0003701
X1381065Y1010365
X1392157Y0997607
X1384756Y0997607
X1390319Y0988048
X1392170Y0991237
X1382918Y0988048
X1384768Y0991237
X1392170Y0984859
X1390319Y0975292
X1390319Y0981670
X1392170Y0972103
X1388469Y0972103
X1384768Y0984859
X1382918Y0981670
X1384768Y0972103
X1381067Y0972103
X1388469Y0978481
X1390319Y0968914
X1390319Y0962536
X1392170Y0959347
X1388469Y0959347
X1388469Y0965725
X1384768Y0959347
X1381067Y0959347
X1390319Y0956158
X1388469Y0952969
X1390319Y0949780
X1392170Y0946591
X1390319Y0943402
X1388469Y0946591
R02X-0003701
X1393351Y1066323
X1391500Y1063134
X1380398Y1069512
X1382249Y1066323
X1385949Y1066323
X1380398Y1063134
X1391500Y1050378
X1391500Y1056756
X1389650Y1059945
X1393351Y1053567
X1393351Y1047189
X1384099Y1050378
X1384099Y1056756
X1385949Y1053567
X1385949Y1047189
X1385937Y1040819
X1393339Y1040819
X1385937Y1034441
X1385937Y1028063
X1386606Y1007174
X1391500Y1082268
X1389650Y1085457
X1391500Y1088646
X1389650Y1079079
X1393351Y1079079
X1391500Y1075890
X1380398Y1082268
X1380398Y1088646
X1382249Y1079079
X1385949Y1079079
X1380398Y1075890
X1389650Y1072701
X1391500Y1069512
X1389650Y1066323
X1391500Y1114158
X1389650Y1117347
X1391500Y1107780
X1389650Y1110969
X1393351Y1110969
X1380398Y1114158
X1380398Y1107780
X1382249Y1110969
X1385949Y1110969
X1389650Y1104591
X1393351Y1104591
X1389650Y1098213
X1391500Y1101402
X1391500Y1095024
X1389650Y1091835
X1393351Y1091835
X1380398Y1095024
X1382249Y1091835
X1385949Y1091835
X1391500Y1146047
X1393351Y1149236
X1389650Y1142858
X1389650Y1136480
X1393351Y1136480
X1391500Y1139669
X1380398Y1146047
X1382249Y1149236
X1385949Y1149236
X1382249Y1136480
X1385949Y1136480
X1380398Y1139669
X1389650Y1130102
X1391500Y1133292
R02Y-0006378
X1389650Y1123725
X1393351Y1123725
X1380398Y1133292
R02Y-0006378
X1382249Y1123725
X1385949Y1123725
X1389650Y1155614
X1393351Y1155614
X1387800Y1158803
X1385949Y1161992
X1382249Y1155614
X1385949Y1155614
X1401422Y0898757
X1406973Y0889190
X1403272Y0889190
X1406973Y0882812
X1403272Y0882812
X1395871Y0889190
X1399571Y0895568
X1401422Y0892379
X1395871Y0882812
X1399571Y0882812
X1408823Y0879623
X1395871Y0876434
X1397721Y0879623
X1397721Y0873245
X1395871Y0946591
X1408823Y0937024
X1405123Y0937024
X1408823Y0930646
X1405123Y0930646
X1401422Y0937024
X1399571Y0940213
X1399571Y0933835
X1401422Y0930646
X1399571Y0927457
X1395871Y0933835
X1395871Y0927457
X1408823Y0917890
X1405123Y0917890
X1401422Y0924268
X1399571Y0921079
X1395871Y0914701
X1401422Y0917890
X1399571Y0914701
X1408823Y0905134
X1405123Y0905134
X1401422Y0911512
X1401422Y0905134
X1395871Y0901946
X1399571Y0901946
X1400740Y1040819
X1399559Y0997607
X1406961Y0997607
X1405123Y0988048
X1406973Y0991237
X1397721Y0988048
X1399571Y0991237
X1406973Y0984859
X1405123Y0975292
X1408823Y0975292
X1405123Y0981670
X1399571Y0984859
X1401422Y0975292
X1399571Y0972103
X1395871Y0972103
X1399571Y0978481
X1397721Y0981670
X1405123Y0962536
X1408823Y0962536
X1401422Y0968914
X1401422Y0962536
X1399571Y0959347
X1395871Y0959347
X1399571Y0965725
X1405123Y0949780
X1408823Y0949780
X1401422Y0956158
X1399571Y0952969
X1401422Y0949780
X1399571Y0946591
X1401422Y0943402
X1406304Y1050378
X1406304Y1056756
X1408154Y1053567
X1408154Y1047189
X1398902Y1050378
X1400752Y1059945
X1400752Y1053567
X1398902Y1056756
X1400752Y1047189
X1406304Y1063134
X1400752Y1072701
X1400752Y1066323
X1397052Y1066323
X1402603Y1069512
X1402603Y1063134
X1406304Y1088646
X1406304Y1075890
X1400752Y1085457
X1402603Y1082268
X1402603Y1088646
X1397052Y1079079
X1400752Y1079079
X1402603Y1075890
X1406304Y1101402
X1400752Y1098213
X1397052Y1104591
X1400752Y1104591
X1402603Y1101402
X1397052Y1091835
X1400752Y1091835
X1402603Y1095024
X1406304Y1107780
X1400752Y1117347
X1402603Y1114158
X1400752Y1110969
X1397052Y1110969
X1402603Y1107780
X1406304Y1133292
X1406304Y1120536
X1402603Y1133292
X1400752Y1123725
X1397052Y1123725
X1402603Y1126914
X1402603Y1120536
X1406304Y1158803
X1398902Y1165181
X1397052Y1161992
X1400752Y1155614
X1397052Y1155614
X1398902Y1158803
X1404453Y1149236
X1408154Y1149236
X1397052Y1149236
X1402603Y1146047
X1400752Y1142858
X1400752Y1136480
X1397052Y1136480
X1402603Y1139669
X1423602Y0937024
X1421751Y0933835
X1421751Y0927457
X1423602Y0930646
X1410674Y0940213
R02Y-0006378
X1421751Y0921079
X1421751Y0914701
X1423602Y0917890
X1410674Y0921079
X1410674Y0914701
X1421751Y0908324
X1423602Y0905134
X1421751Y0901946
X1410674Y0908324
X1410674Y0901946
X1421751Y0889190
X1421751Y0895568
X1421751Y0882812
X1410674Y0895568
R02Y-0006378
X1421751Y0876434
X1423602Y0879623
X1410674Y0876434
X1410004Y1101402
X1411855Y1098213
X1411855Y1104591
X1411855Y1091835
X1422932Y1085457
X1422932Y1079079
X1410004Y1088646
X1411855Y1085457
X1411855Y1079079
X1410004Y1075890
X1422932Y1066323
X1422932Y1072701
X1411855Y1072701
X1411855Y1066323
X1410004Y1063134
X1422932Y1053567
X1422932Y1059945
X1422932Y1047189
X1411855Y1059945
X1421764Y0997607
X1421751Y0991237
X1423602Y0988048
X1421751Y0984859
R02Y-0006378
X1423602Y0975292
X1423602Y0981670
X1410674Y0978481
X1410674Y0972103
X1421751Y0965725
X1421751Y0959347
X1423602Y0962536
X1410674Y0965725
X1410674Y0959347
X1421751Y0952969
X1421751Y0946591
X1423602Y0949780
X1410674Y0952969
X1410674Y0946591
X1421751Y0940213
X1422932Y1161992
X1422932Y1155614
X1411855Y1161992
X1411855Y1155614
X1422932Y1149236
R02Y-0006378
X1411855Y1149236
R02Y-0006378
X1422932Y1130102
X1422932Y1123725
X1410004Y1133292
X1411855Y1130102
X1410004Y1120536
X1411855Y1123725
X1422932Y1117347
X1422932Y1110969
X1411855Y1117347
X1411855Y1110969
X1410004Y1107780
X1422932Y1098213
X1422932Y1104591
X1422932Y1091835
X1436554Y0889190
X1432854Y0895568
X1431003Y0892379
X1429153Y0889190
X1425452Y0889190
X1429153Y0882812
X1436554Y0876434
X1436554Y0901946
X1427302Y0905134
X1431003Y0905134
X1431003Y0911512
X1431003Y0898757
X1432854Y0901946
X1436554Y0933835
X1436554Y0927457
X1427302Y0937024
X1431003Y0937024
X1432854Y0940213
X1432854Y0933835
X1427302Y0930646
X1431003Y0930646
X1432854Y0927457
X1436554Y0914701
X1431003Y0924268
X1432854Y0921079
X1427302Y0917890
X1431003Y0917890
X1432854Y0914701
X1436554Y0946591
X1431003Y0956158
X1432854Y0952969
X1432854Y0946591
X1427302Y0949780
X1431003Y0949780
X1431003Y0943402
X1436554Y0959347
X1431003Y0968914
X1432854Y0965725
X1431003Y0962536
X1427302Y0962536
X1432854Y0959347
X1437735Y1053567
X1437735Y1047189
X1432184Y1050378
X1424783Y1050378
X1430334Y1053567
X1432184Y1056756
X1434035Y1059945
X1424783Y1056756
X1430334Y1047189
X1437748Y1040819
X1430346Y1040819
X1429165Y0997607
X1436567Y0997607
X1438405Y0988048
X1436554Y0991237
X1429153Y0991237
X1431003Y0988048
X1436554Y0984859
X1436554Y0972103
X1438405Y0981670
X1429153Y0984859
X1427302Y0975292
X1431003Y0975292
X1432854Y0972103
X1431003Y0981670
X1432854Y0978481
X1437735Y1066323
X1434035Y1066323
X1434035Y1072701
X1432184Y1069512
X1424783Y1063134
X1428483Y1063134
X1432184Y1063134
X1434035Y1085457
X1432184Y1088646
X1428483Y1088646
X1432184Y1082268
X1424783Y1088646
X1434035Y1079079
X1424783Y1075890
X1432184Y1075890
X1428483Y1075890
X1437735Y1104591
X1437735Y1091835
X1424783Y1101402
X1434035Y1098213
X1432184Y1101402
X1428483Y1101402
X1434035Y1104591
X1434035Y1091835
X1432184Y1095024
X1437735Y1079079
X1437735Y1110969
X1432184Y1114158
X1434035Y1117347
X1434035Y1110969
X1424783Y1107780
X1432184Y1107780
X1428483Y1107780
X1437735Y1123725
X1432184Y1133292
X1428483Y1133292
X1424783Y1133292
X1434035Y1123725
X1424783Y1120536
X1428483Y1120536
X1432184Y1120536
X1432184Y1126914
X1435885Y1152425
X1435885Y1158803
X1430333Y1155614
X1437735Y1149236
X1437735Y1136480
X1426633Y1149236
X1432184Y1146047
X1430334Y1149236
X1434035Y1142858
X1434035Y1136480
X1432184Y1139669
X1445806Y0879623
X1447657Y0876434
X1453208Y0911512
X1453208Y0905134
X1453208Y0898757
X1451358Y0901946
X1442106Y0911512
X1443956Y0908324
X1442106Y0905134
X1443956Y0901946
X1447657Y0901946
X1440255Y0901946
X1442106Y0898757
X1453208Y0892379
X1451358Y0889190
X1451357Y0882812
X1443956Y0895568
X1442106Y0892379
X1447657Y0889190
X1440255Y0889190
X1447657Y0882812
X1443956Y0882812
X1453208Y0956158
R02Y-0006378
X1451357Y0946591
X1442106Y0956158
X1443956Y0952969
X1443956Y0946591
X1442106Y0949780
X1440255Y0946591
X1442106Y0943402
X1447657Y0946591
X1451357Y0927457
X1453208Y0930646
X1443956Y0940213
X1442106Y0937024
X1443956Y0933835
X1440255Y0933835
X1447657Y0927457
R02X-0003701
X1453208Y0924268
X1453208Y0917890
X1451357Y0914701
X1442106Y0924268
X1443956Y0921079
X1442106Y0917890
X1447657Y0914701
R02X-0003701
X1443968Y0997607
X1453208Y1000804
X1451357Y0991237
X1453208Y0994426
X1453208Y0988048
X1443956Y0991237
X1445806Y0988048
X1451357Y0984859
X1453208Y0975292
X1451357Y0972103
X1453208Y0981670
X1443956Y0984859
X1440255Y0972103
X1442106Y0975292
X1447657Y0972103
X1443956Y0972103
X1443956Y0978481
X1445806Y0981670
X1453208Y0968914
X1453208Y0962536
X1451357Y0959347
X1442106Y0968914
X1442106Y0962536
X1443956Y0965725
X1447657Y0959347
R02X-0003701
X1452539Y1066323
X1441436Y1066323
X1445137Y1066323
X1448838Y1066323
X1443287Y1069512
X1445137Y1072701
X1443287Y1063134
X1452539Y1053567
X1452539Y1047189
X1446987Y1050378
X1439586Y1050378
X1445137Y1053567
X1439586Y1056756
X1445137Y1059945
X1446987Y1056756
X1445137Y1047189
X1445149Y1040819
X1452542Y1040819
X1453208Y1007182
X1452539Y1079079
X1443287Y1082268
X1445137Y1085457
X1443287Y1088646
X1443287Y1075890
X1441436Y1079079
X1448838Y1079079
X1445137Y1079079
X1452539Y1110969
X1443287Y1114158
X1445137Y1117347
X1443287Y1107780
X1445137Y1110969
X1448838Y1110969
X1441436Y1110969
X1452539Y1091835
X1441436Y1104591
X1445137Y1098213
X1443287Y1101402
X1445137Y1104591
X1443287Y1095024
X1445137Y1091835
X1448838Y1091835
X1441436Y1091835
X1441436Y1136480
X1448838Y1136480
X1445137Y1136480
X1443287Y1139669
X1445137Y1142858
X1452539Y1123725
X1445137Y1130102
X1443287Y1133292
X1443287Y1126914
X1441436Y1123725
X1443287Y1120536
X1448838Y1123725
X1445137Y1123725
X1441436Y1155614
X1450688Y1152425
X1446987Y1158803
X1452539Y1149236
X1452539Y1136480
X1441436Y1149236
X1443287Y1146047
X1448838Y1149236
X1462460Y0889190
X1466161Y0895568
X1464310Y0892379
X1455058Y0895568
X1458759Y0889190
X1458759Y0882812
X1466161Y0882812
X1462460Y0882812
X1455058Y0882812
X1468011Y0879623
X1458759Y0876434
X1456909Y0879623
X1456909Y0873245
X1466161Y0914701
X1462460Y0914701
X1455058Y0914701
X1464310Y0911512
X1455058Y0908324
X1464310Y0905134
X1462460Y0901946
X1466161Y0901946
X1458759Y0901946
X1455058Y0901946
X1464310Y0898757
X1464310Y0949780
X1455058Y0946591
X1464310Y0943402
X1466161Y0940213
X1455058Y0940213
X1458759Y0933835
X1466161Y0933835
X1462460Y0933835
X1464310Y0930646
X1455058Y0933835
X1462460Y0927457
X1466161Y0927457
X1458759Y0927457
X1455058Y0927457
X1466161Y0921079
X1455058Y0921079
X1464310Y0924268
X1464310Y0917890
X1458759Y0914701
X1464310Y0968914
X1464310Y0962536
X1458759Y0959347
X1466161Y0959347
X1462460Y0959347
X1455058Y0959347
X1466161Y0965725
X1455058Y0965725
X1455058Y0952969
X1464310Y0956158
X1466161Y0952969
X1458759Y0946591
X1466161Y0946591
X1462460Y0946591
X1461791Y1044000
X1461791Y1037622
X1454389Y1044000
X1456239Y1028055
X1463641Y1028055
X1468011Y1007182
X1460609Y1007182
X1458759Y1010371
X1466161Y1010371
X1466161Y1003993
X1458759Y1003993
X1468011Y1000804
R02Y-0006378
X1460609Y1000804
X1466161Y0991237
X1458759Y0991237
X1460609Y0994426
X1460609Y0988048
X1466161Y0997615
X1458759Y0997615
X1468011Y0981670
X1466161Y0984859
X1458759Y0984859
X1464310Y0975292
X1458759Y0972103
X1466161Y0972103
X1462460Y0972103
X1455058Y0972103
X1466161Y0978481
X1455058Y0978481
X1460609Y0981670
X1467342Y1066323
X1467342Y1072701
X1456239Y1066323
X1454389Y1069512
X1465491Y1069512
X1463641Y1066323
X1459940Y1066323
X1456239Y1072701
X1454389Y1063134
X1465491Y1063134
X1467342Y1053567
X1467342Y1059945
X1467342Y1047189
X1461791Y1050378
X1454389Y1050378
X1461791Y1056756
X1454389Y1056756
X1459940Y1053567
X1456239Y1059945
X1459940Y1047189
X1467342Y1040811
X1454389Y1037622
X1465491Y1031244
X1456239Y1034433
X1463641Y1034433
X1458090Y1031244
X1459940Y1040811
X1456239Y1104591
X1463641Y1104591
X1459940Y1104591
X1454389Y1095024
X1465491Y1095024
X1456239Y1091835
R02X0003701
X1467342Y1085457
X1467342Y1079079
X1454389Y1082268
X1465491Y1082268
X1456239Y1085457
X1454389Y1088646
X1465491Y1088646
X1454389Y1075890
X1465491Y1075890
X1456239Y1079079
X1463641Y1079079
X1459940Y1079079
X1467342Y1117347
X1467342Y1110969
X1465491Y1114158
X1454389Y1114158
X1456239Y1117347
X1456239Y1110969
X1459940Y1110969
X1463641Y1110969
X1454389Y1107780
X1465491Y1107780
X1467342Y1098213
X1467342Y1104591
X1467342Y1091835
X1456239Y1098213
X1458090Y1158803
X1461791Y1152425
X1463641Y1155614
X1467342Y1142858
X1467342Y1136480
X1454389Y1146047
X1463641Y1149236
X1459940Y1149236
X1465491Y1146047
X1456239Y1136480
X1454389Y1139669
X1463641Y1136480
X1459940Y1136480
X1465491Y1139669
X1456239Y1142858
X1467342Y1130102
X1467342Y1123725
X1465491Y1133292
X1456239Y1130102
X1454389Y1133292
X1456239Y1123725
X1465491Y1120536
X1463641Y1123725
X1459940Y1123725
X1454389Y1126914
X1465491Y1126914
X1454389Y1120536
X1479113Y0879623
X1469861Y0876434
X1479113Y0873245
X1475413Y0905134
X1475413Y0911512
X1477263Y0908324
X1482814Y0911512
X1482814Y0905134
X1473562Y0901946
X1475413Y0898757
X1469861Y0901946
X1482814Y0898757
X1477263Y0895568
X1475413Y0892379
X1473562Y0889190
X1469861Y0889190
X1482814Y0892379
X1479113Y0886001
X1469861Y0882812
X1480964Y0882812
X1482814Y0886001
X1477263Y0940213
X1482814Y0937024
X1469861Y0927457
X1473562Y0927457
X1477263Y0933835
X1475413Y0930646
X1482814Y0930646
X1473562Y0933835
X1469861Y0933835
X1477263Y0921079
X1482814Y0924268
X1475413Y0924268
X1475413Y0917890
X1473562Y0914701
X1469861Y0914701
X1482814Y0917890
X1475413Y0956158
X1477263Y0952969
X1482814Y0956158
X1475413Y0949780
X1473562Y0946591
X1469861Y0946591
X1475413Y0943402
X1482814Y0949780
X1482814Y0943402
X1482814Y1000804
X1475413Y0994426
X1475413Y0988048
X1473562Y0997615
X1473562Y0991237
X1482814Y0994426
X1482814Y0988048
X1473562Y0984859
X1475413Y0981670
X1477263Y0978481
X1475413Y0975292
X1473562Y0972103
X1469861Y0972103
X1482814Y0981670
X1482814Y0975292
X1475413Y0968914
X1482814Y0968914
X1477263Y0965725
X1475413Y0962536
X1473562Y0959347
X1469861Y0959347
X1482814Y0962536
X1471043Y1034433
X1476594Y1044000
X1474743Y1040811
X1476594Y1037622
X1478444Y1034433
X1469192Y1044000
X1469192Y1037622
X1472893Y1031244
X1471043Y1028055
X1478444Y1028055
X1475413Y1007182
X1473562Y1010371
X1473562Y1003993
X1482814Y1007182
X1475413Y1000804
X1471043Y1066323
X1474743Y1066323
X1476594Y1069512
X1478444Y1072701
X1476594Y1063134
X1469192Y1056756
X1478444Y1059945
X1474743Y1053567
X1476594Y1056756
X1476594Y1050378
X1469192Y1050378
X1482145Y1059945
X1480295Y1056756
X1474743Y1047189
X1472893Y1101402
X1471043Y1104591
X1474743Y1104591
X1478444Y1104591
X1478444Y1098213
X1476594Y1095024
X1471043Y1091835
X1474743Y1091835
X1476594Y1082268
X1476594Y1088646
X1478444Y1085457
X1471043Y1079079
X1474743Y1079079
X1476594Y1075890
X1478444Y1117347
X1476594Y1114158
X1471043Y1110969
X1474743Y1110969
X1476594Y1107780
X1476594Y1133292
X1478444Y1130102
X1471043Y1123725
X1474743Y1123725
X1476594Y1120536
X1476594Y1126914
X1469192Y1158803
X1480295Y1158803
X1472893Y1152425
X1478444Y1155614
X1474743Y1155614
X1471043Y1149236
X1474743Y1149236
X1476594Y1146047
X1478444Y1142858
X1471043Y1136480
X1474743Y1136480
X1476594Y1139669
X1492066Y0876434
X1495767Y0895568
X1490216Y0892379
X1495767Y0889190
X1488365Y0889190
X1493917Y0886001
X1495767Y0882812
X1488365Y0882812
X1484665Y0882812
X1490216Y0886001
X1495767Y0908324
X1490216Y0911512
X1488365Y0908324
X1495767Y0901946
X1488365Y0901946
X1490216Y0898757
X1490216Y0937024
X1495767Y0940213
X1488365Y0940213
X1495767Y0927457
X1488365Y0927457
X1495767Y0933835
X1490216Y0930646
X1495767Y0921079
X1488365Y0921079
X1490216Y0917890
X1495767Y0914701
X1490216Y0956158
X1495767Y0952969
X1495767Y0946591
X1490216Y0949780
X1488365Y0946591
X1490216Y0968914
X1488365Y0959347
X1495767Y0965725
X1495767Y0959347
X1488365Y0965725
X1495767Y0984859
X1488365Y0984859
X1484665Y0984859
X1497617Y0981670
X1495767Y0978481
X1488365Y0978481
X1486515Y0981670
X1490216Y0975292
X1495767Y0972103
X1496948Y1028055
X1489547Y1028055
X1495767Y1010371
X1495767Y1003993
X1490216Y1007182
X1488365Y1003993
X1495767Y0997615
X1495767Y0991237
X1490216Y0994426
X1488365Y0997615
X1490216Y0988048
X1496948Y1059945
X1496948Y1053567
X1493247Y1059945
X1489547Y1059945
X1491397Y1050378
X1495098Y1056756
X1489547Y1053567
X1483995Y1056756
X1483995Y1050378
X1496948Y1047189
R02Y-0006378
X1491397Y1044000
X1489547Y1034433
X1489547Y1040811
X1491397Y1031244
X1483995Y1044000
R02Y-0006378
X1496948Y1066323
X1496948Y1072701
X1491397Y1069512
X1489547Y1072701
X1483995Y1069512
X1491397Y1063134
X1483995Y1063134
X1491397Y1082268
X1483995Y1082268
X1496948Y1085457
X1491397Y1088646
X1483995Y1088646
X1496948Y1079079
X1489547Y1079079
X1483995Y1075890
X1496948Y1104591
X1496948Y1098213
X1491397Y1101402
X1489547Y1098213
X1483995Y1101402
X1483995Y1095024
X1496948Y1091835
X1489547Y1091835
X1496948Y1117347
X1489547Y1117347
X1483995Y1114158
X1491397Y1107780
X1483995Y1107780
X1496948Y1110969
X1489547Y1110969
X1496948Y1130102
X1483995Y1133292
X1491397Y1126914
X1483995Y1126914
X1496948Y1123725
X1491397Y1120536
X1483995Y1120536
X1498812Y1165289
X1491410Y1165289
X1495111Y1165289
X1493247Y1161992
X1491397Y1158803
X1483995Y1158803
X1496948Y1155614
X1493247Y1155614
X1489547Y1155614
X1485846Y1155614
X1483995Y1152425
X1498799Y1158803
X1487696Y1165181
X1496948Y1149236
X1491397Y1146047
X1489547Y1149236
X1483995Y1146047
X1496948Y1142858
X1496948Y1136480
X1491397Y1139669
X1489547Y1136480
X1483995Y1139669
X1505019Y0886001
X1499468Y0882812
X1508720Y0879623
X1510570Y0876434
X1501318Y0879623
X1501318Y0873245
X1508720Y0924268
X1501318Y0924268
X1503169Y0921079
X1508720Y0917890
X1501318Y0917890
X1503169Y0914701
X1508720Y0911512
X1501318Y0911512
X1508720Y0905134
X1501318Y0905134
X1503169Y0901946
X1508720Y0898757
X1501318Y0898757
X1508720Y0892379
X1501318Y0892379
X1503169Y0895568
X1503169Y0889190
X1508720Y0886001
X1510570Y0882812
X1501318Y0886001
X1501318Y0937024
X1503169Y0940213
X1508720Y0937024
X1508720Y0930646
X1503169Y0933835
X1501318Y0930646
X1503169Y0927457
X1503169Y0984859
X1499468Y0984859
X1508720Y0981670
X1508720Y0975292
X1501318Y0981670
X1503169Y0978481
X1501318Y0975292
X1503169Y0972103
X1512421Y0981670
X1508720Y0968914
X1501318Y0968914
X1508720Y0962536
X1501318Y0962536
X1503169Y0965725
X1503169Y0959347
X1508720Y0956158
X1501318Y0956158
X1503169Y0952969
X1508720Y0949780
X1501318Y0949780
X1503169Y0946591
X1508720Y0943402
X1501318Y0943402
X1504350Y1028055
X1503169Y1003993
X1508720Y1007182
X1503169Y1010371
X1501318Y1007182
X1508720Y1000804
X1501318Y1000804
X1508720Y0994426
X1508720Y0988048
X1501318Y0994426
X1503169Y0997615
X1501318Y0988048
X1503169Y0991237
X1510570Y0984859
X1502499Y1056756
X1506200Y1056756
X1508050Y1059945
X1504350Y1059945
X1509901Y1050378
X1509901Y1056756
X1502499Y1050378
X1504350Y1053567
X1504350Y1047189
X1509901Y1044000
X1509901Y1037622
X1502499Y1044000
X1504350Y1034433
X1502499Y1037622
X1504350Y1040811
X1509901Y1031244
X1502499Y1031244
X1509901Y1082268
X1502499Y1082268
X1509901Y1088646
X1502499Y1088646
X1504350Y1085457
X1504350Y1079079
X1509901Y1075890
X1502499Y1075890
X1509901Y1069512
X1504350Y1066323
X1504350Y1072701
X1502499Y1069512
X1509901Y1063134
X1502499Y1063134
X1502499Y1114158
X1504350Y1117347
X1509901Y1114158
X1504350Y1110969
X1509901Y1107780
X1502499Y1107780
X1504350Y1104591
X1509901Y1101402
X1502499Y1101402
X1504350Y1098213
X1509901Y1095024
X1502499Y1095024
X1504350Y1091835
X1509901Y1146047
X1502499Y1146047
X1504350Y1149236
X1504350Y1142858
X1509901Y1139669
X1504350Y1136480
X1502499Y1139669
X1509901Y1133292
X1509901Y1126914
X1502499Y1126914
X1509901Y1120536
X1504350Y1123725
X1502499Y1120536
X1502512Y1165289
R02X0003701
X1509901Y1158803
R02X-0003701
X1511751Y1155614
X1509901Y1152425
X1502499Y1152425
X1504350Y1155614
X1523523Y0873245
X1516121Y0879623
X1527224Y0879623
X1519822Y0879623
X1517972Y0876434
X1521673Y0876434
X1516121Y0911512
X1527224Y0905134
X1527224Y0911512
X1516121Y0898757
X1527224Y0898757
X1521673Y0901946
X1514271Y0908324
X1514271Y0901946
X1516121Y0892379
X1527224Y0892379
X1521673Y0895568
X1521673Y0889190
X1527224Y0886001
X1525373Y0882812
X1519822Y0886001
X1521673Y0882812
X1514271Y0889190
X1514271Y0882812
X1521673Y0940213
X1527224Y0937024
X1516121Y0937024
X1527224Y0930646
X1521673Y0933835
X1521673Y0927457
X1516121Y0930646
X1514271Y0940213
X1514271Y0927457
X1527224Y0924268
X1521673Y0921079
X1516121Y0917890
X1527224Y0917890
X1521673Y0914701
X1514271Y0921079
X1516121Y0968914
X1527224Y0968914
X1527224Y0962536
X1521673Y0965725
X1521673Y0959347
X1514271Y0965725
X1514271Y0959347
X1516121Y0956158
X1527224Y0956158
X1521673Y0952969
X1527224Y0949780
X1527224Y0943402
X1521673Y0946591
X1516121Y0949780
X1514271Y0946591
X1527224Y1000804
X1516121Y0994426
X1516121Y0988048
X1527224Y0994426
X1527224Y0988048
X1521673Y0997615
X1521673Y0991237
X1514271Y0997615
X1525373Y0984859
X1521673Y0984859
X1516121Y0975292
X1527224Y0981670
X1527224Y0975292
X1521673Y0978481
X1523523Y0981670
X1521673Y0972103
X1514271Y0984859
X1514271Y0978481
X1528405Y1056756
X1528405Y1050378
X1519153Y1059945
X1522854Y1059945
X1517302Y1050378
X1521003Y1056756
X1522854Y1053567
X1522854Y1047189
X1528405Y1031244
X1517302Y1031244
X1515452Y1034433
X1515452Y1040811
X1528405Y1044000
X1528405Y1037622
X1517302Y1044000
X1522854Y1040811
X1522854Y1034433
X1515452Y1028055
X1522854Y1028055
X1527224Y1007182
X1521673Y1010371
X1521673Y1003993
X1516121Y1007182
X1514271Y1003993
X1528405Y1088646
X1517302Y1088646
X1522854Y1085457
X1528405Y1082268
X1517302Y1082268
X1522854Y1079079
X1515452Y1079079
X1528405Y1075890
X1528405Y1069512
X1517302Y1069512
X1522854Y1072701
X1522854Y1066323
X1515452Y1072701
X1528405Y1063134
X1517302Y1063134
X1515452Y1059945
X1515452Y1053567
X1515452Y1117347
X1528405Y1114158
X1522854Y1117347
X1515452Y1110969
X1522854Y1110969
X1528405Y1107780
X1517302Y1107780
X1517302Y1101402
X1522854Y1098213
X1515452Y1098213
X1528405Y1101402
X1522854Y1104591
X1528405Y1095024
X1522854Y1091835
X1515452Y1091835
X1515452Y1130102
X1528405Y1133292
X1528405Y1126914
X1517302Y1126914
X1528405Y1120536
X1517302Y1120536
X1522854Y1123725
X1519153Y1161992
X1522854Y1155614
R02X-0003701
X1528405Y1158803
X1524704Y1158803
X1528405Y1152425
X1517302Y1146047
X1522854Y1149236
X1515452Y1149236
X1528405Y1146047
X1515452Y1136480
X1528405Y1139669
X1517302Y1139669
X1522854Y1136480
X1522854Y1142858
X1538326Y0879623
X1529074Y0876434
X1534625Y0911512
X1534625Y0905134
X1542027Y0911512
X1540176Y0908324
X1534625Y0898757
X1540176Y0901946
X1542027Y0898757
X1529074Y0908324
X1529074Y0901946
X1534625Y0892379
X1542027Y0892379
X1540176Y0889190
X1534625Y0886001
X1536476Y0882812
X1540176Y0882812
X1529074Y0895568
X1529074Y0889190
X1530925Y0886001
X1534625Y0924268
X1540176Y0921079
X1534625Y0917890
X1542027Y0917890
X1529074Y0921079
X1529074Y0914701
X1542027Y0956158
X1534625Y0956158
X1534625Y0949780
X1534625Y0943402
X1542027Y0949780
X1540176Y0946591
X1529074Y0952969
X1529074Y0946591
X1534625Y0937024
X1540176Y0940213
X1542027Y0937024
X1534625Y0930646
X1542027Y0930646
X1540176Y0927457
X1529074Y0940213
R02Y-0006378
X1529074Y0984859
R02Y-0006378
X1534625Y0968914
X1542027Y0968914
X1534625Y0962536
X1540176Y0965725
X1540176Y0959347
X1529074Y0965725
X1529074Y0959347
X1540176Y1003993
X1529074Y1010371
X1529074Y1003993
X1534625Y1000804
R02Y-0006378
X1542027Y0994426
X1540176Y0997615
X1542027Y0988048
X1529074Y0997615
X1529074Y0991237
X1540176Y0984859
X1536476Y0984859
X1534625Y0981670
X1534625Y0975292
X1540176Y0978481
X1542027Y0975292
X1538326Y0981670
X1535806Y1044000
R02Y-0006378
X1543208Y1044000
X1543208Y1031244
X1541357Y1034433
X1541357Y1040811
X1530255Y1040811
X1530255Y1034433
X1541358Y1028055
X1530255Y1028055
X1534625Y1007182
X1542027Y1007182
X1535806Y1069512
X1541357Y1072701
X1543208Y1069512
X1535806Y1063134
X1543208Y1063134
X1530255Y1072701
X1530255Y1066323
X1533956Y1059945
X1535806Y1050378
X1535806Y1056756
X1532106Y1056756
X1543208Y1050378
X1541357Y1059945
X1541357Y1053567
X1530255Y1059945
R02Y-0006378
X1530255Y1091835
X1535806Y1082268
X1535806Y1088646
X1543208Y1088646
X1543208Y1082268
X1541357Y1079079
X1535806Y1075890
X1530255Y1085457
X1530255Y1079079
X1535806Y1114158
X1541357Y1117347
X1541357Y1110969
X1535806Y1107780
X1543208Y1107780
X1530255Y1117347
X1530255Y1110969
X1535806Y1101402
X1541357Y1098213
X1543208Y1101402
X1535806Y1095024
X1541357Y1091835
X1530255Y1104591
X1530255Y1098213
X1535806Y1133292
X1541357Y1130102
X1535806Y1126914
X1543208Y1126914
X1535806Y1120536
X1543208Y1120536
X1530255Y1130102
X1530255Y1123725
X1532106Y1165181
X1541357Y1161992
X1535806Y1158803
X1532106Y1158803
X1535806Y1152425
X1541357Y1155614
X1537657Y1155614
X1530255Y1155614
X1535806Y1146047
X1541357Y1149236
X1543208Y1146047
X1535806Y1139669
X1543208Y1139669
X1541357Y1136480
X1530255Y1149236
X1530255Y1136480
X1530255Y1142858
X1553870Y0969961
R02Y-0006378
X1547578Y0965725
R02Y-0006378
X1553870Y0950827
X1553870Y0944449
X1547578Y0946591
X1553870Y0938071
X1547578Y0940213
X1553870Y0931693
X1547578Y0933835
X1547578Y0927457
X1553870Y0925315
X1547578Y0921079
X1553870Y0918937
X1547578Y0914701
X1553870Y0912559
X1553870Y0906181
X1547578Y0908324
X1553129Y0898757
X1547578Y0901946
X1553129Y0892379
X1547578Y0895568
X1547578Y0889190
X1551279Y0882812
X1553129Y0886001
X1547578Y0882812
X1545728Y0886001
X1553129Y0879623
X1545728Y0873245
X1548759Y1130102
X1555051Y1125867
X1548759Y1123725
X1555051Y1119489
X1548759Y1117347
X1555051Y1113111
X1548759Y1110969
X1555051Y1106733
X1555051Y1100355
X1548759Y1104591
X1548759Y1098213
X1555051Y1093977
X1548759Y1091835
X1555051Y1087599
X1548759Y1085457
X1555051Y1081221
X1548759Y1079079
X1555051Y1074843
X1555051Y1068465
X1548759Y1066323
X1548759Y1072701
X1555051Y1062087
X1555051Y1055709
X1548759Y1059945
X1548759Y1053567
X1555051Y1049331
X1548759Y1047189
X1545058Y1059945
X1546909Y1056756
X1555051Y1036575
X1555051Y1042953
X1548759Y1034433
X1548759Y1040811
X1555051Y1030197
X1548759Y1028055
X1553870Y1001851
X1553870Y1008229
X1547578Y1010371
X1547578Y1003993
X1553870Y0995473
X1553870Y0989095
X1547578Y0997615
X1547578Y0991237
X1545728Y0988048
X1547578Y0984859
X1553870Y0982717
X1553870Y0976339
X1547578Y0978481
X1547578Y0972103
X1543877Y0984859
X1554310Y1158803
X1550609Y1158803
X1555051Y1151378
X1548759Y1155614
X1545058Y1155614
X1548759Y1149236
X1555051Y1145000
X1548759Y1142858
X1555051Y1138622
X1548759Y1136480
X1555051Y1132245
X1367445Y1130103
X0391304Y1130105
X0456712Y0908324
X0528208Y1130104
X0229049Y1521453
X0385458Y1521453
X0390203Y1521453
X0371285Y1521453
X0366560Y1521453
X0380734Y1521453
X0376009Y1521453
X0352387Y1521453
X0357111Y1521453
X0361836Y1521453
X0338214Y1521453
X0342938Y1521453
X0347663Y1521453
X0324041Y1521453
X0328765Y1521453
X0333489Y1521453
X0314592Y1521453
X0319316Y1521453
X0386009Y1528853
X0381285Y1528853
X0371836Y1528853
X0367111Y1528853
X0376560Y1528853
X0352938Y1528853
X0357662Y1528853
X0362387Y1528853
X0338765Y1528853
X0343489Y1528853
X0348214Y1528853
X0324592Y1528853
X0329316Y1528853
X0334040Y1528853
X0315143Y1528853
X0319867Y1528853
X0229600Y1528853
X0262141Y1521453
X0247947Y1521453
X0252672Y1521453
X0257396Y1521453
X0233774Y1521453
X0238498Y1521453
X0243223Y1521453
X0224325Y1521453
X0219601Y1521453
X0214876Y1521453
X0210152Y1521453
X0205427Y1521453
X0200703Y1521453
X0195979Y1521453
X0191254Y1521453
X0186530Y1521453
X0248498Y1528853
X0253223Y1528853
X0257947Y1528853
X0234325Y1528853
X0239049Y1528853
X0243774Y1528853
X0224876Y1528853
X0220152Y1528853
X0215427Y1528853
X0210703Y1528853
X0205978Y1528853
R02X-0004724
X0191805Y1528853
X0187081Y1528853
X0243273Y1536063
X0233824Y1536063
X0229100Y1536063
R02X-0009449
X0205478Y1536063
X0253002Y1514243
X0252722Y1536063
X0371335Y1536063
X0361886Y1536063
X0357162Y1536063
X0347713Y1536063
X0338264Y1536063
X0333540Y1536063
X0381064Y1514243
X0380784Y1536063
X1619487Y1717903
X1619487Y1722440
X1619487Y1726974
X1627361Y1730911
X1627361Y1726377
X1627361Y1721840
X1603739Y1717903
X1603739Y1722440
X1603739Y1726974
X1611613Y1730911
X1611613Y1726377
X1611613Y1721840
X1595865Y1730911
X1595865Y1726377
X1595865Y1721840
X1587991Y1717903
X1587991Y1722440
X1587991Y1726974
X1580117Y1730911
X1580117Y1726377
X1580117Y1721840
X1560431Y1730911
X1560431Y1726377
X1560431Y1721840
X1572243Y1717903
X1572243Y1722440
X1572243Y1726974
X1552557Y1717903
X1552557Y1722440
X1552557Y1726974
X1544683Y1730911
X1544683Y1726377
X1544683Y1721840
X1536809Y1717903
X1536809Y1722440
X1536809Y1726974
X1528935Y1730911
X1528935Y1726377
X1528935Y1721840
X1521061Y1717903
X1521061Y1722440
X1521061Y1726974
X1505313Y1717903
X1505313Y1722440
X1505313Y1726974
X1513187Y1730911
X1513187Y1726377
X1513187Y1721840
X1363187Y1721840
X1355313Y1717903
X1355313Y1722440
X1355313Y1726974
X1363187Y1730911
X1363187Y1726377
X1339565Y1717903
X1339565Y1722440
X1339565Y1726974
X1347439Y1730911
X1347439Y1726377
X1347439Y1721840
X1323817Y1717903
X1323817Y1722440
X1323817Y1726974
X1331691Y1730911
X1331691Y1726377
X1331691Y1721840
X1308069Y1717903
X1308069Y1722440
X1308069Y1726974
X1315943Y1730911
X1315943Y1726377
X1315943Y1721840
X1296258Y1730911
X1296258Y1726377
X1296258Y1721840
X1288384Y1717903
X1288384Y1722440
X1288384Y1726974
X1280510Y1730911
X1280510Y1726377
X1280510Y1721840
X1272636Y1717903
X1272636Y1722440
X1272636Y1726974
X1264762Y1730911
X1264762Y1726377
X1264762Y1721840
X1256888Y1717903
X1256888Y1722440
X1256888Y1726974
X1249014Y1730911
X1249014Y1726377
X1249014Y1721840
X1241140Y1717903
X1241140Y1722440
X1241140Y1726974
X0619487Y1730911
X0619487Y1726377
X0619487Y1721840
X0611613Y1717903
X0611613Y1722440
X0611613Y1726974
X0595865Y1717903
X0595865Y1722440
X0595865Y1726974
X0603739Y1730911
X0603739Y1726377
X0603739Y1721840
X0580117Y1717903
X0580117Y1722440
X0580117Y1726974
X0587991Y1730911
X0587991Y1726377
X0587991Y1721840
X0572243Y1721840
X0564369Y1717903
X0564369Y1722440
X0564369Y1726974
X0572243Y1730911
X0572243Y1726377
X0552558Y1730911
X0552558Y1726377
X0552558Y1721840
X0544684Y1717903
X0544684Y1722440
X0544684Y1726974
X0536810Y1730911
X0536810Y1726377
X0536810Y1721840
X0528936Y1717903
X0528936Y1722440
X0528936Y1726974
X0521062Y1730911
X0521062Y1726377
X0521062Y1721840
X0513188Y1717903
X0513188Y1722440
X0513188Y1726974
X0505314Y1730911
X0505314Y1726377
X0505314Y1721840
X0497440Y1717903
X0497440Y1722440
X0497440Y1726974
X0355314Y1721840
X0355314Y1726377
X0355314Y1730911
X0339566Y1721840
X0339566Y1726377
X0339566Y1730911
X0347440Y1726974
X0347440Y1722440
X0347440Y1717903
X0323818Y1726377
X0323818Y1730911
X0331692Y1726974
X0331692Y1722440
X0331692Y1717903
X0323818Y1721840
X0315944Y1717903
X0308070Y1721840
X0308070Y1726377
X0308070Y1730911
X0315944Y1726974
X0315944Y1722440
X0300196Y1726974
X0300196Y1722440
X0300196Y1717903
X0280511Y1717903
X0280511Y1722440
X0280511Y1726974
X0288385Y1730911
X0288385Y1726377
X0288385Y1721840
X0264763Y1717903
X0264763Y1722440
X0264763Y1726974
X0272637Y1730911
X0272637Y1726377
X0272637Y1721840
X0249015Y1717903
X0249015Y1722440
X0249015Y1726974
X0256889Y1730911
X0256889Y1726377
X0256889Y1721840
X0233267Y1726974
X0233267Y1722440
X0233267Y1717903
X0241141Y1730911
X0241141Y1726377
X0241141Y1721840
X1619487Y1712800
X1627361Y1712203
X1627361Y1707666
X1627361Y1702564
X1627361Y1716737
X1619487Y1703729
X1619487Y1708266
X1611613Y1716737
X1603739Y1703729
X1603739Y1708266
X1603739Y1712800
X1611613Y1712203
X1611613Y1707666
X1611613Y1702564
X1595865Y1712203
X1595865Y1707666
X1595865Y1702564
X1595865Y1716737
X1587991Y1703729
X1587991Y1708266
X1587991Y1712800
X1580117Y1712203
X1580117Y1707666
X1580117Y1702564
X1580117Y1716737
X1560431Y1712203
X1560431Y1707666
X1560431Y1702564
X1560431Y1716737
X1572243Y1703729
X1572243Y1708266
X1572243Y1712800
X1552557Y1703729
X1552557Y1708266
X1552557Y1712800
X1544683Y1712203
X1544683Y1707666
X1544683Y1702564
X1544683Y1716737
X1528935Y1707666
X1528935Y1702564
X1528935Y1716737
X1536809Y1703729
X1536809Y1708266
X1536809Y1712800
X1528935Y1712203
X1521061Y1703729
X1521061Y1708266
X1521061Y1712800
X1505313Y1703729
X1505313Y1708266
X1505313Y1712800
X1513187Y1712203
X1513187Y1707666
X1513187Y1702564
X1513187Y1716737
X1355313Y1703729
X1355313Y1708266
X1355313Y1712800
X1363187Y1712203
X1363187Y1707666
X1363187Y1702564
X1363187Y1716737
X1339565Y1703729
X1339565Y1708266
X1339565Y1712800
X1347439Y1712203
X1347439Y1707666
X1347439Y1702564
X1347439Y1716737
X1323817Y1703729
X1323817Y1708266
X1323817Y1712800
X1331691Y1712203
X1331691Y1707666
X1331691Y1702564
X1331691Y1716737
X1308069Y1703729
X1308069Y1708266
X1308069Y1712800
X1315943Y1712203
X1315943Y1707666
X1315943Y1702564
X1315943Y1716737
X1296258Y1712203
X1296258Y1707666
X1296258Y1702564
X1296258Y1716737
X1288384Y1703729
X1288384Y1708266
X1288384Y1712800
X1280510Y1712203
X1280510Y1707666
X1280510Y1702564
X1280510Y1716737
X1272636Y1703729
X1272636Y1708266
X1272636Y1712800
X1264762Y1712203
X1264762Y1707666
X1264762Y1702564
X1264762Y1716737
X1256888Y1708266
X1256888Y1712800
X1249014Y1712203
X1249014Y1707666
X1249014Y1702564
X1249014Y1716737
X1256888Y1703729
X1241140Y1703729
X1241140Y1708266
X1241140Y1712800
X0619487Y1712203
X0619487Y1707666
X0619487Y1702564
X0619487Y1716737
X0611613Y1703729
X0611613Y1708266
X0611613Y1712800
X0595865Y1703729
X0595865Y1708266
X0595865Y1712800
X0603739Y1712203
X0603739Y1707666
X0603739Y1702564
X0603739Y1716737
X0580117Y1703729
X0580117Y1708266
X0580117Y1712800
X0587991Y1712203
X0587991Y1707666
X0587991Y1702564
X0587991Y1716737
X0572243Y1716737
X0564369Y1703729
X0564369Y1708266
X0564369Y1712800
X0572243Y1712203
X0572243Y1707666
X0572243Y1702564
X0552558Y1712203
X0552558Y1707666
X0552558Y1702564
X0552558Y1716737
X0544684Y1703729
X0544684Y1708266
X0544684Y1712800
X0536810Y1712203
X0536810Y1707666
X0536810Y1702564
X0536810Y1716737
X0528936Y1703729
X0528936Y1708266
X0528936Y1712800
X0521062Y1712203
X0521062Y1707666
X0521062Y1702564
X0521062Y1716737
X0505314Y1702564
X0505314Y1716737
X0513188Y1703729
X0513188Y1708266
X0513188Y1712800
X0505314Y1712203
X0505314Y1707666
X0497440Y1703729
X0497440Y1708266
X0497440Y1712800
X0355314Y1702564
X0355314Y1707666
X0355314Y1712203
X0355314Y1716737
X0339566Y1702564
X0339566Y1707666
X0339566Y1712203
X0339566Y1716737
X0347440Y1712800
X0347440Y1708266
X0347440Y1703729
X0323818Y1702564
X0323818Y1707666
X0323818Y1712203
X0323818Y1716737
X0331692Y1712800
X0331692Y1708266
X0331692Y1703729
X0308070Y1702564
X0308070Y1707666
X0308070Y1712203
X0308070Y1716737
X0315944Y1712800
X0315944Y1708266
X0315944Y1703729
X0300196Y1712800
X0300196Y1708266
X0300196Y1703729
X0280511Y1703729
X0280511Y1708266
X0280511Y1712800
X0288385Y1707667
X0288385Y1702565
X0288385Y1716738
X0288385Y1712204
X0264763Y1703729
X0264763Y1708266
X0264763Y1712800
X0272637Y1716737
X0272637Y1712203
X0272637Y1707666
X0272637Y1702564
X0249015Y1703729
X0249015Y1708266
X0249015Y1712800
X0256889Y1716737
X0256889Y1712203
X0256889Y1707666
X0256889Y1702564
X0233267Y1712800
X0233267Y1708266
X0233267Y1703729
X0241141Y1716737
X0241141Y1712203
X0241141Y1707666
X0241141Y1702564
X1619487Y1689556
X1619487Y1694093
X1619487Y1698627
X1627361Y1698030
X1627361Y1693493
X1627361Y1688391
X1603739Y1689556
X1603739Y1694093
X1603739Y1698627
X1611613Y1698030
X1611613Y1693493
X1611613Y1688391
X1595865Y1698030
X1595865Y1693493
X1595865Y1688391
X1587991Y1689556
X1587991Y1694093
X1587991Y1698627
X1580117Y1698030
X1580117Y1693493
X1580117Y1688391
X1560431Y1698030
X1560431Y1693493
X1560431Y1688391
X1572243Y1689556
X1572243Y1694093
X1572243Y1698627
X1552557Y1689556
X1552557Y1694093
X1552557Y1698627
X1544683Y1698030
X1544683Y1693493
X1544683Y1688391
X1536809Y1689556
X1536809Y1694093
X1536809Y1698627
X1528935Y1698030
X1528935Y1693493
X1528935Y1688391
X1521061Y1689556
X1521061Y1694093
X1521061Y1698627
X1505313Y1689556
X1505313Y1694093
X1505313Y1698627
X1513187Y1698030
X1513187Y1693493
X1513187Y1688391
X1355313Y1698627
X1363187Y1698030
X1363187Y1693493
X1363187Y1688391
X1355313Y1689556
X1355313Y1694093
X1339565Y1689556
X1339565Y1694093
X1339565Y1698627
X1347439Y1698030
X1347439Y1693493
X1347439Y1688391
X1323817Y1689556
X1323817Y1694093
X1323817Y1698627
X1331691Y1698030
X1331691Y1693493
X1331691Y1688391
X1308069Y1689556
X1308069Y1694093
X1308069Y1698627
X1315943Y1698030
X1315943Y1693493
X1315943Y1688391
X1296258Y1698030
X1296258Y1693493
X1296258Y1688391
X1288384Y1689556
X1288384Y1694093
X1288384Y1698627
X1280510Y1698030
X1280510Y1693493
X1280510Y1688391
X1272636Y1689556
X1272636Y1694093
X1272636Y1698627
X1264762Y1698030
X1264762Y1693493
X1264762Y1688391
X1256888Y1689556
X1256888Y1694093
X1256888Y1698627
X1249014Y1698030
X1249014Y1693493
X1249014Y1688391
X1241140Y1689556
X1241140Y1694093
X1241140Y1698627
X0619487Y1698030
X0619487Y1693493
X0619487Y1688391
X0611613Y1689556
X0611613Y1694093
X0611613Y1698627
X0595865Y1689556
X0595865Y1694093
X0595865Y1698627
X0603739Y1698030
X0603739Y1693493
X0603739Y1688391
X0580117Y1689556
X0580117Y1694093
X0580117Y1698627
X0587991Y1698030
X0587991Y1693493
X0587991Y1688391
X0564369Y1698627
X0572243Y1698030
X0572243Y1693493
X0572243Y1688391
X0564369Y1689556
X0564369Y1694093
X0552558Y1698030
X0552558Y1693493
X0552558Y1688391
X0544684Y1689556
X0544684Y1694093
X0544684Y1698627
X0536810Y1698030
X0536810Y1693493
X0536810Y1688391
X0528936Y1689556
X0528936Y1694093
X0528936Y1698627
X0521062Y1698030
X0521062Y1693493
X0521062Y1688391
X0513188Y1689556
X0513188Y1694093
X0513188Y1698627
X0505314Y1698030
X0505314Y1693493
X0505314Y1688391
X0497440Y1689556
X0497440Y1694093
X0497440Y1698627
X0355314Y1693493
X0355314Y1698030
X0355314Y1688391
X0347440Y1689556
X0339566Y1688391
X0339566Y1693493
X0339566Y1698030
X0347440Y1698627
X0347440Y1694093
X0323818Y1688391
X0323818Y1693493
X0323818Y1698030
X0331692Y1698627
X0331692Y1694093
X0331692Y1689556
X0308070Y1688391
X0308070Y1693493
X0308070Y1698030
X0315944Y1698627
X0315944Y1694093
X0315944Y1689556
X0300196Y1698627
X0300196Y1694093
X0300196Y1689556
X0280511Y1689556
X0280511Y1694093
X0280511Y1698627
X0288385Y1698031
X0288385Y1693494
X0288385Y1688391
X0264763Y1689556
X0264763Y1694093
X0264763Y1698627
X0272637Y1698030
X0272637Y1693493
X0272637Y1688391
X0249015Y1689556
X0249015Y1694093
X0249015Y1698627
X0256889Y1698030
X0256889Y1693493
X0256889Y1688391
X0233267Y1698627
X0233267Y1694093
X0233267Y1689556
X0241141Y1698030
X0241141Y1693493
X0241141Y1688391
X1619487Y1675383
X1619487Y1679920
X1619487Y1684454
X1627361Y1683857
X1627361Y1679320
X1603739Y1675383
X1603739Y1679920
X1603739Y1684454
X1611613Y1683857
X1611613Y1679320
X1595865Y1683857
X1595865Y1679320
X1587991Y1675383
X1587991Y1679920
X1587991Y1684454
X1580117Y1683857
X1580117Y1679320
X1560431Y1683857
X1560431Y1679320
X1572243Y1675383
X1572243Y1679920
X1572243Y1684454
X1552557Y1675383
X1552557Y1679920
X1552557Y1684454
X1544683Y1683857
X1544683Y1679320
X1536809Y1675383
X1536809Y1679920
X1536809Y1684454
X1528935Y1683857
X1528935Y1679320
X1521061Y1675383
X1521061Y1679920
X1521061Y1684454
X1505313Y1675383
X1505313Y1679920
X1505313Y1684454
X1513187Y1683857
X1513187Y1679320
X1355313Y1675383
X1355313Y1679920
X1355313Y1684454
X1363187Y1683857
X1363187Y1679320
X1339565Y1675383
X1339565Y1679920
X1339565Y1684454
X1347439Y1683857
X1347439Y1679320
X1323817Y1675383
X1323817Y1679920
X1323817Y1684454
X1331691Y1683857
X1331691Y1679320
X1308069Y1675383
X1308069Y1679920
X1308069Y1684454
X1315943Y1683857
X1315943Y1679320
X1296258Y1683857
X1296258Y1679320
X1288384Y1675383
X1288384Y1679920
X1288384Y1684454
X1280510Y1683857
X1280510Y1679320
X1272636Y1675383
X1272636Y1679920
X1272636Y1684454
X1264762Y1683857
X1264762Y1679320
X1256888Y1675383
X1256888Y1679920
X1256888Y1684454
X1249014Y1683857
X1249014Y1679320
X1241140Y1675383
X1241140Y1679920
X1241140Y1684454
X0619487Y1683857
X0619487Y1679320
X0611613Y1675383
X0611613Y1679920
X0611613Y1684454
X0595865Y1675383
X0595865Y1679920
X0595865Y1684454
X0603739Y1683857
X0603739Y1679320
X0580117Y1675383
X0580117Y1679920
X0580117Y1684454
X0587991Y1683857
X0587991Y1679320
X0572243Y1679320
X0564369Y1675383
X0564369Y1679920
X0564369Y1684454
X0572243Y1683857
X0552558Y1683857
X0552558Y1679320
X0544684Y1675383
X0544684Y1679920
X0544684Y1684454
X0536810Y1683857
X0536810Y1679320
X0528936Y1675383
X0528936Y1679920
X0528936Y1684454
X0521062Y1683857
X0521062Y1679320
X0513188Y1675383
X0513188Y1679920
X0513188Y1684454
X0505314Y1683857
X0505314Y1679320
X0497440Y1675383
X0497440Y1679920
X0497440Y1684454
X0355314Y1679320
X0355314Y1683857
X0339566Y1679320
X0339566Y1683857
X0347440Y1684454
X0347440Y1679920
X0347440Y1675383
X0323818Y1679320
X0323818Y1683857
X0331692Y1684454
X0331692Y1679920
X0331692Y1675383
X0308070Y1679320
X0308070Y1683857
X0315944Y1684454
X0315944Y1679920
X0315944Y1675383
X0300196Y1684454
X0300196Y1679920
X0300196Y1675383
X0280511Y1675383
X0280511Y1679920
X0280511Y1684454
X0288385Y1679320
X0288385Y1683857
X0264763Y1675383
X0264763Y1679920
X0264763Y1684454
X0272637Y1683857
X0272637Y1679320
X0249015Y1675383
X0249015Y1679920
X0249015Y1684454
X0256889Y1683857
X0256889Y1679320
X0233267Y1684454
X0233267Y1679920
X0233267Y1675383
X0241141Y1683857
X0241141Y1679320
X0451254Y1528853
X0455978Y1528853
X0460703Y1528853
R02X0004724
X0474876Y1528853
X0479600Y1528853
X0484325Y1528853
R02X0004724
X0498498Y1528853
X0503222Y1528853
X0507947Y1528853
X0512671Y1528853
X0517396Y1528853
X0522120Y1528853
X0450703Y1521453
X0455427Y1521453
X0460152Y1521453
R02X0004724
X0474325Y1521453
X0479049Y1521453
X0483774Y1521453
R02X0004724
X0497947Y1521453
X0502671Y1521453
X0507396Y1521453
X0512120Y1521453
X0516845Y1521453
X0521569Y1521453
X0526314Y1521453
X0517175Y1514243
X0469651Y1536063
X0474375Y1536063
X0483824Y1536063
X0493273Y1536063
X0497997Y1536063
R02X0009449
X0579316Y1528853
X0584040Y1528853
X0588765Y1528853
R02X0004724
X0602938Y1528853
X0607662Y1528853
X0612387Y1528853
R02X0004724
X0626560Y1528853
X0631284Y1528853
X0636009Y1528853
X0640733Y1528853
X0645458Y1528853
X0650182Y1528853
X0578765Y1521453
X0583489Y1521453
X0588214Y1521453
R02X0004724
X0602387Y1521453
X0607111Y1521453
X0611836Y1521453
R02X0004724
X0626009Y1521453
X0630733Y1521453
X0635458Y1521453
X0640182Y1521453
X0644907Y1521453
X0649631Y1521453
X0654376Y1521453
X0645237Y1514243
X0597713Y1536063
X0602437Y1536063
X0611886Y1536063
X0621335Y1536063
X0626059Y1536063
R02X0009449
X1194954Y1561853
X1199678Y1561853
X1204403Y1561853
R02X0004724
X1218576Y1561853
X1223300Y1561853
X1228025Y1561853
R02X0004724
X1242198Y1561853
X1246922Y1561853
X1251647Y1561853
X1256371Y1561853
X1261096Y1561853
X1265820Y1561853
X1194403Y1554453
X1199127Y1554453
X1203852Y1554453
R02X0004724
X1218025Y1554453
X1222749Y1554453
X1227474Y1554453
R02X0004724
X1241647Y1554453
X1246371Y1554453
X1251096Y1554453
X1255820Y1554453
X1260545Y1554453
X1265269Y1554453
X1270014Y1554453
X1260875Y1547243
X1213351Y1569063
X1218075Y1569063
X1227524Y1569063
X1236973Y1569063
X1241697Y1569063
R02X0009449
X1323016Y1561853
X1327740Y1561853
X1332465Y1561853
R02X0004724
X1346638Y1561853
X1351362Y1561853
X1356087Y1561853
R02X0004724
X1370260Y1561853
X1374984Y1561853
X1379709Y1561853
X1384433Y1561853
X1389158Y1561853
X1393882Y1561853
X1322465Y1554453
X1327189Y1554453
X1331914Y1554453
R02X0004724
X1346087Y1554453
X1350811Y1554453
X1355536Y1554453
R02X0004724
X1369709Y1554453
X1374433Y1554453
X1379158Y1554453
X1383882Y1554453
X1388607Y1554453
X1393331Y1554453
X1398076Y1554453
X1388937Y1547243
X1341413Y1569063
X1346137Y1569063
X1355586Y1569063
X1365035Y1569063
X1369759Y1569063
R02X0009449
X1459128Y1561853
X1463852Y1561853
X1468577Y1561853
R02X0004724
X1482750Y1561853
X1487474Y1561853
X1492199Y1561853
R02X0004724
X1506372Y1561853
X1511096Y1561853
X1515821Y1561853
X1520545Y1561853
X1525270Y1561853
X1529994Y1561853
X1458577Y1554453
X1463301Y1554453
X1468026Y1554453
R02X0004724
X1482199Y1554453
X1486923Y1554453
X1491648Y1554453
R02X0004724
X1505821Y1554453
X1510545Y1554453
X1515270Y1554453
X1519994Y1554453
X1524719Y1554453
X1529443Y1554453
X1534188Y1554453
X1525049Y1547243
X1477525Y1569063
X1482249Y1569063
X1491698Y1569063
X1501147Y1569063
X1505871Y1569063
R02X0009449
X1587190Y1561853
X1591914Y1561853
X1596639Y1561853
R02X0004724
X1610812Y1561853
X1615536Y1561853
X1620261Y1561853
R02X0004724
X1634434Y1561853
X1639158Y1561853
X1643883Y1561853
X1648607Y1561853
X1653332Y1561853
X1658056Y1561853
X1586639Y1554453
X1591363Y1554453
X1596088Y1554453
R02X0004724
X1610261Y1554453
X1614985Y1554453
X1619710Y1554453
R02X0004724
X1633883Y1554453
X1638607Y1554453
X1643332Y1554453
X1648056Y1554453
X1652781Y1554453
X1657505Y1554453
X1662250Y1554453
X1653111Y1547243
X1605587Y1569063
X1610311Y1569063
X1619760Y1569063
X1629209Y1569063
X1633933Y1569063
R02X0009449
X0484467Y0930647
X1371815Y0930646
X0473365Y0917891
X1382918Y0917890
X0473365Y0911513
X1382918Y0911512
X0473365Y0924269
X1382918Y0924268
X0462263Y0917891
X1394020Y0917890
X0462263Y0911513
X1394020Y0911512
X0462263Y0924269
X1394020Y0924268
X0453011Y0914702
X1403272Y0914701
X0453011Y0921080
X1403272Y0921079
X0495570Y0924269
X1360713Y0924268
X0495570Y0917891
X1360713Y0917890
X0495570Y0930647
X1360713Y0930646
X0484467Y0924269
X1371815Y0924268
X0484467Y0917891
X1371815Y0917890
X0484467Y0911513
X1371815Y0911512
X0453011Y0927458
X1403272Y0927457
X0480767Y0930647
X1375516Y0930646
X0469664Y0917891
X1386619Y0917890
X0469664Y0911513
X1386619Y0911512
X0469664Y0924269
X1386619Y0924268
X0458562Y0917891
X1397721Y0917890
X0458562Y0911513
X1397721Y0911512
X0458562Y0924269
X1397721Y0924268
X0449310Y0914702
X1406973Y0914701
X0449310Y0921080
X1406973Y0921079
X0491869Y0924269
X1364414Y0924268
X0491869Y0917891
X1364414Y0917890
X0491869Y0930647
X1364414Y0930646
X0480767Y0924269
X1375516Y0924268
X0480767Y0917891
X1375516Y0917890
X0480767Y0911513
X1375516Y0911512
X0449310Y0927458
X1406973Y0927457
X0484467Y0905135
X1371815Y0905134
X0473365Y0898758
X1382918Y0898757
X0473365Y0892380
X1382918Y0892379
X0473365Y0905135
X1382918Y0905134
X0462263Y0898758
X1394020Y0898757
X0462263Y0892380
X1394020Y0892379
X0462263Y0905135
X1394020Y0905134
X0453011Y0895569
X1403272Y0895568
X0453011Y0901947
X1403272Y0901946
X0495570Y0911513
X1360713Y0911512
X0495570Y0898758
X1360713Y0898757
X0495570Y0892380
X1360713Y0892379
X0495570Y0905135
X1360713Y0905134
X0484467Y0898758
X1371815Y0898757
X0484467Y0892380
X1371815Y0892379
X0453011Y0908325
X1403272Y0908324
X0480767Y0905135
X1375516Y0905134
X0469664Y0898758
X1386619Y0898757
X0469664Y0892380
X1386619Y0892379
X0469664Y0905135
X1386619Y0905134
X0458562Y0898758
X1397721Y0898757
X0458562Y0892380
X1397721Y0892379
X0458562Y0905135
X1397721Y0905134
X0449310Y0895569
X1406973Y0895568
X0449310Y0901947
X1406973Y0901946
X0491869Y0911513
X1364414Y0911512
X0491869Y0898758
X1364414Y0898757
X0491869Y0892380
X1364414Y0892379
X0491869Y0905135
X1364414Y0905134
X0480767Y0898758
X1375516Y0898757
X0480767Y0892380
X1375516Y0892379
X0449310Y0908325
X1406973Y0908324
X0421579Y0949781
X1434704Y0949780
X0410477Y0956159
X1445806Y0956158
X0410477Y0943403
X1445806Y0943402
X0410477Y0949781
X1445806Y0949780
X0399374Y0956159
X1456909Y0956158
X0399374Y0943403
X1456909Y0943402
X0399374Y0949781
X1456909Y0949780
X0388272Y0956159
X1468011Y0956158
X0388272Y0943403
X1468011Y0943402
X0430831Y0952970
X1425452Y0952969
X0430831Y0946592
X1425452Y0946591
X0430831Y0940214
X1425452Y0940213
X0421579Y0956159
X1434704Y0956158
X0421579Y0937025
X1434704Y0937024
X0421579Y0943403
X1434704Y0943402
X0388272Y0949781
X1468011Y0949780
X0417878Y0949781
X1438405Y0949780
X0406776Y0956159
X1449507Y0956158
X0406776Y0943403
X1449507Y0943402
X0406776Y0949781
X1449507Y0949780
X0395673Y0956159
X1460609Y0956158
X0395673Y0943403
X1460609Y0943402
X0395673Y0949781
X1460609Y0949780
X0384571Y0956159
X1471712Y0956158
X0384571Y0943403
X1471712Y0943402
X0427130Y0952970
X1429153Y0952969
X0427130Y0946592
X1429153Y0946591
X0427130Y0940214
X1429153Y0940213
X0417878Y0956159
X1438405Y0956158
X0417878Y0937025
X1438405Y0937024
X0417878Y0943403
X1438405Y0943402
X0384571Y0949781
X1471712Y0949780
X0406776Y0924269
X0406776Y0911513
X0406776Y0917891
X0395673Y0930647
X0395673Y0911513
X0395673Y0917891
X0395673Y0924269
X0384571Y0930647
X0384571Y0917891
X0427130Y0927458
R02Y-0006378
X0417878Y0924269
X0417878Y0911513
X0417878Y0917891
X0384571Y0924269
X0410477Y0924269
X0410477Y0911513
X0410477Y0917891
X0399374Y0930647
X0399374Y0911513
X0399374Y0917891
X0399374Y0924269
X0388272Y0930647
X0388272Y0917891
X0430831Y0927458
R02Y-0006378
X0421579Y0924269
X0421579Y0911513
X0421579Y0917891
X0388272Y0924269
X0406776Y0905135
X1449507Y0905134
X0406776Y0892380
X1449507Y0892379
X0406776Y0898758
X1449507Y0898757
X0395673Y0905135
X1460609Y0905134
X0395673Y0892380
X1460609Y0892379
X0395673Y0898758
X1460609Y0898757
X0384571Y0905135
X1471712Y0905134
X0384571Y0892380
X1471712Y0892379
X0384571Y0898758
X1471712Y0898757
X0427130Y0908325
X1429153Y0908324
X0427130Y0901947
X1429153Y0901946
X0427130Y0895569
X1429153Y0895568
X0417878Y0905135
X1438405Y0905134
X0417878Y0892380
X1438405Y0892379
X0417878Y0898758
X1438405Y0898757
X0384571Y0911513
X1471712Y0911512
X0410477Y0905135
X1445806Y0905134
X0410477Y0892380
X1445806Y0892379
X0410477Y0898758
X1445806Y0898757
X0399374Y0905135
X1456909Y0905134
X0399374Y0892380
X1456909Y0892379
X0399374Y0898758
X1456909Y0898757
X0388272Y0905135
X1468011Y0905134
X0388272Y0892380
X1468011Y0892379
X0388272Y0898758
X1468011Y0898757
X0430831Y0908325
X1425452Y0908324
X0430831Y0901947
X1425452Y0901946
X0430831Y0895569
X1425452Y0895568
X0421579Y0905135
X1434704Y0905134
X0421579Y0892380
X1434704Y0892379
X0421579Y0898758
X1434704Y0898757
X0388272Y0911513
X1468011Y0911512
X0469664Y0968915
X1386619Y0968914
X0469664Y0962537
X1386619Y0962536
X0469664Y0975293
X1386619Y0975292
X0458562Y0968915
X1397721Y0968914
X0458562Y0962537
X1397721Y0962536
X0458562Y0975293
X1397721Y0975292
X0449310Y0965726
X1406973Y0965725
X0449310Y0959348
X1406973Y0959347
X0449310Y0972104
X1406973Y0972103
X0491869Y0968915
X1364414Y0968914
X0491869Y0962537
X1364414Y0962536
X0491869Y0975293
X1364414Y0975292
X0480767Y0968915
X1375516Y0968914
X0480767Y0962537
X1375516Y0962536
X0480767Y0975293
X1375516Y0975292
X0449310Y0978482
X1406973Y0978481
X0473365Y0968915
X1382918Y0968914
X0473365Y0962537
X1382918Y0962536
X0473365Y0975293
X1382918Y0975292
X0462263Y0968915
X1394020Y0968914
X0462263Y0962537
X1394020Y0962536
X0462263Y0975293
X1394020Y0975292
X0453011Y0965726
X1403272Y0965725
X0453011Y0959348
X1403272Y0959347
X0453011Y0972104
X1403272Y0972103
X0495570Y0968915
X1360713Y0968914
X0495570Y0962537
X1360713Y0962536
X0495570Y0975293
X1360713Y0975292
X0484467Y0968915
X1371815Y0968914
X0484467Y0962537
X1371815Y0962536
X0484467Y0975293
X1371815Y0975292
X0453011Y0978482
X1403272Y0978481
X0469664Y0949781
X1386619Y0949780
X0469664Y0943403
X1386619Y0943402
X0469664Y0956159
X1386619Y0956158
X0458562Y0949781
X1397721Y0949780
X0458562Y0943403
X1397721Y0943402
X0458562Y0937025
X1397721Y0937024
X0458562Y0956159
X1397721Y0956158
X0449310Y0940214
X1406973Y0940213
X0449310Y0946592
X1406973Y0946591
X0491869Y0949781
X1364414Y0949780
X0491869Y0943403
X1364414Y0943402
X0491869Y0956159
X1364414Y0956158
X0480767Y0949781
X1375516Y0949780
X0480767Y0943403
X1375516Y0943402
X0480767Y0956159
X1375516Y0956158
X0449310Y0952970
X1406973Y0952969
X0473365Y0949781
X1382918Y0949780
X0473365Y0943403
X1382918Y0943402
X0473365Y0956159
X1382918Y0956158
X0462263Y0949781
X1394020Y0949780
X0462263Y0943403
X1394020Y0943402
X0462263Y0937025
X1394020Y0937024
X0462263Y0956159
X1394020Y0956158
X0453011Y0940214
X1403272Y0940213
X0453011Y0946592
X1403272Y0946591
X0495570Y0949781
X1360713Y0949780
X0495570Y0943403
X1360713Y0943402
X0495570Y0956159
X1360713Y0956158
X0484467Y0949781
X1371815Y0949780
X0484467Y0943403
X1371815Y0943402
X0484467Y0956159
X1371815Y0956158
X0453011Y0952970
X1403272Y0952969
X1426633Y1155614
X0315437Y1158804
X0499271Y0879624
X1291579Y1158803
X1475413Y0879623
X1465491Y1158803
X1467342Y1155614
X1469192Y1152425
X1471043Y1161992
X1471043Y1155614
X0496751Y1050379
X0546712Y1161993
X0510373Y0879624
X0567066Y1158804
X0374650Y1165182
X0378351Y1165182
X0450491Y1161993
X0467145Y1165182
X0528208Y1161993
X0327209Y0882813
X1316304Y0879623
X1312603Y0879623
X1424783Y1152425
X1305201Y0879623
X1486515Y0879623
X1543208Y1158803
X1439586Y1158803
X1426633Y1161992
X1533956Y1161992
X1318154Y0876434
X1443287Y1165181
X1321855Y0876434
X1454389Y1158803
X1476778Y1165778
X1303351Y0882812
X1299650Y0876434
X1297800Y0879623
X1327406Y0879623
X1323705Y0879623
X1472893Y1158803
X1446987Y1152425
M00
X1898799Y1800398
X1898799Y1810398
X1908799Y1810398
X1908799Y1800398
X1908799Y1208198
X1908799Y1198198
X1898799Y1198198
X1898799Y1208198
X1910275Y0562227
X1910275Y0572227
X1900275Y0572227
X1900275Y0562227
X1900275Y-0029973
X1900275Y-0039973
X1910275Y-0039973
X1910275Y-0029973
X1931395Y-0029963
X1931395Y-0039963
X1921395Y-0039963
X1921395Y-0029963
X1973362Y-0029821
X1973362Y-0039821
X1963362Y-0039821
X1963362Y-0029821
X1984482Y-0029811
X1984482Y-0039811
X1994482Y-0039811
X1994482Y-0029811
X1942395Y-0029783
X1942395Y-0039783
X1952395Y-0039783
X1952395Y-0029783
X1952395Y0582417
X1952395Y0572417
X1942395Y0572417
X1942395Y0582417
X1921395Y0582237
X1921395Y0572237
X1931395Y0572237
X1931395Y0582237
X1994482Y0582389
X1994482Y0572389
X1984482Y0572389
X1984482Y0582389
X2005452Y0582389
X2005452Y0572389
X2015452Y0572389
X2015452Y0582389
X1963362Y0582379
X1963362Y0572379
X1973362Y0572379
X1973362Y0582379
X1963362Y0562379
X1963362Y0572379
X1973362Y0572379
X1973362Y0562379
X2005452Y0562389
X2005452Y0572389
X2015452Y0572389
X2015452Y0562389
X1921395Y0562237
X1921395Y0572237
X1931395Y0572237
X1931395Y0562237
X1994482Y0562389
X1994482Y0572389
X1984482Y0572389
X1984482Y0562389
X1952395Y0562417
X1952395Y0572417
X1942395Y0572417
X1942395Y0562417
X1984482Y1174589
X1984482Y1184589
X1994482Y1184589
X1994482Y1174589
X1942395Y1174617
X1942395Y1184617
X1952395Y1184617
X1952395Y1174617
X1931395Y1174437
X1931395Y1184437
X1921395Y1184437
X1921395Y1174437
X1973362Y1174579
X1973362Y1184579
X1963362Y1184579
X1963362Y1174579
X1992856Y1208350
X1992856Y1198350
X1982856Y1198350
X1982856Y1208350
X1950886Y1208170
X1950886Y1198170
X1940886Y1198170
X1940886Y1208170
X2003823Y1208312
X2003823Y1198312
X2013823Y1198312
X2013823Y1208312
X1961856Y1208170
X1961856Y1198170
X1971856Y1198170
X1971856Y1208170
X1919766Y1208160
X1919766Y1198160
X1929766Y1198160
X1929766Y1208160
X1982856Y1800550
X1982856Y1810550
X1992856Y1810550
X1992856Y1800550
X1940886Y1800370
X1940886Y1810370
X1950886Y1810370
X1950886Y1800370
X1929766Y1800360
X1929766Y1810360
X1919766Y1810360
X1919766Y1800360
X1971856Y1800370
X1971856Y1810370
X1961856Y1810370
X1961856Y1800370
X2013823Y1800512
X2013823Y1810512
X2003823Y1810512
X2003823Y1800512
X2068539Y1174741
X2068539Y1184741
X2078539Y1184741
X2078539Y1174741
X2026452Y1174769
X2026452Y1184769
X2036452Y1184769
X2036452Y1174769
X2057419Y1174731
X2057419Y1184731
X2047419Y1184731
X2047419Y1174731
X2015452Y1174589
X2015452Y1184589
X2005452Y1184589
X2005452Y1174589
X2036452Y0582569
X2036452Y0572569
X2026452Y0572569
X2026452Y0582569
X2047419Y0582531
X2047419Y0572531
X2057419Y0572531
X2057419Y0582531
X2078539Y0582541
X2078539Y0572541
X2068539Y0572541
X2068539Y0582541
X2047419Y0562531
X2047419Y0572531
X2057419Y0572531
X2057419Y0562531
X2036452Y0562569
X2036452Y0572569
X2026452Y0572569
X2026452Y0562569
X2057419Y-0029669
X2057419Y-0039669
X2047419Y-0039669
X2047419Y-0029669
X2015452Y-0029811
X2015452Y-0039811
X2005452Y-0039811
X2005452Y-0029811
X2026452Y-0029631
X2026452Y-0039631
X2036452Y-0039631
X2036452Y-0029631
M00
X1053290Y1652082
X0266360Y0203070
X0269925Y0217700
X0864826Y0411557
X0848500Y0452128
X0189290Y0396730
X0185160Y0419220
X0181550Y0441290
X0177675Y0419260
X0172010Y0474900
X0162830Y0396930
X0158380Y0419760
X0154770Y0441830
X0147450Y0423860
X0147810Y0475710
X0749260Y0456074
X0807127Y0770958
X1792692Y0770217
X0786850Y0770218
X1762992Y0770217
X0757149Y0770218
X1733291Y0770217
X0727448Y0770218
X1703590Y0770217
X0697747Y0770218
X1673889Y0770217
X0668046Y0770218
X1644188Y0770217
X0090015Y0770218
X1066157Y0770217
X0119716Y0770218
X1095858Y0770217
X0149416Y0770218
X1125558Y0770217
X0179117Y0770218
X1155259Y0770217
X0208818Y0770218
X1184960Y0770217
X0238519Y0770218
X1214841Y0772277
X1096768Y1635080
X0404661Y1634139
X1097000Y1629500
X0405747Y1623350
X0709150Y1536250
X1709964Y1597490
X0703290Y1545100
X1709833Y1606340
X0643300Y1674805
X0707050Y1531700
X0372953Y1653197
X0184139Y1651088
X1686675Y1659287
X1715693Y1597190
X1416862Y1582871
X1205604Y1675800
X0640600Y1674805
X0707050Y1541800
X0374962Y1648511
X0183920Y1653973
X1680367Y1663367
X1713593Y1603040
X1413836Y1586944
X1205604Y1679000
X0645190Y1595050
X0650200Y1674805
X0707050Y1548400
X0371823Y1644516
X0183974Y1656804
X1675290Y1663157
X1713593Y1609640
X1416709Y1592819
X1205604Y1682200
X0645180Y1597800
X0647500Y1674805
X0703290Y1551700
X0375050Y1639400
X0183986Y1659548
X1670202Y1663150
X1709833Y1612940
X1205604Y1685400
X1676685Y1537893
X0955000Y1287000
X1071667Y0467000
X0954362Y0630061
X0955000Y1283000
X1071667Y0471500
X0954362Y0633314
X0260596Y0151065
X0071659Y0149191
X0735500Y0399330
X0679035Y0204181
X1756933Y0372452
X1536422Y0292816
X0837847Y0405347
X1006763Y0396206
X1010252Y0363440
X0761858Y0418358
X0824653Y0405347
X1099500Y0318000
X0703477Y0369409
X0673011Y0169021
X0847581Y0232222
X1260107Y0399125
X0708584Y0404868
X0724143Y0424657
X1289352Y0421950
X0964807Y0205125
X0961407Y0205125
X1289352Y0418550
X0100818Y0168906
X0278638Y0083024
X0100818Y0165506
X0275238Y0083024
X1743491Y0092827
X1564506Y0313734
X1564506Y0310334
X1740091Y0092827
X0655683Y1664212
X0689538Y1427467
X0875039Y1407246
X0661731Y1561083
X0658648Y1664169
X0874989Y1410441
X0691587Y1429515
X0664246Y1561009
X0640846Y1665189
X0450180Y1614950
X0647460Y1662952
X0450500Y1612450
X0631643Y1670946
X0883379Y1417881
X0883279Y1421726
X0633422Y1673488
X0446910Y1562098
X0931216Y1323050
X0446810Y1565020
X0931326Y1328467
X0421277Y1571923
X0935028Y1313769
X0419254Y1566828
X0935300Y1317525
X0389276Y1568413
X0173490Y1542540
X0163320Y1494340
X0387939Y1565534
X0170230Y1542960
X0163460Y1491010
X0980779Y1451545
X1012500Y1328500
X1427713Y1553652
X1466111Y1685098
X0975703Y1451367
X1430213Y1553652
X1470500Y1685500
X1012500Y1322500
X1013529Y1318950
X1716070Y1472037
X0973255Y1456714
X1669377Y1675241
X1013605Y1316050
X0969519Y1452784
X1722347Y1471246
X1671902Y1676267
X1013500Y1337160
X1154336Y1555979
X1157255Y1556000
X1013500Y1332740
X1161492Y1551175
X1297620Y1529534
X1297490Y1526910
X1163485Y1546195
X1012500Y1347500
X1181385Y1670312
X1012500Y1341580
X1184362Y1670254
X1275585Y0393597
X0082026Y0143491
X0582002Y0197481
X0087137Y0143663
X0071775Y0153194
X0092197Y0143853
X0582124Y0194150
X1548772Y0291916
X1536538Y0296819
X1546789Y0287116
X1181000Y0402500
X1551900Y0287288
X1174031Y0403519
X1556960Y0287478
X0289163Y0212503
X0331780Y0182900
X0827000Y0489055
X0964669Y1271000
X0917034Y1288235
X0966441Y1278145
X0916945Y1296713
X0963500Y1275000
X0916895Y1292330
X0917112Y1266300
X0978318Y1263128
X0917341Y1283775
X0964000Y1267000
X0988242Y1273193
X0917158Y1279451
X0982665Y1265474
X0917396Y1271025
X0917127Y1275251
X0985396Y1268154
X0265365Y0049171
X0257516Y0051565
X0248816Y0048965
X0269860Y0072741
X0261816Y0048965
X0263516Y0051565
X0250516Y0051565
X0254016Y0051565
X0255816Y0048965
X0252316Y0048965
X0261016Y0051565
X0259316Y0048965
X0419617Y0308000
X0627880Y0455310
X0308240Y0148100
X0233284Y0137195
X0270178Y0140322
X0497885Y0051315
X0617420Y0119640
X0827341Y0415344
X0818157Y0381020
X1723241Y0048822
X1737617Y0081640
X1737617Y0079140
X1737617Y0073140
X1737617Y0075640
X1738093Y0055603
X1738093Y0053103
X1730241Y0048822
X1726741Y0048822
X1729895Y0051354
X1727225Y0051424
X1724685Y0051454
X1736006Y0044338
X1736006Y0041838
X1621680Y0366920
X1615020Y0183050
X1788950Y0142750
X0593758Y0415850
X1850791Y0170287
X1760124Y0128246
X1650035Y0434750
X0962673Y0167763
X0962673Y0170263
X0948401Y0176499
X0940721Y0176389
X0940721Y0173389
X0935591Y0176049
X0938161Y0176389
X0938161Y0173389
X0935551Y0173329
X0945721Y0176389
X0943221Y0176389
X0943221Y0173389
X0945721Y0173389
X0426947Y0320749
X0680488Y0504784
X0711544Y0465523
X0652954Y0394284
X0670000Y0446362
X1259659Y0389456
X1269840Y0411128
X0181025Y0159123
X0066650Y0265316
X0605769Y0442593
X0659918Y0326503
X1822394Y0436225
X0792302Y0357537
X0702095Y0474971
X0555727Y0479968
X0537051Y0211959
X0338244Y0192264
X0292811Y0213242
X0845801Y1287776
X0844250Y1266759
X0652763Y0427866
X0627925Y0421966
X1732251Y1708265
X0825061Y0764884
X0652576Y0497964
X0750168Y0675833
X0747500Y0374362
X0752187Y1691058
X0768463Y1687769
X0697018Y0537577
X0708395Y0481271
X0705245Y0478121
X0698946Y0465523
X0682915Y0500568
X0761858Y0446705
X1488875Y1677385
X1656101Y1701094
X1138480Y1576364
X0922000Y1328000
X0961566Y1448341
X0922000Y1324000
X0964503Y1448097
X1718425Y1468245
X0925500Y1319000
X0967002Y1448013
X0969785Y1447987
X1722334Y1468146
X0925459Y1315352
X0925500Y1337000
X0954541Y1448307
X0925500Y1333000
X0958306Y1448056
X0922000Y1346000
X0944105Y1448317
X0922000Y1342000
X0949216Y1448337
X1439850Y1541470
X1447026Y1577299
X1473947Y0492169
X0847686Y0475915
X1543582Y1524562
X0849772Y0494585
X0746110Y0471822
X1674923Y1582973
X1759379Y0507927
X0860341Y0503154
X1539344Y1579519
X0746110Y0478121
X0848097Y0503315
X1574966Y1577038
X1676176Y1580650
X0748077Y0521789
X1753566Y0512968
X0742961Y0481271
X1690353Y1591494
X0864361Y0493001
X0852177Y0341882
X0736661Y0474971
X0800674Y0504130
X1310914Y1577299
X0995000Y1362000
X1140325Y1598697
X0954259Y0657371
X0733512Y0471822
X0801857Y0508031
X1403232Y1579519
X0978026Y1459998
X0961592Y0821737
X0937580Y0655946
X0778747Y0572269
X0727292Y0487570
X1166873Y1561431
X0729489Y0666547
X1016000Y1361000
X0957462Y0668700
X0724697Y0535053
X0727292Y0484420
X1275170Y1579519
X0998000Y1365500
X1140422Y1595455
X0660215Y0483109
X0704965Y0638767
X0954361Y0660215
X0690452Y0486984
X0724143Y0487570
X1548671Y1545220
X1548671Y1549120
X1541876Y1554436
X1545521Y1545220
X1545521Y1549120
X1545644Y1552845
X1539369Y1552250
X1541191Y1549953
R02Y-0002500
X1680589Y1563526
X1680589Y1559626
X1671034Y1546934
X1673706Y1560425
X1668703Y1550898
X1671034Y1552234
R02Y0002500
X1671034Y1549734
X1668827Y1553551
X1412559Y1545220
X1412559Y1549120
X1405079Y1547453
X1405079Y1544953
X1405079Y1549953
X1403257Y1552250
X1409409Y1545220
X1409409Y1549120
X1409532Y1552845
X1405764Y1554436
X1284497Y1545220
X1284497Y1549120
X1277702Y1554436
X1281347Y1545220
X1281347Y1549120
X1281470Y1552845
X1275195Y1552250
X1277017Y1549953
R02Y-0002500
X1429571Y1584844
X1431989Y1584099
X1434494Y1584844
X1431989Y1581199
X1442901Y1574795
R03Y0002500
X1435401Y1574795
R03Y0002500
X1437901Y1582295
X1437901Y1574795
X1440401Y1577295
R02Y0002500
X1440401Y1574795
X1437901Y1577295
X1437901Y1579795
X1557633Y1584844
X1560051Y1584099
X1562556Y1584844
X1560051Y1581199
X1668826Y1572998
X1668826Y1575498
X1671006Y1571744
R02Y0002500
X1563463Y1577295
R02Y0002500
X1563463Y1574795
X1570963Y1577295
R02Y0002500
X1570963Y1574795
X1565963Y1582295
X1568463Y1582295
X1565963Y1579795
X1568463Y1579795
X1568463Y1577295
X1565963Y1577295
X1568463Y1574795
X1565963Y1574795
X1293459Y1584844
X1295877Y1584099
X1298382Y1584844
X1295877Y1581199
X1306789Y1577295
R02Y0002500
X1306789Y1574795
X1299289Y1577295
R02Y0002500
X1299289Y1574795
X1301789Y1582295
X1304289Y1582295
X1301789Y1579795
X1304289Y1579795
X1304289Y1577295
X1301789Y1577295
X1304289Y1574795
X1301789Y1574795
X1186455Y1605490
X1186455Y1602590
X1186455Y1608390
X1188960Y1609135
X1170539Y1583751
R03X0002500
X1170539Y1586251
R03X0002500
X1178039Y1588751
R02X-0002500
X1180923Y1586251
X1180923Y1588751
X1168023Y1588751
X1170539Y1588751
X1168023Y1586251
X0643041Y1682883
X0429947Y1594398
X0404669Y1594317
X0589507Y0462559
X0838963Y1345974
X0839244Y1352094
X0841039Y1358082
X0841472Y1365050
X1009896Y1301500
X1100961Y1622543
X1098549Y1625749
X1009905Y1305500
X0717843Y0418358
X0711363Y0369274
X0720993Y0427807
X0696391Y0368617
X0849351Y0499070
X0752409Y0474971
X0877936Y1312336
X1486000Y1686000
X1159500Y1682500
X1137755Y1569543
X0995500Y1368000
X0945617Y1309500
X0887117Y1436735
X0643128Y1639803
X0673359Y1674409
X0670839Y1620863
X0441931Y1581662
X0786440Y0480769
X0758709Y0481271
X0972408Y1312557
X0850684Y1310000
X0958299Y0659886
X0922591Y0496671
X0826472Y0483896
X1016000Y1303000
X0732580Y0537193
X0720613Y0677040
X0784543Y0734510
X0437736Y1544392
X0864003Y0866609
X0727292Y0481271
X0732520Y0545988
X0720563Y0679886
X0764568Y0736183
X0531339Y1546481
X0864106Y0863534
X0727292Y0478121
X0717515Y0679833
X0719710Y0612831
X0762396Y0732915
X0567214Y1544299
X0864020Y0859972
X0724143Y0478121
X0724931Y0678364
X0762530Y0565340
X0760425Y0736233
X0659532Y1546519
X0864140Y0856052
X0736609Y0518426
X0724143Y0481271
X0657430Y1555228
X0683067Y1641758
X0684280Y1452260
X0666978Y1560945
X0685578Y1637479
X0743664Y1626945
X1426899Y1616990
X0747289Y1693063
X1437594Y1616845
X1139188Y1621603
X0739900Y1523152
X1429072Y1643655
X0736723Y1623938
X0822794Y0775011
X0764401Y0676968
X0687310Y0522141
X0659028Y1710047
X1398883Y1680341
X1430238Y1617137
X1396783Y1617170
X0719117Y1682722
X1438565Y1612583
X1139142Y1618859
X0737551Y1524008
X1419811Y1599084
X0748413Y1679367
X0739611Y1458211
X1600442Y1434535
X0786877Y0475344
X1207954Y1703343
X1154824Y1471134
X0830046Y0476031
X0793951Y0342224
X1406447Y1619572
X1139037Y1614153
X0735453Y1525368
X0723181Y1688825
X0540797Y1512220
X0540797Y1516120
X0534002Y1521436
X0537647Y1512220
X0537647Y1516120
X0537770Y1519845
X0531495Y1519250
X0533317Y1516953
R02Y-0002500
X0672715Y1530526
X0672715Y1526626
X0661710Y1514148
X0660660Y1519234
X0665832Y1527425
X0663160Y1521734
X0663160Y1524234
X0663160Y1519234
X0663160Y1516734
X0663160Y1511734
X0421697Y1551844
X0424115Y1551099
X0426620Y1551844
X0424115Y1548199
X0427527Y1541795
R03Y0002500
X0435027Y1541795
R03Y0002500
X0430027Y1549295
X0430027Y1541795
X0432527Y1544295
R02Y0002500
X0432527Y1541795
X0430027Y1544295
X0430027Y1546795
X0552177Y1548199
X0554682Y1551844
X0552177Y1551099
X0549759Y1551844
X0660953Y1542498
X0663133Y1538744
R02Y0002500
X0660953Y1539998
X0563089Y1544295
R02Y0002500
X0563089Y1541795
X0555589Y1544295
R02Y0002500
X0555589Y1541795
X0558089Y1549295
X0560589Y1549295
X0558089Y1546795
X0560589Y1546795
X0560589Y1544295
X0558089Y1544295
X0560589Y1541795
X0558089Y1541795
X0666092Y1553650
X0439935Y1532600
X0833963Y1339464
X0833853Y1345833
X0303041Y1544299
X0890620Y1342990
X0864768Y0844815
X0727576Y0736756
X0705697Y0679533
X0712115Y0541872
X0708500Y0517362
X0714694Y0474971
X0395359Y1546519
X0888854Y1337936
X0865109Y0850795
X0729391Y0734135
X0708012Y0676836
X0710464Y0557036
X0714694Y0478121
X0710429Y0545752
X0865601Y0841219
X0725712Y0734135
X0703584Y0676544
X0702657Y0533695
X0750155Y1516451
X0159000Y1525480
X0708395Y0484420
X0750205Y1512307
X0863671Y0839062
X0723814Y0736782
X0701386Y0679683
X0696829Y0533604
X0267297Y1546119
X0261530Y1550300
X0389290Y1561250
X0437910Y1553910
X0177672Y1657538
X0177666Y1649223
X0177509Y1653825
X0876907Y1229586
R02Y0003000
X0905008Y1235940
R02Y-0003000
X0881694Y1235763
R02Y-0003000
X0664315Y1654484
X0647574Y1668505
X0643074Y1668505
X0650074Y1668505
X0678117Y1662787
X0654712Y1653813
X0669648Y1640917
X0613948Y1641600
X0462215Y1581510
X0947650Y1346000
X0947650Y1341500
X0947650Y1332500
X0947650Y1337000
X0947650Y1328000
R03Y-0004500
X0381350Y1645800
X0381350Y1642900
X0381350Y1649000
X0410108Y1535680
X0719958Y1477038
X0717358Y1477038
X0721267Y1474792
R02X-0002600
X0713126Y1469814
R03X0002600
X0715017Y1472287
R02X0002600
X0716871Y1467422
R02X-0002600
X0719471Y1467422
X0405331Y1548928
X0559215Y1530596
X0920107Y1229920
X0891247Y1225520
X0891247Y1219520
X0912053Y1225520
X0886707Y1235920
X0896974Y1229869
X0910707Y1235920
X0876923Y1239520
X0699247Y1508062
X0699140Y1513772
X0693495Y1519305
X0295042Y1530596
X0548197Y1512088
X0550471Y1511031
X0550471Y1513584
X0548197Y1514641
X0540810Y1521436
X0543672Y1519845
X0543947Y1512220
X0543947Y1516120
X0284024Y1512076
X0276637Y1521436
X0279499Y1519845
X0284024Y1514576
X0279774Y1516120
X0279774Y1512220
X0282588Y1509469
X0280088Y1509469
X0404699Y1521436
X0407561Y1519845
X0407836Y1516120
X0407836Y1512220
X0412086Y1514576
X0412086Y1512076
X0408150Y1509469
X0410650Y1509469
X0162188Y1518040
X0161188Y1510800
X0423131Y1517138
X0422587Y1510708
X0425087Y1510708
X0425631Y1517138
X0421294Y1557729
X0414202Y1559396
X0693395Y1508058
X0690683Y1508058
X0687529Y1508173
X0696237Y1508149
X0678339Y1510960
X0678386Y1507965
X0681563Y1510708
X0681517Y1508034
X0684557Y1510685
X0684603Y1507851
X0696330Y1516584
X0680717Y1513292
X0675505Y1512606
X0683666Y1515189
X0673174Y1515806
X0690752Y1516516
X0693587Y1516470
X0693655Y1513818
X0690751Y1513750
X0687711Y1513612
X0687666Y1510870
X0690820Y1510755
X0693532Y1510755
X0696329Y1513818
X0696374Y1510846
X0699049Y1510892
X0677871Y1519579
X0678345Y1516994
X0678121Y1528516
X0677871Y1524579
X0677871Y1522079
X0856500Y1348500
X0856500Y1339500
X0852780Y1338365
X0856500Y1330500
X0853100Y1331688
X0856500Y1321500
X0852955Y1320320
X0852811Y1313450
X0920107Y1241920
X0920107Y1238920
X0920107Y1232920
X0920107Y1235920
X0905007Y1241920
X0905007Y1238920
X0910707Y1232920
X0910707Y1229920
X0912053Y1219520
X0912053Y1222520
X0915053Y1222520
X0915053Y1219520
X0915053Y1225520
X0896907Y1238920
X0896907Y1241920
X0896974Y1235869
X0896974Y1232869
X0891247Y1222520
X0888247Y1222520
X0888247Y1225520
X0888247Y1219520
X0881807Y1241920
X0881807Y1238920
X0886707Y1232920
X0886707Y1229920
X0941033Y1282115
X0374432Y1582600
X0404686Y1512220
X0404686Y1516120
X0401659Y1519845
X0397891Y1521436
X0397206Y1514453
X0397206Y1511953
X0397206Y1516953
X0395384Y1519250
X0401536Y1512220
X0401536Y1516120
X0276624Y1512220
X0276624Y1516120
X0267322Y1519250
X0269144Y1516953
X0269144Y1514453
X0273474Y1512220
X0273474Y1516120
X0269144Y1511953
X0273597Y1519845
X0269829Y1521436
X0108971Y1482181
X0106371Y1482181
X0108996Y1485113
X0106396Y1485113
X0177792Y1582589
X0180292Y1582589
X0066696Y1488010
X0057770Y1488047
X0049265Y1493450
X0049265Y1490950
X0072396Y1496490
R02Y-0002600
X0084051Y1501690
X0109878Y1501879
X0101584Y1491292
X0101835Y1501863
X0102931Y1488097
X0064030Y1496595
R02Y-0002500
X0049177Y1496272
X0550939Y1536646
X0549674Y1538890
X0170166Y1562621
R03X-0002500
X0169966Y1570121
R03X-0002500
X0162666Y1565121
R03X0002500
X0162666Y1567621
R03X0002500
X0538719Y1546795
X0538719Y1549295
X0541219Y1549295
X0541219Y1546795
X0551219Y1541795
X0551219Y1544295
X0548719Y1544295
X0548719Y1541795
X0548719Y1546795
X0548719Y1549295
X0543719Y1546795
X0543719Y1549295
X0546219Y1544295
X0546219Y1546795
X0546219Y1541795
X0546219Y1549295
X0417098Y1536411
X0420057Y1537595
X0422557Y1537595
X0417098Y1538911
X0420657Y1549295
R03Y-0002500
X0415657Y1544295
R02Y0002500
X0418157Y1541795
R02Y0002500
X0415657Y1541795
X0423157Y1544295
X0423157Y1541795
X0418157Y1549295
X0274546Y1546795
X0274546Y1549295
X0282046Y1541795
X0279546Y1546795
X0279546Y1549295
X0282046Y1544295
R02Y0002500
X0277046Y1549295
X0277046Y1546795
X0287046Y1541795
X0287046Y1544295
X0284546Y1544295
X0284546Y1541795
X0284546Y1546795
X0284546Y1549295
X0286514Y1538682
X0284014Y1538682
X0048324Y1545961
X0033822Y1477075
R03Y0003000
X0042822Y1477075
X0042822Y1480075
X0042822Y1486075
X0042822Y1483075
X0057822Y1477075
X0057822Y1480075
X0057822Y1485294
X0057822Y1482791
X0066785Y1479175
X0066710Y1482324
X0067010Y1476292
X0066710Y1485324
X0081822Y1486075
X0081822Y1483075
X0088722Y1485741
X0088722Y1482741
X0081822Y1477075
X0081822Y1480075
X0088722Y1476741
X0088722Y1479741
X0038650Y1499326
X0041309Y1496173
X0041360Y1498971
X0049188Y1499181
X0057777Y1490580
X0064030Y1501595
X0064030Y1499095
X0075245Y1496640
X0075245Y1494040
X0075245Y1499240
X0075245Y1491440
X0080852Y1488638
X0080932Y1491440
X0080932Y1496640
X0080932Y1494040
X0077883Y1491440
X0077883Y1496640
X0077883Y1494040
X0083991Y1496540
X0101634Y1493992
X0101534Y1499244
X0104184Y1493892
X0104184Y1496492
X0104512Y1499196
X0083892Y1488840
X0083991Y1491440
X0083991Y1494040
X0089042Y1488506
X0089092Y1491106
X0101634Y1496492
X0106784Y1496492
X0108053Y1487893
X0105453Y1487893
X0106784Y1491292
X0104184Y1491292
X0106784Y1493892
X0109733Y1496567
X0110605Y1487896
X0109733Y1491367
X0109733Y1493967
X0080833Y1499240
X0077883Y1499240
X0072390Y1499211
X0083892Y1499140
X0107112Y1499196
X0104616Y1501811
X0109712Y1499196
X0107197Y1501756
X0103555Y1482128
X0103571Y1476485
X0103555Y1479128
X0103555Y1485128
X0083121Y1542294
X0288004Y1548199
X0290509Y1551844
X0288004Y1551099
X0285586Y1551844
X0298916Y1544295
R02Y0002500
X0298916Y1541795
X0293916Y1541795
X0296416Y1541795
X0293916Y1544295
X0296416Y1544295
X0296416Y1546795
X0293916Y1546795
X0293916Y1549295
X0296416Y1549295
X0291416Y1544295
R02Y0002500
X0291416Y1541795
X0178582Y1569590
X0178582Y1572490
X0181087Y1576135
X0178582Y1575390
X0170166Y1550751
X0162666Y1553251
X0162666Y1550751
X0165166Y1550751
X0165166Y1553251
X0167666Y1553251
X0167666Y1550751
X0170166Y1553251
X0170166Y1555751
X0167666Y1555751
R02X-0002500
X0173050Y1553251
X0173050Y1555751
X0160150Y1555751
X0160150Y1553251
X0075380Y1627622
X1734500Y1656965
X0833756Y1330156
X0834017Y1336252
X0088511Y1552296
X0049196Y1551294
X0047633Y1600896
X1761463Y1683465
X1736479Y1584330
X1775794Y1585332
X0074133Y1610896
X0043933Y1613818
X0074134Y1621396
X0072255Y1616730
X0079164Y1636992
X0027205Y1498230
X0126717Y1635893
X0408925Y1576805
X0124312Y1633488
X0075764Y1636993
X0027205Y1501630
X0408925Y1573805
X0070567Y1625603
X1734963Y1673465
X1765163Y1670543
X1734962Y1662965
X1734589Y1666203
X1726604Y1540970
X1726381Y1647386
X1730381Y1647386
X1730004Y1540968
X1735463Y1651965
X0063633Y1587481
X0058633Y1587481
X1689062Y1451496
X1706086Y1691568
X1681538Y1451522
X1702750Y1696185
X1682408Y0228337
X0548610Y0048082
X0084093Y1570285
X0081468Y1570285
X0078522Y1567888
X0078522Y1570388
X0108555Y1577462
X0108555Y1574657
X0081103Y1580311
X0083603Y1580311
X0097486Y1576705
X0099986Y1576705
X0099986Y1574205
X0097486Y1574205
X0094786Y1576705
X0094786Y1574205
X0078403Y1580311
X0078522Y1565141
X0112418Y1558180
X0112339Y1562515
X0112339Y1565015
X0078522Y1562641
X0078372Y1558916
X0078372Y1556416
X0114610Y1545543
X0111901Y1545543
X0112418Y1555680
X0111196Y1542569
X0078096Y1542444
X0078796Y1545669
X0075396Y1542369
X0075796Y1545669
X0077920Y1538245
X0113100Y1537346
X0114030Y1542419
X0110655Y1538946
X0108328Y1538946
X0105898Y1538946
X0103468Y1538946
X0070155Y1538946
X0067725Y1538946
X0072585Y1538946
X0074912Y1538946
X1797118Y1596588
X1797043Y1599811
X1798979Y1616550
X1782654Y1617726
X1782654Y1615026
X1795479Y1616550
X1791979Y1616550
X1777454Y1617726
X1780154Y1617726
X1777454Y1615026
X1780154Y1615026
X1767206Y1616451
X1760206Y1616451
X1763706Y1616451
X1768030Y1603149
X1768180Y1606549
X1797076Y1603662
X1797143Y1607014
X1768105Y1595925
X1768030Y1599249
X1801879Y1578905
X1800479Y1572305
X1801479Y1575605
X1798879Y1578905
X1798479Y1575605
X1797938Y1571982
X1795611Y1571982
X1790751Y1571982
X1793181Y1571982
X1763079Y1578705
X1766079Y1578705
X1762679Y1575405
X1765679Y1575405
X1764679Y1572105
X1759868Y1571982
X1762195Y1571982
X1755008Y1571982
X1757438Y1571982
X1202857Y1412454
X1202548Y1407453
X1030000Y0554500
X0661528Y1674865
X0663431Y1645780
X0664159Y1674844
X0669178Y1646627
X0441460Y1596020
X0443590Y1593880
X0660389Y1654481
X0667971Y1654404
X0639800Y1646650
X0644905Y1646491
X0649297Y1623185
X0649153Y1625726
X0637218Y1654131
X0642716Y1653939
X0427081Y1581620
X0424616Y1560086
X0432051Y1560635
X0433440Y1581700
X0408895Y1553644
X0413540Y1556646
X0424488Y1565400
X0431923Y1565790
X0388784Y1581801
X0402912Y1558011
X0388445Y1585898
X0405758Y1557900
X0172070Y1495550
X0172180Y1490210
X0401249Y1564422
X0407198Y1564990
X1438078Y1669992
X1469588Y1673342
X1439316Y1675080
X1468102Y1670817
X1433157Y1651977
X1433618Y1659331
X1651698Y1665045
X1656849Y1664949
X1656180Y1659220
X1653930Y1660640
X1651101Y1671833
X1656101Y1671720
X1147814Y1562823
X1142639Y1562789
X1302390Y1530430
X1308900Y1525510
X1165806Y1658934
X1158343Y1658514
X1190830Y1675710
X1189263Y1682551
X1169098Y1666278
X1159688Y1665427
X0902482Y1140558
X0072375Y1604365
X0072660Y1587365
X0696283Y0546530
X0287723Y0548499
X0149171Y1616759
X1734763Y1680465
X0852303Y0337488
X1731936Y1690165
X0805341Y0578059
X0689574Y0572866
X0752926Y0361021
X0746110Y0434106
X0784500Y0367500
X0786571Y0403455
X0770159Y0410257
X0758709Y0418358
X0805425Y0395502
X0597500Y0483500
X0742961Y0434106
X0664634Y0449952
X0783256Y0409340
X0755559Y0418358
X0784498Y0396353
X0765008Y0427807
X0773233Y0409154
X0691943Y1441626
X0385068Y1683502
X0702402Y1650469
X0727320Y1623698
X0673729Y1556768
X0871099Y0323000
X0430500Y1613709
X0406343Y1613847
X0430500Y1605835
X0419277Y1600725
X0406697Y1604207
X0399801Y1606376
X0399447Y1612609
X1113490Y1651862
X1120595Y1658967
X1124394Y1658967
X1132981Y1634531
X1117136Y1630441
X1114286Y1630507
X1132406Y1658967
X1137542Y1647925
X1124532Y1634915
X0919779Y1155658
X0900280Y1150769
X0702553Y0735811
X0889273Y1134470
X0694837Y0676412
X0664741Y0506865
X0735500Y0143000
X0687000Y0119500
X0760193Y0106500
X0754737Y0185469
X0757576Y0112575
X0046833Y1612596
X0043633Y1606896
X0083811Y1537296
X0099818Y1546296
X0064275Y1546296
X0048157Y1536296
X0041208Y1619896
X0061605Y1546833
X0097018Y1546331
X0057811Y1598061
X0102011Y1550242
X0061110Y1598146
X0066229Y1549536
X0048383Y1532395
X0083796Y1533746
X0093296Y1549142
X0091511Y1552296
X0064633Y1632896
X0064133Y1627896
X0055370Y1551351
X0146453Y1614879
X0773463Y0563455
X1762263Y1671765
X1765463Y1677465
X1787239Y1579406
X1771094Y1570332
X1751558Y1579332
X1735351Y1569832
X1746779Y1583378
X1784601Y1578967
X1767888Y1664465
X1751340Y1686140
X1789294Y1583278
X1747986Y1686215
X1753512Y1583478
X1735379Y1566282
X1771079Y1566782
X1780579Y1582178
X1744463Y1651229
X1778794Y1585332
X1746079Y1587705
X1744963Y1656465
X0860541Y0446089
X0850155Y0335042
X1720845Y1668498
X1190174Y1615418
X1748358Y1529248
X1748358Y1524248
X1748358Y1526748
X1748313Y1518704
X1748346Y1521223
X1424621Y1569411
X1424621Y1571911
X1770776Y1515902
X1770886Y1518471
X1770886Y1521095
X1770846Y1526601
X1770846Y1524001
X1768286Y1521095
X1768286Y1518471
X1768176Y1515902
X1768334Y1529342
X1768246Y1524001
X1768246Y1526601
X1774552Y1518631
X1774552Y1516031
X1774552Y1521231
X1774579Y1526360
X1774579Y1523860
X1777152Y1521231
X1777152Y1516031
X1777152Y1518631
X1777179Y1523860
X1777179Y1526360
X1765286Y1521095
X1823649Y1525144
X1745410Y1524534
X1742810Y1524534
X1556060Y1571682
X1558560Y1571682
X1291887Y1571682
X1294387Y1571682
X1177839Y1603121
X1172839Y1603121
X1175339Y1603121
X1170339Y1603121
X1173039Y1595621
R02X0002500
X1170539Y1595621
X1170539Y1598121
X1173039Y1598121
R02X0002500
X1170539Y1600621
R03X0002500
X1546593Y1579795
X1546593Y1582295
X1549093Y1582295
X1549093Y1579795
X1559093Y1574795
X1559093Y1577295
X1556593Y1577295
X1556593Y1574795
X1556593Y1579795
X1556593Y1582295
X1551593Y1579795
X1551593Y1582295
X1554093Y1577295
X1554093Y1579795
X1554093Y1574795
X1554093Y1582295
X1427931Y1570595
X1430431Y1570595
X1428531Y1582295
R03Y-0002500
X1423531Y1577295
R02Y0002500
X1426031Y1574795
R02Y0002500
X1423531Y1574795
X1431031Y1577295
X1431031Y1574795
X1426031Y1582295
X1282419Y1579795
X1282419Y1582295
X1284919Y1582295
X1284919Y1579795
X1294919Y1574795
X1294919Y1577295
X1292419Y1577295
X1292419Y1574795
X1292419Y1579795
X1292419Y1582295
X1287419Y1579795
X1287419Y1582295
X1289919Y1577295
X1289919Y1579795
X1289919Y1574795
X1289919Y1582295
X1815875Y1524682
X1818475Y1524682
X1807290Y1524532
X1809890Y1524532
X1827029Y1512405
X1827029Y1509405
X1827029Y1503405
X1827029Y1506405
X1794268Y1528720
X1797450Y1528768
X1799994Y1528674
X1797362Y1526104
X1799882Y1526112
X1797362Y1523504
X1799882Y1523512
X1797362Y1520904
X1779997Y1528888
X1794265Y1526062
X1794265Y1520862
X1794265Y1523462
X1780039Y1526360
X1780039Y1523860
X1780012Y1521231
X1765334Y1529342
X1765246Y1526601
X1765246Y1524001
X1751132Y1529248
X1751132Y1524248
X1751132Y1526748
X1804049Y1528031
X1794265Y1518262
X1799882Y1518312
X1799882Y1520912
X1797362Y1518304
X1812029Y1512405
X1812029Y1509405
X1803029Y1512405
X1780012Y1516031
X1780012Y1518631
X1803029Y1509405
X1788029Y1512405
X1765176Y1515902
X1765286Y1518471
X1779029Y1512405
X1788029Y1509405
X1779029Y1509405
X1751087Y1518704
X1751120Y1521223
X1764029Y1512405
X1745746Y1521239
X1764029Y1509405
X1742758Y1521239
X1745543Y1518678
X1756329Y1512405
X1739565Y1528105
X1756329Y1509405
X1741329Y1512405
X1741329Y1509405
X1812029Y1503405
X1812029Y1506405
X1803029Y1503405
X1803029Y1506405
X1788029Y1503405
X1788029Y1506405
X1779029Y1503405
X1779029Y1506405
X1764029Y1503405
X1764029Y1506405
X1756329Y1503405
X1756329Y1506405
X1741329Y1503405
X1741329Y1506405
X1770404Y1575330
X1735354Y1580480
X0055254Y0292892
X0040500Y0288500
X0306528Y0256528
X1631657Y0392925
X0047892Y0295452
X0041492Y0298207
X0053633Y1629896
X0058633Y1629896
X1755463Y1654465
X1750463Y1654465
X0163148Y1474504
X0750968Y1482349
X0717229Y1612376
X0148228Y0216118
X0149231Y0224204
X0751575Y0184252
X1410750Y0244583
X0686891Y0115868
X0749260Y0443555
X0753483Y0648749
X0793131Y0734310
X0799450Y0511801
X1659419Y0224597
X0981019Y0349387
X0995530Y0500034
X0736647Y0529772
X0736661Y0471822
X0728714Y0554190
X0742792Y1647982
X0650753Y1615912
X0792782Y0565323
X0743547Y0147703
X0578454Y0088926
X0695162Y1441350
X0639132Y1573127
X0755559Y0474971
X0781699Y0536425
X0768733Y1694485
X0724281Y0553438
X0736528Y0579615
X0879424Y1425001
X1596273Y1271472
X0909473Y1448779
X0433012Y1621612
X0436776Y1610394
X0426704Y1526731
X0436776Y1613794
X0426704Y1523331
X0554766Y1526731
X0422069Y1595433
X0425469Y1595433
X0554766Y1523331
X0410991Y1597002
X0290593Y1526731
X0413396Y1594597
X0290593Y1523331
X0162531Y1526731
X0403837Y1612456
X0162531Y1523331
X0403837Y1609056
X1434578Y1559731
X1118133Y1591398
X1129184Y1662705
X1434578Y1556331
X1118133Y1587998
X1125784Y1662705
X1146501Y1652208
X1131824Y1603993
X1562640Y1559731
X1562640Y1556331
X1146501Y1655608
X1131824Y1600593
X1298466Y1559731
X1141084Y1643272
X1142917Y1586714
X1298466Y1556331
X1141084Y1646672
X1142917Y1583314
X1113847Y1604554
X1170404Y1559731
X1170404Y1556331
X1117247Y1604554
X0420765Y1627695
X0546253Y1457507
X0417365Y1627695
X0546253Y1454107
X1090958Y1649928
X1115098Y1472271
X1090958Y1646528
X1115098Y1468871
X0949507Y1140558
X0966804Y1155658
X0947305Y1150769
X0704598Y0732288
X0698756Y0676388
X0672699Y0506907
X0937148Y1134343
X1269310Y1583170
X1397030Y1594060
X0936393Y1148087
X0979091Y1241920
X0979091Y1238920
X0979091Y1232920
X0979091Y1235920
X0963991Y1241920
X0979091Y1229920
X0963992Y1235940
R02Y-0003000
X0969691Y1235920
X0963991Y1238920
X0969691Y1232920
X0969691Y1229920
X0969907Y1225520
X0966907Y1225520
X0966907Y1219520
X0966907Y1222520
X0969907Y1222520
X0969907Y1219520
X0955891Y1241920
X0955958Y1229869
X0955891Y1238920
X0955958Y1235869
X0955958Y1232869
X0940791Y1241920
X0935891Y1229586
R02Y0003000
X0940678Y1235763
R02Y-0003000
X0945691Y1235920
X0935907Y1239520
X0940791Y1238920
X0945691Y1232920
X0945691Y1229920
X0946101Y1225520
X0943101Y1225520
X0946101Y1219520
X0946101Y1222520
X0943101Y1222520
X0943101Y1219520
X1670773Y1688827
X1674338Y1677832
X1646879Y1681738
X1199272Y1683025
X1197746Y1680914
X1199299Y1675517
X1159500Y1679000
X1159703Y1673000
X1666168Y1667688
X1190314Y1661630
X1671156Y1656405
R02X0003200
X1680695Y1656307
X0914276Y1347550
X0914355Y1340726
X0918000Y1339500
X0918000Y1330500
X0914462Y1329351
X0914333Y1322700
X0918000Y1321500
X0918000Y1312500
X0999350Y1337160
X0999350Y1328260
X0999350Y1323840
R02Y-0004420
X0999350Y1341580
X0999350Y1346000
X0999350Y1332740
X1435904Y1694335
X1140960Y1491934
X1143460Y1491934
X1140960Y1489434
X1143460Y1489434
X1158460Y1489434
R05X-0002500
X1158460Y1491934
R05X-0002500
X1417981Y1568680
X1567089Y1563596
X1302915Y1563596
X1448061Y1593055
X1448000Y1676000
X1436311Y1665948
X1659975Y1592929
X1686219Y1549994
X1685745Y1552579
X1685995Y1561516
X1685745Y1557579
X1685745Y1555079
X1556071Y1545076
X1552135Y1542469
X1554635Y1542469
X1556071Y1547576
X1548684Y1554436
X1551546Y1552845
X1551821Y1545220
X1551821Y1549120
X1431735Y1550240
X1430735Y1543800
X1433235Y1543800
X1434235Y1550240
X1416023Y1542469
X1419959Y1547576
X1419959Y1545076
X1418523Y1542469
X1415709Y1549120
X1415709Y1545220
X1415434Y1552845
X1412572Y1554436
X1287647Y1549120
X1287647Y1545220
X1287372Y1552845
X1284510Y1554436
X1291897Y1547576
X1290461Y1542469
X1287961Y1542469
X1291897Y1545076
X1141045Y1539952
R05X0002500
X1141045Y1537452
R05X0002500
X1141045Y1534952
R05X0002500
X1153545Y1542452
R05X-0002500
X1153545Y1544952
X1141045Y1544952
X1143545Y1544952
R03X0002500
X0941500Y1278059
X1170061Y1551040
X1169061Y1543800
X1164528Y1565578
X1149467Y1568988
X1140655Y1569256
X0788537Y0734410
X0746110Y0443555
X0750074Y0648739
X0838342Y0514610
X0982806Y0498606
X1723492Y0293068
X0980346Y0353527
X0800500Y0540500
X0665425Y0537000
X0695796Y0468672
X0649500Y0490260
X0570309Y1602380
R08X-0012060
X0642669Y1602380
R05X-0012060
X0461769Y1602380
X0566909Y1602380
X0554849Y1602380
R07X-0012060
X0639269Y1602380
R05X-0012060
X0458369Y1602380
X0570309Y1614292
R08X-0012060
X0642669Y1614292
R05X-0012060
X0461769Y1614292
X0566909Y1614292
X0554849Y1614292
R07X-0012060
X0639269Y1614292
R05X-0012060
X0458369Y1614292
X0494947Y1548397
X0490223Y1548397
X0485498Y1548397
X0480774Y1548397
X0476049Y1548397
X0471325Y1548397
X0466600Y1548397
X0461876Y1548397
X0457151Y1548397
X0523293Y1548397
X0518569Y1548397
X0513844Y1548397
X0509120Y1548397
R02X-0004724
X0452427Y1548397
X0494947Y1544997
X0490223Y1544997
X0485498Y1544997
X0480774Y1544997
X0476049Y1544997
X0471325Y1544997
X0466600Y1544997
X0461876Y1544997
X0457151Y1544997
X0523293Y1544997
X0518569Y1544997
X0513844Y1544997
X0509120Y1544997
R02X-0004724
X0452427Y1544997
X0564279Y1592380
R08X-0012060
X0636639Y1592380
R05X-0012060
X0455739Y1592380
X0560879Y1592380
X0548819Y1592380
R07X-0012060
X0633239Y1592380
R05X-0012060
X0452339Y1592380
X0564279Y1624292
R08X-0012060
X0636639Y1624292
R05X-0012060
X0455739Y1624292
X0560879Y1624292
X0548819Y1624292
R07X-0012060
X0633239Y1624292
R05X-0012060
X0452339Y1624292
X0623009Y1548397
X0618285Y1548397
X0613560Y1548397
X0608836Y1548397
X0604111Y1548397
X0599387Y1548397
X0594662Y1548397
X0589938Y1548397
X0585213Y1548397
X0651355Y1548397
X0646631Y1548397
X0641906Y1548397
X0637182Y1548397
R02X-0004724
X0580489Y1548397
X0623009Y1544997
X0618285Y1544997
X0613560Y1544997
X0608836Y1544997
X0604111Y1544997
X0599387Y1544997
X0594662Y1544997
X0589938Y1544997
X0585213Y1544997
X0651355Y1544997
X0646631Y1544997
X0641906Y1544997
X0637182Y1544997
R02X-0004724
X0580489Y1544997
X0306136Y1602380
R08X-0012060
X0378496Y1602380
R05X-0012060
X0197596Y1602380
X0302736Y1602380
X0290676Y1602380
R07X-0012060
X0375096Y1602380
R05X-0012060
X0194196Y1602380
X0306136Y1614292
R08X-0012060
X0378496Y1614292
R05X-0012060
X0197596Y1614292
X0302736Y1614292
X0290676Y1614292
R07X-0012060
X0375096Y1614292
R05X-0012060
X0194196Y1614292
X0358836Y1548397
X0354112Y1548397
X0349387Y1548397
X0344663Y1548397
X0339938Y1548397
X0335214Y1548397
X0330489Y1548397
X0325765Y1548397
X0321040Y1548397
X0387182Y1548397
X0382458Y1548397
X0377733Y1548397
X0373009Y1548397
R02X-0004724
X0316316Y1548397
X0358836Y1544997
X0354112Y1544997
X0349387Y1544997
X0344663Y1544997
X0339938Y1544997
X0335214Y1544997
X0330489Y1544997
X0325765Y1544997
X0321040Y1544997
X0387182Y1544997
X0382458Y1544997
X0377733Y1544997
X0373009Y1544997
R02X-0004724
X0316316Y1544997
X0300106Y1592380
R08X-0012060
X0372466Y1592380
R05X-0012060
X0191566Y1592380
X0296706Y1592380
X0284646Y1592380
R07X-0012060
X0369066Y1592380
R05X-0012060
X0188166Y1592380
X0300106Y1624292
R08X-0012060
X0372466Y1624292
R05X-0012060
X0191566Y1624292
X0296706Y1624292
X0284646Y1624292
R07X-0012060
X0369066Y1624292
R05X-0012060
X0188166Y1624292
X0230774Y1548397
X0226050Y1548397
X0221325Y1548397
X0216601Y1548397
X0211876Y1548397
X0207152Y1548397
X0202427Y1548397
X0197703Y1548397
X0192978Y1548397
X0259120Y1548397
X0254396Y1548397
X0249671Y1548397
X0244947Y1548397
R02X-0004724
X0188254Y1548397
X0230774Y1544997
X0226050Y1544997
X0221325Y1544997
X0216601Y1544997
X0211876Y1544997
X0207152Y1544997
X0202427Y1544997
X0197703Y1544997
X0192978Y1544997
X0259120Y1544997
X0254396Y1544997
X0249671Y1544997
X0244947Y1544997
R02X-0004724
X0188254Y1544997
X1578183Y1635380
R08X-0012060
X1650543Y1635380
R05X-0012060
X1469643Y1635380
X1574783Y1635380
X1562723Y1635380
R07X-0012060
X1647143Y1635380
R05X-0012060
X1466243Y1635380
X1578183Y1647292
R08X-0012060
X1650543Y1647292
R05X-0012060
X1469643Y1647292
X1574783Y1647292
X1562723Y1647292
R07X-0012060
X1647143Y1647292
R05X-0012060
X1466243Y1647292
X1502821Y1581397
X1498097Y1581397
X1493372Y1581397
X1488648Y1581397
X1483923Y1581397
X1479199Y1581397
X1474474Y1581397
X1469750Y1581397
X1465025Y1581397
X1531167Y1581397
X1526443Y1581397
X1521718Y1581397
X1516994Y1581397
R02X-0004724
X1460301Y1581397
X1502821Y1577997
X1498097Y1577997
X1493372Y1577997
X1488648Y1577997
X1483923Y1577997
X1479199Y1577997
X1474474Y1577997
X1469750Y1577997
X1465025Y1577997
X1531167Y1577997
X1526443Y1577997
X1521718Y1577997
X1516994Y1577997
R02X-0004724
X1460301Y1577997
X1572153Y1625380
R08X-0012060
X1644513Y1625380
R05X-0012060
X1463613Y1625380
X1568753Y1625380
X1556693Y1625380
R07X-0012060
X1641113Y1625380
R05X-0012060
X1460213Y1625380
X1572153Y1657292
R08X-0012060
X1644513Y1657292
R05X-0012060
X1463613Y1657292
X1568753Y1657292
X1556693Y1657292
R07X-0012060
X1641113Y1657292
R05X-0012060
X1460213Y1657292
X1630883Y1581397
X1626159Y1581397
X1621434Y1581397
X1616710Y1581397
X1611985Y1581397
X1607261Y1581397
X1602536Y1581397
X1597812Y1581397
X1593087Y1581397
X1659229Y1581397
X1654505Y1581397
X1649780Y1581397
X1645056Y1581397
R02X-0004724
X1588363Y1581397
X1630883Y1577997
X1626159Y1577997
X1621434Y1577997
X1616710Y1577997
X1611985Y1577997
X1607261Y1577997
X1602536Y1577997
X1597812Y1577997
X1593087Y1577997
X1659229Y1577997
X1654505Y1577997
X1649780Y1577997
X1645056Y1577997
R02X-0004724
X1588363Y1577997
X1314009Y1635380
R08X-0012060
X1386369Y1635380
R05X-0012060
X1205469Y1635380
X1310609Y1635380
X1298549Y1635380
R07X-0012060
X1382969Y1635380
R05X-0012060
X1202069Y1635380
X1314009Y1647292
R08X-0012060
X1386369Y1647292
R05X-0012060
X1205469Y1647292
X1310609Y1647292
X1298549Y1647292
R07X-0012060
X1382969Y1647292
R05X-0012060
X1202069Y1647292
X1366709Y1581397
X1361985Y1581397
X1357260Y1581397
X1352536Y1581397
X1347811Y1581397
X1343087Y1581397
X1338362Y1581397
X1333638Y1581397
X1328913Y1581397
X1395055Y1581397
X1390331Y1581397
X1385606Y1581397
X1380882Y1581397
R02X-0004724
X1324189Y1581397
X1366709Y1577997
X1361985Y1577997
X1357260Y1577997
X1352536Y1577997
X1347811Y1577997
X1343087Y1577997
X1338362Y1577997
X1333638Y1577997
X1328913Y1577997
X1395055Y1577997
X1390331Y1577997
X1385606Y1577997
X1380882Y1577997
R02X-0004724
X1324189Y1577997
X1307979Y1625380
R08X-0012060
X1380339Y1625380
R05X-0012060
X1199439Y1625380
X1304579Y1625380
X1292519Y1625380
R07X-0012060
X1376939Y1625380
R05X-0012060
X1196039Y1625380
X1307979Y1657292
R08X-0012060
X1380339Y1657292
R05X-0012060
X1199439Y1657292
X1304579Y1657292
X1292519Y1657292
R07X-0012060
X1376939Y1657292
R05X-0012060
X1196039Y1657292
X1238647Y1581397
X1233923Y1581397
X1229198Y1581397
X1224474Y1581397
X1219749Y1581397
X1215025Y1581397
X1210300Y1581397
X1205576Y1581397
X1200851Y1581397
X1266993Y1581397
X1262269Y1581397
X1257544Y1581397
X1252820Y1581397
R02X-0004724
X1196127Y1581397
X1238647Y1577997
X1233923Y1577997
X1229198Y1577997
X1224474Y1577997
X1219749Y1577997
X1215025Y1577997
X1210300Y1577997
X1205576Y1577997
X1200851Y1577997
X1266993Y1577997
X1262269Y1577997
X1257544Y1577997
X1252820Y1577997
R02X-0004724
X1196127Y1577997
X0657520Y0486330
X0702095Y0471822
X0667090Y0385150
X0652380Y0482390
X0651950Y0099890
X0727200Y0073210
X1119459Y1556343
X1701348Y1466557
X1143060Y0516476
X0724143Y0427807
X0736528Y0576480
X1005270Y0625710
X1771000Y1278060
X1073307Y1451931
X1769650Y1280200
X1139360Y0516031
X0736661Y0437256
X0765041Y0565867
X1028540Y0621000
X1705246Y1465325
X1070312Y1452028
X1112529Y1547661
X0708395Y0459223
X1164268Y1064705
X1164268Y1068051
X0188126Y1064706
X0188126Y1068052
X1134567Y1064705
X1134567Y1068051
X0158425Y1064706
X0158425Y1068052
X1104866Y1064705
X1104866Y1068051
X0128724Y1064706
X0128724Y1068052
X1075166Y1064705
X1075166Y1068051
X0099024Y1064706
X0099024Y1068052
X1045465Y1064705
X1045465Y1068051
X0069323Y1064706
X0069323Y1068052
X1653197Y1064705
X1653197Y1068051
X0677055Y1064706
X0677055Y1068052
X1682898Y1064705
X1682898Y1068051
X0706756Y1064706
X0706756Y1068052
X1712599Y1064705
X1712599Y1068051
X0736457Y1064706
X0736457Y1068052
X1742300Y1064705
X1742300Y1068051
X0766158Y1064706
X0766158Y1068052
X1772000Y1064705
X1772000Y1068051
X0795858Y1064706
X0795858Y1068052
X1206580Y0094846
X0758056Y1518349
X0709260Y1617903
X0695933Y1623460
X0757826Y1514412
X1649380Y1446713
X1287700Y1431700
X1641167Y1446746
X1291700Y1431700
X1194000Y1447500
X1279525Y1432000
X1180200Y1457100
X1194000Y1442500
X1276500Y1432000
X1176500Y1457071
X0907500Y0963309
X0909000Y0977491
X0911041Y0979459
X0912500Y0963309
X0901000Y0909000
X0907075Y0948500
X0912425Y0948500
X0917000Y0909000
X0196763Y1710444
X0841660Y0558200
X0842825Y0452739
X0752409Y0449854
X0833751Y0463578
X0739811Y0430957
X0909000Y0982000
X0904535Y0744639
X0839200Y0467900
X0907207Y0667646
X0833800Y0444700
X0739811Y0434106
X0909000Y0974000
X0906345Y0742414
X0845100Y0440100
X0909320Y0663930
X0414100Y0096620
X0419900Y0096620
X0411299Y0212096
X0443299Y0212095
X0431299Y0212095
X0448038Y0158659
X0436103Y0158594
X0431359Y0082589
X0438200Y0212096
X0448499Y0212036
X1441000Y1614500
X1685500Y1663599
X1695987Y1671618
X1701984Y1671618
X1445500Y1614500
X0492685Y0160994
X0470010Y0141070
X0424086Y0133265
X0479400Y0097574
X0479400Y0090574
X0424084Y0110839
X0479465Y0123644
X0422890Y0136700
X0433997Y0170701
X0424086Y0123023
X0479465Y0115644
X0479465Y0119644
X0479400Y0110930
X0479400Y0094574
X0452948Y0104003
X0441182Y0077125
X0445267Y0082124
X0500674Y0116261
X0502750Y0111276
X0559069Y0101985
X0400426Y0116215
X0559069Y0105385
X0400426Y0112815
X0553780Y0121240
X0553780Y0124640
X0555505Y0112203
X0417486Y0127579
X0552105Y0112203
X0417486Y0124179
X0482255Y0129822
X0459056Y0095101
X0482255Y0133222
X0462456Y0095101
X0452102Y0088711
X0472895Y0130020
X0476295Y0130020
X0455502Y0088711
X0535170Y0115130
X0544403Y0071436
X0535170Y0111230
X0541003Y0071436
X0405606Y0129715
X0514240Y0097146
X0405606Y0125815
X0517640Y0097146
X0526460Y0097495
X0445014Y0094684
X0526460Y0100895
X0448414Y0094684
X0446710Y0249340
X0442710Y0237990
X0423299Y0212096
X0449997Y0170701
X0480200Y0191900
X1090000Y0477500
X0441320Y0313170
X0440710Y0250340
X0437440Y0237270
X0419299Y0212096
X0441997Y0170701
X0483800Y0189400
X1084000Y0477500
X0441320Y0307170
X1214094Y0287948
X1219325Y0438151
X0780877Y0431368
X0758709Y0443555
X0724147Y0345291
X0485962Y0290679
X0435710Y0250340
X0541675Y0137169
X0567773Y0316153
X0569893Y0300293
X0571063Y0314669
X0561808Y0300492
X0862987Y0507305
X0557243Y0294693
X0538166Y0130698
X0543408Y0133912
X0533442Y0164428
X0521618Y0165428
X0480773Y0307153
X0482893Y0291293
X0484063Y0305669
X0474808Y0291492
X0470243Y0285693
X0521773Y0280721
X0522798Y0289035
X0509346Y0125842
X0497700Y0157200
X0500600Y0157100
X0541675Y0156195
X0541675Y0142021
X0541675Y0151470
X0541675Y0146874
X0517748Y0305145
X0520273Y0305145
X0517748Y0313200
X0520273Y0313200
X0515223Y0305145
X0515223Y0313200
X0517748Y0289035
X0520273Y0289035
X0515223Y0289035
X0516723Y0280721
X0519248Y0280721
X0503161Y0154620
X0507945Y0160919
X0503000Y0135600
X0500136Y0141058
X0789135Y0617097
X0866549Y0748027
X0979228Y1297918
X0947135Y1287403
X0973562Y0859767
X0540616Y0463486
X0533211Y0350838
X1214094Y0282948
X1214094Y0269008
X0906274Y0654921
X0653523Y0399987
X0616457Y0502306
X0944515Y0939850
X0689269Y0410420
X0724143Y0418358
X0694299Y0413108
X0724143Y0421508
X0908823Y0655116
X0651279Y0404458
X0618957Y0502306
X0935368Y0939182
X1080453Y0457959
X1768041Y0556537
X1077873Y0463444
X1773963Y0557537
X0165491Y1662182
X0087891Y1674521
X0165491Y1665582
X0087891Y1671121
X0099443Y1658531
X0041679Y1676723
X0099443Y1661931
X0041679Y1673323
X0100443Y1687463
X0040922Y1658269
X0100443Y1684063
X0040922Y1654869
X0085836Y1658543
X0165336Y1678477
X0165336Y1675077
X0085836Y1655143
X1093300Y1532660
X1096300Y1532660
X1087300Y1532660
X1090300Y1532660
X1060110Y1532850
X1063110Y1532850
X1056584Y1526080
X1054110Y1532850
X1057110Y1532850
X1051110Y1532850
X1028440Y1532930
X1031440Y1532930
X1033218Y1526080
X1022440Y1532930
X1025440Y1532930
X1019440Y1532930
X1009852Y1526080
X1000280Y1532760
X0988280Y1532760
X0997280Y1532760
X0991280Y1532760
X0994280Y1532760
X0986486Y1526080
X0963120Y1526080
X0958350Y1532760
R03X0003000
X0955350Y1532760
X0944406Y1532791
X1056584Y1520080
X1056584Y1523080
X1033218Y1520080
X1033218Y1523080
X1009852Y1520080
X1009852Y1523080
X0986486Y1520080
X0986486Y1523080
X0963120Y1523080
X0963120Y1520080
X0816693Y1506784
X1022796Y1550840
X0816694Y1509796
X1025796Y1550840
X0816729Y1497364
X0991196Y1550840
X0816717Y1500388
X0994196Y1550840
X1054396Y1550840
X0816693Y1516784
X1057396Y1550840
X0816706Y1519820
X0816690Y1487376
X0959584Y1550824
X0816690Y1490376
X0962584Y1550824
X0784277Y1500632
X0808714Y1487376
X0808714Y1506784
X0808714Y1516784
X0784277Y1504569
X0808714Y1509784
X0808714Y1490376
X0808714Y1519784
X1092934Y1550784
X0816714Y1526784
X1089934Y1550784
X0816714Y1529784
X0981768Y1501204
X0958402Y1501204
X1075232Y1501204
R03X-0023366
X0774616Y1520361
X0772906Y1522901
X1080232Y1501204
R05X-0023366
X0774646Y1516441
X1102248Y1496186
X0824714Y1487376
X0824714Y1506784
X0784277Y1512443
X0824714Y1526784
X0824714Y1497376
X0824714Y1516784
X0824714Y1490376
X0824714Y1509784
X0784277Y1508506
X0824714Y1529784
X0824714Y1500376
X0824714Y1519784
X1099098Y1501204
X1689184Y1702095
X1155180Y1655534
X1155253Y1559176
X0758163Y1510474
X0722480Y1657616
X0691036Y1625508
X0758163Y1506538
X1524425Y1185241
X1597234Y1382689
X1590723Y1381589
X1592788Y1388318
X1586000Y1387641
X1584156Y1381419
X0695796Y0449854
X0662570Y0457755
X0698946Y0449854
X0662570Y0461547
X0680187Y0491243
X0711544Y0446705
X0681213Y0495658
X0714694Y0443555
X0702095Y0430957
X0651853Y0439518
X1505016Y0817107
X1547561Y0807269
X1556361Y0807269
X1501636Y0828796
X1551961Y0807269
X0707500Y0368862
X0724143Y0434106
X0692996Y0418358
X0724143Y0437256
X0715500Y0368862
X0720993Y0418358
X0687345Y0046940
X0687835Y0037850
X0749260Y0427807
X0817497Y0419344
X0705245Y0465523
X0746110Y0446705
X0816170Y0458524
X0146086Y1705603
X0198760Y1719991
X0783358Y0495344
X0791403Y0342262
X0436226Y0475526
X0636579Y0366941
X0749260Y0462373
X0803410Y0341572
X0636500Y0360362
X0797252Y0455344
X0426208Y0468977
X0155260Y1723682
X0813114Y0455344
X0786755Y0455524
X0746110Y0462373
X0758709Y0434106
X0817497Y0431060
X1222094Y0282948
X1222094Y0269008
X1350094Y0269008
X1350094Y0282948
X1302094Y0269008
X1302094Y0282948
X1334094Y0269008
X1334094Y0282948
X1286094Y0269008
X1286094Y0282948
X1342094Y0269008
X1342094Y0282948
X1294094Y0269008
X1294094Y0282948
X1326094Y0269008
X1326094Y0282948
X1278094Y0269008
X1278094Y0282948
X1270094Y0269008
X1270094Y0282948
X1366094Y0269008
X1366094Y0282948
X1318094Y0269008
X1318094Y0282948
X1358094Y0269008
X1358094Y0282948
X1310094Y0269008
X1310094Y0282948
X0569004Y0225496
X0491635Y0215652
X0674611Y0345662
X0684800Y0477862
X1342094Y0292066
X0758709Y0449854
X0822878Y0446425
X0828286Y0401567
X1310094Y0287948
X0672111Y0345662
X0684800Y0481862
X1326094Y0292066
X0752409Y0427807
X0816281Y0403814
X1294094Y0287948
X0708395Y0468672
X1350094Y0287948
X0742961Y0430957
X0813148Y0403908
X1286094Y0292066
X0798312Y0372571
X0752409Y0446705
X1334094Y0287948
X0749260Y0430957
X0820018Y0403710
X1270094Y0292066
X1278094Y0287948
X0746110Y0449854
X0831381Y0455167
X0834426Y0401504
X0684680Y0485942
X0663551Y0346035
X1358094Y0292066
X1210698Y0313671
X0848030Y0338461
X0857942Y0448575
X0832224Y0450328
X1302069Y0303184
X0677111Y0345662
X0687472Y0486994
X1366094Y0287948
X0758709Y0456074
X0797000Y0404000
X1302094Y0292066
X0590501Y0086909
X0570863Y0410728
X0575913Y0413287
X0512076Y0206404
X0538613Y0227882
X0460567Y0225205
X1817275Y0180619
X0508001Y0220166
X1738658Y-0022543
X1738673Y-0025058
X1738628Y-0017513
X1738643Y-0020028
X1738642Y-0030445
X1738627Y-0027930
X1738643Y-0038396
X1738673Y-0033366
X1738658Y-0035881
X1738628Y-0040911
X1732350Y-0018819
X1735375Y-0017499
X1735390Y-0020014
X1727111Y-0019575
X1735389Y-0030431
X1732349Y-0029236
X1735374Y-0027916
X1735390Y-0038410
X1732350Y-0039605
X1727111Y-0028849
X1727111Y-0038849
X1735375Y-0040925
X1541580Y-0019575
X1536341Y-0018819
X1533316Y-0017499
X1533301Y-0020014
X1530033Y-0022543
X1530018Y-0025058
X1530063Y-0017513
X1530048Y-0020028
X1533301Y-0038410
X1536341Y-0039605
X1541580Y-0028849
X1541580Y-0038849
X1533302Y-0030431
X1536342Y-0029236
X1533317Y-0027916
X1533316Y-0040925
X1530048Y-0038396
X1530018Y-0033366
X1530033Y-0035881
X1530049Y-0030445
X1530064Y-0027930
X1530063Y-0040911
X1445282Y0019143
X1445267Y0021658
X1441999Y0024187
X1441984Y0026702
X1445252Y0024173
X1445237Y0026688
X1445176Y0006159
X1441923Y0006145
X1445176Y0016159
X1445161Y0013644
X1441923Y0016145
X1441908Y0013630
X1445171Y0010052
X1441909Y0010052
X1445161Y0003644
X1441908Y0003630
X1445176Y-0003841
X1445161Y-0006356
X1441923Y-0003855
X1441908Y-0006370
X1445171Y0000052
X1441909Y0000052
X1445171Y-0009948
X1441909Y-0009948
X1445176Y-0023841
X1441923Y-0023855
X1445176Y-0013841
X1445161Y-0016356
X1441923Y-0013855
X1441908Y-0016370
X1445171Y-0019948
X1441909Y-0019948
X1445161Y-0026356
X1441908Y-0026370
X1445261Y-0034263
X1445276Y-0036778
X1442008Y-0034249
X1442023Y-0036764
X1445307Y-0031442
X1445292Y-0028927
X1438959Y0025382
X1438883Y0004950
X1438883Y0014950
X1433817Y0014626
X1433817Y0005352
X1438883Y-0005050
X1433817Y-0004648
X1438883Y-0025050
X1438883Y-0015050
X1433817Y-0015374
X1433817Y-0025374
X1438983Y-0035569
X1433817Y-0034648
X1248286Y0014626
X1248286Y0005352
X1248286Y-0004648
X1248286Y-0025374
X1248286Y-0015374
X1248286Y-0034648
X1240179Y0024250
X1240194Y0026765
X1243219Y0025445
X1236926Y0024236
X1236941Y0026751
X1236896Y0019206
X1236911Y0021721
X1240180Y0003833
X1243220Y0005028
X1240195Y0006348
X1240194Y0010052
X1240195Y0016348
X1243220Y0015028
X1240180Y0013833
X1236927Y0003819
X1236942Y0006334
X1236932Y0010052
X1236942Y0016334
X1236927Y0013819
X1240180Y-0006167
X1243220Y-0004972
X1240195Y-0003652
X1240194Y0000052
X1240194Y-0009948
X1236927Y-0006181
X1236942Y-0003666
X1236932Y0000052
X1236932Y-0009948
X1243170Y-0025018
X1240145Y-0023698
X1240180Y-0016167
X1243220Y-0014972
X1240195Y-0013652
X1240194Y-0019948
X1240130Y-0026213
X1236892Y-0023712
X1236927Y-0016181
X1236942Y-0013666
X1236932Y-0019948
X1236877Y-0026227
X1240082Y-0036849
X1243122Y-0035654
X1240097Y-0034334
X1236813Y-0028961
X1236798Y-0031476
X1236829Y-0036863
X1236844Y-0034348
X1186378Y0026688
X1186393Y0024173
X1186408Y0021658
X1186423Y0019143
X1186392Y0003807
X1186377Y0006322
X1186312Y0009926
X1186392Y0013807
X1186377Y0016322
X1186377Y-0003678
X1186392Y-0006193
X1186312Y-0000074
X1186312Y-0010074
X1186377Y-0023678
X1186392Y-0016193
X1186377Y-0013678
X1186312Y-0020074
X1186392Y-0026193
X1186433Y-0028927
X1186448Y-0031442
X1186417Y-0036778
X1186402Y-0034263
X1180100Y0025382
X1183125Y0026702
X1183140Y0024187
X1174958Y0024626
X1183139Y0003821
X1183124Y0006336
X1180099Y0005016
X1183050Y0009926
X1183139Y0013821
X1183124Y0016336
X1180099Y0015016
X1174958Y0015352
X1174958Y0005352
X1180099Y-0004984
X1183124Y-0003664
X1183139Y-0006179
X1183050Y-0000074
X1183050Y-0010074
X1174958Y-0005374
X1180099Y-0024984
X1183124Y-0023664
X1183139Y-0016179
X1183124Y-0013664
X1180099Y-0014984
X1183050Y-0020074
X1183139Y-0026179
X1174958Y-0015374
X1174958Y-0024648
X1183164Y-0036764
X1183149Y-0034249
X1180124Y-0035569
X0844766Y0024626
X0844766Y0015352
X0844766Y0005352
X0844766Y-0005374
X0844766Y-0015374
X0844766Y-0024648
X0833391Y0021721
X0833376Y0019206
X0833421Y0026751
X0839699Y0025445
X0833406Y0024236
X0836674Y0026765
X0836659Y0024250
X0836660Y0003833
X0833407Y0003819
X0839700Y0005028
X0833422Y0006334
X0836675Y0006348
X0833412Y0010052
X0836674Y0010052
X0836660Y0013833
X0833407Y0013819
X0839700Y0015028
X0833422Y0016334
X0836675Y0016348
X0836660Y-0006167
X0833407Y-0006181
X0839700Y-0004972
X0833422Y-0003666
X0836675Y-0003652
X0836674Y-0009948
X0833412Y-0009948
X0836674Y0000052
X0833412Y0000052
X0839700Y-0024972
X0833422Y-0023666
X0836675Y-0023652
X0836674Y-0019948
X0833412Y-0019948
X0836675Y-0013652
X0833422Y-0013666
X0839700Y-0014972
X0833407Y-0016181
X0836660Y-0016167
X0836660Y-0026167
X0833407Y-0026181
X0836629Y-0029116
X0836644Y-0031631
X0833376Y-0029102
X0833391Y-0031617
X0836659Y-0034146
X0836674Y-0036661
X0833406Y-0034132
X0839699Y-0035341
X0833421Y-0036647
X0731758Y-0009673
X0731743Y-0007158
X0735011Y-0009687
X0728718Y-0008478
X0734996Y-0007172
X0735026Y-0012202
X0735041Y-0014717
X0735026Y-0025540
X0735041Y-0023025
X0731742Y-0017575
X0734995Y-0017589
X0728717Y-0018895
X0735010Y-0020104
X0731757Y-0020090
X0728718Y-0029264
X0735011Y-0028055
X0731758Y-0028069
X0734996Y-0030570
X0731743Y-0030584
X0723479Y-0009234
X0723479Y-0019234
X0723479Y-0028508
X0393287Y-0009234
X0381740Y-0012202
X0381770Y-0007172
X0388048Y-0008478
X0381755Y-0009687
X0385023Y-0007158
X0385008Y-0009673
X0393287Y-0018508
X0381725Y-0014717
X0385009Y-0020090
X0381756Y-0020104
X0388049Y-0018895
X0381771Y-0017589
X0385024Y-0017575
X0381725Y-0023025
X0381740Y-0025540
X0393287Y-0028508
X0385008Y-0028069
X0381755Y-0028055
X0388048Y-0029264
X0385023Y-0030584
X0381770Y-0030570
X1436263Y0008289
X1245840Y0008289
X1436263Y0011689
X1245840Y0011689
X1436263Y-0031711
X1245840Y-0031711
X1436263Y-0028311
X1245840Y-0028311
X1729557Y-0032512
X1539134Y-0032512
X1729557Y-0035912
X1539134Y-0035912
X1436263Y-0001711
X1245840Y-0001711
X1436263Y0001689
X1245840Y0001689
X1729557Y-0025912
X1539134Y-0025912
X1729557Y-0022512
X1539134Y-0022512
X1436263Y-0021711
X1245840Y-0021711
X1436263Y-0018311
X1245840Y-0018311
X1177404Y-0008311
X0842320Y-0008311
X1177404Y-0011711
X0842320Y-0011711
X0725925Y-0015571
X0390841Y-0015571
X0725925Y-0012171
X0390841Y-0012171
X1177404Y0008289
X0842320Y0008289
X1177404Y0011689
X0842320Y0011689
X1177404Y-0018311
X0842320Y-0018311
X1177404Y-0021711
X0842320Y-0021711
X1177404Y0021689
X0842320Y0021689
X1177404Y0018289
X0842320Y0018289
X0725925Y-0022171
X0390841Y-0022171
X0725925Y-0025571
X0390841Y-0025571
X1705561Y0644554
X1701661Y0644554
X0783759Y0479344
X0758709Y0462373
X0758709Y0459223
X1222094Y0292066
X1202508Y0341424
X0837912Y0401545
X0581335Y0472100
X0635640Y0464257
X0562331Y0048438
X0777166Y0504477
X0749260Y0465523
X0783821Y0431534
X0755559Y0440405
X0597050Y0281950
X1262094Y0287948
X1205625Y0313758
X0626824Y0182080
X0989582Y0303563
X0758709Y0440405
X0859469Y0425293
X0855497Y0507205
X0994409Y0349813
X0932129Y0244103
X0382184Y0466351
X0653266Y0479106
X0736661Y0478121
X0382184Y0507101
X0410984Y0496649
X1208431Y0128748
X0642854Y0756832
X0642854Y0760178
X0123980Y0714980
R04X-0002500
X0113980Y0722480
X0123980Y0717480
R04X-0002500
X0123980Y0719980
R04X-0002500
X0123980Y0722480
R03X-0002500
X0238469Y0756832
X0208768Y0756832
X0213327Y0756832
X0213327Y0760178
X0179067Y0756832
X0183626Y0756832
X0183626Y0760178
X0672555Y0760178
X0672555Y0756832
X0667996Y0756832
X0702256Y0760178
X0702256Y0756832
X0697697Y0756832
X0731957Y0760178
X0731957Y0756832
X0727398Y0756832
X0761658Y0760178
X0761658Y0756832
X0757099Y0756832
X0791358Y0756832
X0791358Y0760178
X0786800Y0756832
X0816500Y0756832
X0419984Y0508000
X0444441Y0565549
X0064823Y0760178
X0064823Y0756832
X0089965Y0756832
X0094524Y0756832
X0094524Y0760178
X0119666Y0756832
X0124224Y0756832
X0124224Y0760178
X0149366Y0756832
X0153925Y0756832
X0153925Y0760178
X1753990Y0713890
X1673839Y0756831
X1648697Y0756831
X1648697Y0760177
X1644138Y0756831
X1618996Y0756831
X1618996Y0760177
X1753990Y0706390
R02Y0002500
X1743990Y0711390
R03X0002500
X1743990Y0708890
R03X0002500
X1743990Y0706390
R03X0002500
X1743990Y0713890
R03X0002500
X1678398Y0756831
X1678398Y0760177
X1703540Y0756831
X1708099Y0756831
X1708099Y0760177
X1733241Y0756831
X1737800Y0760177
X1737800Y0756831
X1762942Y0756831
X1767500Y0756831
X1767500Y0760177
X1792642Y0756831
X1214600Y0759562
X1189469Y0756831
X1189469Y0760177
X1184910Y0756831
X1159768Y0760177
X1159768Y0756831
X1155209Y0756831
X1130067Y0760177
X1130067Y0756831
X1125508Y0756831
X1100366Y0760177
X1100366Y0756831
X1095808Y0756831
X1070666Y0760177
X1070666Y0756831
X1066107Y0756831
X1182256Y0632368
X0406184Y0507900
X1040965Y0760177
X1040965Y0756831
X1230094Y0282948
X1230094Y0269008
X1254094Y0282948
X1254094Y0269008
X0802752Y0459344
X0746110Y0456074
X0802533Y0449802
X0749260Y0459223
X0755559Y0465523
X0765008Y0468672
X0662000Y0469862
X0765975Y0414414
X0816000Y0463578
X0761858Y0465523
X0755559Y0462373
X0752409Y0437256
X0816109Y0449802
X0786358Y0483566
X0758709Y0465523
X0786999Y0435476
X0761858Y0427807
X0761858Y0430957
X0802270Y0435372
X0816409Y0467568
X0761858Y0468672
X0764600Y0517022
X0746110Y0465523
X0772427Y0495344
X0758709Y0478121
X0801552Y0463318
X0765008Y0465523
X0786887Y0451344
X0752409Y0459223
X0772427Y0475344
X0752409Y0462373
X0711544Y0456074
X0802752Y0480159
X0687310Y0500453
X0714694Y0456074
X0765008Y0456074
X0797463Y0476159
X0746110Y0459223
X0755559Y0459223
X0695796Y0437256
X0662000Y0429844
X0765008Y0474971
X0801753Y0491344
X0802752Y0487344
X0765008Y0471822
X0772427Y0487344
X0758709Y0474971
X0761858Y0471822
X0801874Y0471344
X0816236Y0439279
X0755559Y0434106
X0816109Y0471344
X0761858Y0474971
X0816239Y0435344
X0765008Y0430957
X0752409Y0465523
X0731864Y0074943
X1532824Y0555981
X1627152Y0168920
X1313011Y0139845
X1200012Y0181187
X1527853Y0560264
X1313011Y0135820
X1200037Y0177187
X1631455Y0167875
X1534565Y0564945
X0986790Y0480140
X1471395Y0487582
X1475257Y0530656
X1532730Y0562949
X1465395Y0487582
X0988650Y0465315
X1465832Y0530656
X0344984Y0199299
X0296283Y0242391
X0761858Y0478121
X0680576Y0207105
X1558198Y0486791
X0827341Y0419344
X1596299Y0536344
X0738672Y0494444
X0733512Y0468672
X0607091Y0528168
X0424784Y0496572
X0732500Y0529862
X0556351Y0041538
X0584752Y0086248
X1278137Y0171551
X1252693Y0124739
X1305091Y0131750
X1278211Y0156030
X0603344Y0139131
X0765000Y0186500
X0767500Y0386862
X0752409Y0471822
X0236104Y0151996
X0390881Y0284156
X1305091Y0127830
X1278211Y0161030
X1305091Y0123680
X1278137Y0166051
X0234628Y0166735
X0275793Y0129595
X0256586Y0138373
X0625755Y0168917
X0801762Y0495344
X0761858Y0481271
X0679316Y0209861
X1247834Y0159844
X1287486Y0134165
X1278137Y0184987
X1249431Y0137739
X0643800Y0161862
X0622705Y0285305
X0731500Y0368862
X0727292Y0418358
X0517314Y0200449
X0606585Y0043529
X0518691Y0191846
X0602837Y0032910
X0395590Y0147010
X0618705Y0285305
X0641006Y0161829
X0626705Y0285305
X0685500Y0124000
X0756000Y0145500
X0757188Y0091829
X0826474Y0431344
X0727292Y0424657
X0719500Y0368862
X0984509Y0303623
X0739500Y0374362
X0920018Y0362877
X0711544Y0427807
X0754813Y0374362
X0746110Y0430957
X0801614Y1339062
X0720993Y0484420
X0711544Y0474971
X0752409Y0478121
X0562208Y0397599
X0786877Y0471344
X0777754Y0558740
X0656832Y0577205
X0945120Y0193264
X0786825Y0459518
X0959033Y0487289
X0693621Y0346169
X0711544Y0440405
X1226094Y0314216
X1222094Y0305216
X0441320Y0316170
X0573763Y0058688
X0727500Y0386862
X0736661Y0427807
X1673100Y0121762
X0817497Y0427060
X0761858Y0424657
X0888000Y0293000
X0884004Y0271332
X0749260Y0449854
X0777408Y0256648
X0999350Y1310500
X1037566Y1047135
X0892000Y1307500
X0912500Y1310000
X0129070Y1608338
X0081006Y1593265
X0902377Y1456465
X0941011Y1269499
X0945872Y1301500
X0982000Y1307500
X0945872Y1304541
X0851400Y1305499
X0851500Y1302000
X1003090Y1037329
X1833288Y1469639
X1759949Y1297324
X1578020Y1344773
X1578411Y1348623
X1572668Y0806778
X1368109Y0098000
X1597481Y0271991
X1661928Y0230172
X1652525Y0161762
X1652525Y0151762
X1684925Y0126762
X1684925Y0141762
X1684925Y0157762
X1684925Y0166762
X1683275Y0120762
X1697530Y0636369
X1545987Y0562012
X1212051Y0559827
X1183811Y0640682
X0964114Y0554704
X0833000Y0503500
X1546149Y0541169
X1689000Y0234000
X0739128Y0566639
X0749131Y0570340
X0831018Y0583076
X1725423Y1692656
X1040626Y0668441
X1035026Y0756009
X0752409Y0481271
X0711544Y0481271
X0733512Y0474971
X0739811Y0465523
X0736661Y0465523
X0733512Y0465523
X0727292Y0465523
X0720993Y0465523
X0724143Y0465523
X0724143Y0440405
X0720993Y0440405
X0711544Y0424657
X0669929Y0407999
X0715500Y0360862
X0602223Y0322200
R02X0002525
X0604748Y0314145
X0602223Y0314145
X0607273Y0314145
X0603723Y0289721
X0604748Y0298035
X0602223Y0298035
X0606248Y0289721
X0607273Y0298035
X0609798Y0322200
X0609798Y0314145
X0609798Y0298035
X0608773Y0289721
X0324647Y0566086
X0389784Y0476070
X0397184Y0507101
X0411500Y0510800
X0427500Y0510553
X0611925Y0437000
X0580523Y0435949
X0642128Y0363279
X0707943Y0360643
X0530729Y0398634
X0581203Y0164356
X0581203Y0169415
X0585685Y0174975
X0691484Y0360643
X0755559Y0421508
X0817497Y0415344
X0622197Y0436116
X0651432Y0433532
X1754339Y0128242
X0649495Y0385118
X0749260Y0446705
X1262094Y0282948
X1262094Y0269008
X1238094Y0269008
X1246094Y0269008
X1545480Y1245090
X0711500Y0374362
X0944112Y0386593
X0939613Y0562031
X1584068Y1271198
X0854190Y0404035
X0867356Y0558714
X0707500Y0374362
X0635058Y0399700
X1599007Y1309762
X0921318Y0549357
X0921318Y0372475
X0817780Y0366905
X1695100Y0146762
X0826765Y0356334
X0828714Y0443552
X1695100Y0121762
X0708500Y0555451
X0624718Y0553428
X0569923Y0490726
X0654273Y0419251
X1608341Y1313269
X0703500Y0390862
X0699813Y0344798
X0866168Y0374774
X0919294Y0374503
X0917582Y0549564
X0916268Y0269859
X0875170Y0185113
X0908621Y0188899
X0949181Y0280131
X0708395Y0446705
X0958101Y0457846
X0749260Y0440405
X0816117Y0443552
X0558690Y1226149
X0424024Y1269644
X0611896Y0538178
X0575345Y0437151
X0711500Y0390862
X0634105Y0404652
X0695500Y0386862
X0755135Y0368907
X0749260Y0424657
X0860299Y0491620
X0801341Y0279141
X0982455Y0271443
X1020521Y0194499
X0982455Y0260781
X0958049Y0453912
X0797197Y0447344
X0141642Y0494147
X0586953Y0063441
X0152843Y1562666
X0405342Y1628611
X0405436Y1620268
X0141642Y0488684
X0591070Y0060201
X0152843Y1559146
X0558876Y1458305
X0704771Y0167788
X0558876Y1454905
X0704771Y0171188
X0646358Y0590316
X0280828Y0025935
X0650258Y0590316
X0284228Y0025935
X0644414Y0571169
X0280826Y0050649
X0648314Y0571169
X0284226Y0050649
X0638694Y0590504
X0225731Y0026477
X0634794Y0590504
X0229131Y0026477
X0635567Y0671774
X0225727Y0050649
X0638967Y0671774
X0229127Y0050649
X0814296Y1387445
X0814296Y1384045
X1340948Y1177681
X1340948Y1181681
X1025493Y0761819
X1025493Y0765719
X0708395Y0471822
X0651114Y0473884
X0063633Y0528229
X0047812Y0517635
X0055682Y0517595
X0042810Y0528070
X0056192Y0537795
X0062142Y0539495
X0570860Y0124710
X0570860Y0121310
X0482380Y0141942
X0540615Y0088213
X0485780Y0141942
X0538210Y0090618
X0493780Y0131442
X0537318Y0047067
X0490380Y0131442
X0533918Y0047067
X1249152Y0072895
X1056960Y0482262
X1062250Y0484672
X1019210Y0480155
X1022874Y0474545
X1111076Y0464388
X1158764Y0489516
X0644963Y0029143
X1107300Y0456944
X1162144Y0487630
X0654117Y0029099
X1062640Y0449155
X1057276Y0458155
X1019205Y0457687
X1023515Y0454397
X1017220Y0464155
X1023420Y0462921
X1017350Y0472155
X1023420Y0468039
X1085851Y0465978
X0266327Y0522456
X0693608Y1671081
X0372395Y1677449
X0117655Y1621766
X0693480Y1673940
X0372449Y1680520
X0114618Y1624541
X1084840Y0460005
X0269568Y0522366
X1180000Y0436000
X1178340Y0461615
X0854221Y0129362
X0842721Y0181362
X0597293Y0193186
X0575440Y0200785
X0575425Y0189835
X1176000Y0436500
X1178340Y0467165
X0854221Y0135862
X0845721Y0181362
X0604293Y0193185
X0746522Y0308804
X0958000Y0862000
X0695220Y0060455
X0747594Y0319106
X0958000Y0865500
X0698462Y0060683
X0923000Y0895500
X0812070Y0341590
X0712725Y0084714
X0920000Y0895500
X0816232Y0341584
X0715745Y0086300
X0939216Y0664767
X1178340Y0442234
X0658759Y1707147
X0906387Y0815721
X1178340Y0447734
X0653154Y1683265
X0906387Y0821221
X0941478Y0668648
X0651143Y1706162
X0650158Y1687189
X1124091Y1683983
X0871214Y1466542
X1125498Y1487292
X1132176Y1690038
X0708418Y0650389
X0822794Y0772511
X0760529Y0677715
X0695796Y0484420
X0671001Y1696017
X0125183Y1716741
X0107500Y1707450
X0118956Y1635244
X0727292Y0427807
X0274993Y0522052
X0135722Y1715672
X0095460Y1725241
X0129020Y1726741
X0095400Y1719741
X0127168Y1721695
X0127710Y1700166
X0096101Y1696469
X0127290Y1705666
X0096555Y1705508
X0596068Y0106798
X0672800Y0369362
X0597275Y0094922
X0680800Y0369362
X0614282Y0095873
X0675500Y0390862
X0679500Y0390862
X0610009Y0100748
X0626208Y0100861
X0683500Y0390862
X0606183Y0095873
X0676800Y0369362
X0684800Y0369362
X0622156Y0095948
X0676000Y0378100
X0705245Y0474971
X0685200Y0377820
X0705245Y0434106
X0561721Y0041024
X1062173Y0479655
X0857187Y0342210
X0860587Y0342210
X0719821Y0045862
X0724621Y0040062
X0728721Y0043562
X0733315Y0040862
X0736621Y0045262
X0740101Y0041162
X0745901Y0040362
X0746101Y0046262
X1152114Y1672517
X0951886Y0804495
X0683369Y0058157
X0840457Y0335368
X1133206Y1675383
X1152211Y1682373
X1122610Y1677976
X0566771Y0041133
X0039967Y0526709
X0030562Y0533055
X0678000Y0482862
X0702095Y0481271
X0670000Y0482862
X0229687Y0522453
X0678000Y0477862
X0702095Y0478121
X0670000Y0477862
X0217687Y0522453
X1755238Y0026477
X1758638Y0026477
X1755235Y0050649
X1758635Y0050649
X1700183Y0026505
X1703583Y0026505
X1700136Y0050649
X1703536Y0050649
X0307255Y1647150
X0297323Y1653772
X0307255Y1643750
X0297323Y1657172
X0045052Y1684283
X0056627Y0585818
X0159427Y1696652
X0814532Y0139851
X0814571Y0145952
X1616464Y0457509
X1573487Y0546996
X0863420Y0429362
X1466609Y0458608
X0568709Y0434227
X1616250Y0465042
X0859500Y0429362
X0588742Y0431976
X1572436Y0574022
X0040940Y0387302
X0039320Y0392269
X0142576Y1640163
X0045812Y0451602
X0047618Y0415184
X0142576Y1643563
X0049212Y0451602
X0047619Y0419084
X0060921Y0430806
X0045960Y0428806
X0064821Y0430806
X0049360Y0428806
X1455579Y1665701
X0427300Y0071300
X0416549Y0071665
X1009220Y0243638
X0428149Y0065016
X0416549Y0066365
X1015220Y0243638
X0384824Y1629713
X0991664Y0446372
X0873884Y0447991
X0883776Y0786814
X0679413Y1548843
X0410851Y1557434
X0389000Y1621500
X0389824Y1629713
X0994900Y0446192
X0873884Y0450491
X0883633Y0790336
X0679854Y1551492
X0394000Y1621500
X0421108Y1560235
X1151679Y0072258
X1142643Y0074738
X1003909Y0460162
X1142144Y0063186
X1126902Y0060805
X1003909Y0454662
X0996320Y0470364
X1446000Y1600500
X1381457Y0485550
X0993650Y0465315
X1373862Y0485552
X1451000Y1601000
X0845221Y0129362
X0845221Y0135862
X0602294Y0203786
X0608794Y0203786
X0276821Y0140465
X0593661Y0188776
X0283049Y0139731
X0264574Y0151206
X0600161Y0188776
X0286996Y0139865
X0838821Y0206872
X0844527Y0204968
X1744510Y0377452
X1193040Y0481691
X1770220Y0377452
X1270483Y0433148
X1744380Y0382892
X1770220Y0382952
X1270483Y0435648
X1186040Y0481691
X1242429Y0427255
X1178254Y0453142
X1256137Y0453872
X1242429Y0439255
X1178340Y0458734
X1256137Y0459182
X0615190Y0074533
X0745132Y0344964
X0867646Y0833388
X0672163Y1560899
X0686808Y1643500
X0628410Y0045381
X0867651Y0836820
X0748752Y0343582
X0669524Y1560850
X0703563Y1644116
X0739880Y1648046
X0735642Y1648537
X0035740Y0363337
X0399264Y0121144
X0192592Y0353072
X0486682Y0189516
X0400000Y0220300
X0370369Y1661817
X0718116Y1639129
X0121705Y1619460
X1099108Y1691229
X1087141Y1688914
X1328427Y0349452
X1250975Y0474945
X0845986Y0429413
X1113948Y1711244
X0683000Y0521500
X0824380Y0517595
X1664335Y0210191
X1612144Y0418552
X1301582Y0171551
X1238094Y0258633
X1134567Y0513870
X1561246Y0580393
X1564946Y0582733
X1572436Y0582433
X1568446Y0582733
X1572436Y0585933
X1572436Y0589433
X1572436Y0578933
X1562016Y0587783
X1562016Y0584283
X1565436Y0589433
X1565436Y0585933
X1568936Y0589433
X1568936Y0585933
X0130553Y0069343
X0141557Y0075340
X0152553Y0069343
X0164761Y0075340
X0175761Y0069340
X0186757Y0075343
X0197761Y0069340
X0208895Y0075340
X0219891Y0069343
X0064557Y0069340
X0075553Y0075343
X0086557Y0069340
X0097557Y0075340
X0108557Y0069340
X0119557Y0075340
X0230895Y0075340
X0127153Y0069343
X0138157Y0075340
X0149153Y0069343
X0161361Y0075340
X0172361Y0069340
X0183357Y0075343
X0194361Y0069340
X0205495Y0075340
X0216491Y0069343
X0061157Y0069340
X0072153Y0075343
X0083157Y0069340
X0094157Y0075340
X0105157Y0069340
X0116157Y0075340
X0227495Y0075340
X1501698Y1485895
X1494998Y1495595
X1448098Y1485895
X1441398Y1495595
X1435160Y1513190
X1552668Y1527082
X1552668Y1517082
X1541898Y1485895
X1528498Y1485895
X1521798Y1495595
X1515098Y1505295
X1435160Y1538390
X1505098Y1485895
X1498398Y1495595
X1451498Y1485895
X1444798Y1495595
X1435160Y1516590
X1552668Y1530482
X1552668Y1513682
X1545298Y1485895
X1531898Y1485895
X1525198Y1495595
X1518498Y1505295
X1435160Y1534990
X1698440Y1466590
X1764267Y1460080
X1786260Y0379059
X1278050Y0152912
X1077172Y1676686
X1077031Y1451498
X0068020Y0395222
X0053406Y0402862
X0041933Y0395652
X0043020Y0382942
X0067681Y0360702
X0154945Y1627750
X0385001Y0813527
X0163735Y1631969
X0372000Y0843027
X0154945Y1624350
X0385001Y0816927
X0163735Y1635369
X0372000Y0846427
X0050880Y1418963
X0371999Y0822927
X0058349Y1409731
X0372000Y0835197
X0050880Y1415563
X0371999Y0819527
X0058349Y1406331
X0372000Y0831797
X0388630Y1236747
X0035852Y0699822
X0716699Y0209021
X0390974Y1219449
X0716699Y0197187
X0035852Y0688916
X0368726Y1214455
X0035852Y0678010
X0716699Y0185687
X0313284Y1215122
X0035852Y0667045
X0716699Y0173687
X0388630Y1240147
X0035852Y0703222
X0716699Y0212421
X0390974Y1222849
X0716699Y0200587
X0035852Y0692316
X0372126Y1214455
X0035852Y0681410
X0716699Y0189087
X0313284Y1218522
X0035852Y0670445
X0716699Y0177087
X0704771Y0215032
R03Y-0011811
X0704771Y0218432
R03Y-0011811
X1370685Y1223032
X1007587Y0764946
X1346063Y1214329
X1007587Y0775880
X1342036Y1203029
X1007587Y0786882
X1315657Y1196132
X1007587Y0797884
X1370685Y1226432
X1007587Y0761546
X1346063Y1217729
X1007587Y0772480
X1342036Y1206429
X1007587Y0783482
X1315657Y1199532
X1007587Y0794484
X1007587Y0808818
X1007587Y0819752
R02Y0011002
X1007587Y0805418
X1007587Y0816352
X1007587Y0827354
X1007587Y0838356
X0860942Y0330858
X0864342Y0330858
X0722500Y0383162
X0724143Y0430957
X0656600Y0060537
X0835115Y0115223
X0588215Y0214079
X0674348Y0218580
X0733512Y0418358
X0837161Y0218212
X1089030Y1717841
X0813114Y0459344
X1484395Y0487582
X0927798Y1660762
X1089030Y1722841
X0723500Y0360862
X0818677Y0356405
X1124834Y0056805
X0630810Y0122089
X0417025Y0054762
X0870892Y0131868
X0816732Y0629198
X0865466Y0783081
X0680107Y1554330
X0421683Y1565312
X0400380Y1621500
X1450500Y1624000
X1151707Y1663655
X0588723Y0427949
X0746110Y0468672
X0752652Y0504106
X0624381Y0503765
X0394824Y1629713
X0754030Y1669256
X0915991Y1667328
X0828751Y0459344
X0892376Y0466430
X0903149Y0825094
X0753770Y1636083
X0951798Y1660762
X0939071Y1448219
X0822218Y0756979
X0644849Y0495582
X0738486Y0679139
X0705245Y0456074
X0837161Y0213207
X0520818Y1167366
X0517118Y1167366
X0531921Y1167366
X1536916Y1240844
X0528220Y1167366
X0596621Y1240366
X0828246Y1266501
X0877226Y1441585
X1496960Y1167390
X1493260Y1167390
X1508063Y1167390
X1504362Y1167390
X0630477Y1353109
X0436903Y1289694
X0662600Y1308502
X0594991Y1289582
X0110075Y1410500
X1626333Y1308091
X1641065Y1406393
X1604137Y1271358
X1608418Y1331089
X1414172Y1286188
X1211075Y1395200
X0142000Y1414500
X0083023Y1311607
X0336778Y1192112
X1055171Y1311203
X1244300Y1403500
X0523074Y0855939
X0526474Y0849434
X0407543Y0580490
X0365158Y0593580
X0224157Y0712915
X0549957Y0658478
X1499469Y0863322
X1478258Y0584142
X1340257Y0675111
X1662377Y0693300
X0145000Y1414425
X0082953Y1307607
X0339278Y1192112
X1055171Y1307203
X1249600Y1403425
X0526474Y0851934
X0549957Y0661478
X0407543Y0577415
X1662377Y0696300
X0436903Y1285694
X0594991Y1285582
X0110000Y1407425
X1414165Y1289564
X1211000Y1392125
X1608418Y1333589
X0523074Y0853439
X0365158Y0597546
X0224157Y0715915
X1499469Y0860322
X1478258Y0588108
X1340257Y0677765
X0206199Y0714074
X0289421Y0575098
X0210199Y0714074
X0274096Y0574698
X1200923Y0606134
X1293581Y0542716
X1200923Y0601734
X1294938Y0561331
X0630477Y1350109
X0662600Y1311502
X1626333Y1311091
X1641065Y1403393
X1607267Y1271978
X0771427Y0158026
X0625553Y0152683
X0626596Y0360196
X0714471Y0046670
X0711544Y0468672
X0648500Y0453862
X0698946Y0446705
X0205479Y1648730
X0205479Y1652130
X0062813Y0416000
X0558576Y0071436
X0062812Y0412100
X0555176Y0071436
X0551721Y0079372
X0547821Y0079372
X0873175Y0750472
X0869275Y0750472
X0516020Y0109270
X0516020Y0105370
X0736864Y0074943
X1431262Y0061392
X0813114Y0443344
X0822252Y0309973
X1404917Y0116911
X1162067Y0570050
X1444769Y0163842
X1065154Y0736282
X1349012Y1204971
X1589845Y1305289
X1439769Y0174217
X1242692Y0483435
X1078499Y0648202
X1454769Y0163842
X1044056Y0736188
X1361285Y1206718
X1362810Y1211071
X1449769Y0174217
X1083281Y0651601
X1061817Y0736362
X0729380Y0080518
X1205929Y0086872
X1452040Y0113018
X1238769Y0075320
X1446040Y0120218
X0734380Y0080518
X1700156Y1698830
X1218430Y0421012
X0819321Y0056961
X0734769Y0060757
X1463038Y1687060
X1418000Y1607500
X1421890Y1635500
X0973997Y0320848
X0740537Y0073564
X1419914Y1602777
X0500209Y0227881
X0422936Y0223501
X0529713Y0033346
X0524713Y0033346
X0538613Y0233000
X0460624Y0230323
X0570209Y0047982
X0790503Y0501826
X0758709Y0471822
X1765090Y0202326
X1762564Y0202326
X1758030Y0202263
X1755504Y0202263
X1774644Y0201002
X1777170Y0201002
X1771055Y0194120
X1773581Y0194120
X1769405Y0200920
X1771931Y0200920
X0794273Y1361500
X0794273Y1364500
X0794273Y1357600
X0794273Y1354600
X0163061Y1406548
X0163061Y1409048
X0162873Y1411611
X0163099Y1414400
X0173202Y1414249
X0172976Y1411460
X0173164Y1408897
X0173164Y1406397
X0199307Y1409876
R03X-0002500
X0188507Y1409876
X0199495Y1407313
X0199495Y1404813
X0196995Y1407313
X0196995Y1404813
X0194495Y1407313
X0194495Y1404813
X0191995Y1407313
X0191995Y1404813
X0188695Y1407313
X0188695Y1404813
X0221145Y1376307
X0223211Y1374577
X0223311Y1377577
X0221145Y1379207
X0225411Y1376077
X0225411Y1378977
X0192511Y1376077
X0188245Y1376307
X0190311Y1374577
X0192511Y1378977
X0190411Y1377577
X0188245Y1379207
X0157611Y1374577
X0157711Y1377577
X0159811Y1376077
X0159811Y1378977
X0155545Y1376307
X0155545Y1379207
X0122945Y1376307
X0125011Y1374577
X0127211Y1376077
X0122945Y1379207
X0125111Y1377577
X0127211Y1378977
X0225411Y1373177
X0215951Y1372872
X0213521Y1372872
X0219401Y1367167
X0219401Y1370067
X0218381Y1372872
X0192511Y1373177
X0186481Y1367247
X0186481Y1370147
X0180621Y1372872
R02X0002430
X0159811Y1373177
X0153741Y1367077
X0153741Y1369977
X0147921Y1372872
R02X0002430
X0127211Y1373177
X0121241Y1369947
X0121241Y1367047
X0117751Y1372872
X0120181Y1372872
X0115321Y1372872
X1137465Y1403877
X1134965Y1403877
X1134965Y1401377
X1137465Y1401377
X1137425Y1398737
X1132425Y1398737
X1134925Y1398737
X1127425Y1398737
X1129925Y1398737
X1132465Y1401377
X1132465Y1403877
X1127465Y1401377
X1129965Y1401377
X1127465Y1403877
X1129965Y1403877
X1197149Y1376058
X1194949Y1374558
X1192883Y1376288
X1197149Y1378958
X1195049Y1377558
X1192883Y1379188
X1162149Y1377558
X1159983Y1379188
X1164249Y1378958
X1162049Y1374558
X1159983Y1376288
X1164249Y1376058
X1131549Y1376058
X1131549Y1378958
X1129349Y1374558
X1127283Y1376288
X1129449Y1377558
X1127283Y1379188
X1096749Y1374558
X1098949Y1376058
X1094683Y1376288
X1096849Y1377558
X1098949Y1378958
X1094683Y1379188
X1197149Y1373158
X1185259Y1372853
X1187689Y1372853
X1191049Y1370088
X1191049Y1367188
X1190119Y1372853
X1164249Y1373158
X1158059Y1369918
X1158059Y1367018
X1154789Y1372853
X1152359Y1372853
X1157219Y1372853
X1131549Y1373158
X1125469Y1370008
X1125469Y1367108
X1122089Y1372853
X1119659Y1372853
X1124519Y1372853
X1098949Y1373158
X1092889Y1370178
X1092889Y1367278
X1091919Y1372853
R02X-0002430
X0460211Y0601014
X0457711Y0601014
X0460211Y0598514
X0457711Y0598514
X0447212Y0674540
X0447212Y0671640
X0479812Y0648140
X0479812Y0645240
X0513012Y0613940
X0513012Y0611040
X0445111Y0665601
X0443045Y0667331
X0440845Y0662931
X0442945Y0664331
X0445111Y0662701
X0440845Y0665831
X0440845Y0668731
X0447875Y0669036
X0452735Y0669036
X0450305Y0669036
X0477711Y0636201
X0473445Y0636431
X0475545Y0637831
X0473445Y0639331
X0475645Y0640831
X0477711Y0639101
X0473445Y0642231
X0482905Y0642536
X0480475Y0642536
X0485335Y0642536
X0511011Y0605001
X0511011Y0602101
X0508845Y0603731
X0506745Y0605231
X0506745Y0602331
X0508945Y0606731
X0506745Y0608131
X0513775Y0608436
X0518635Y0608436
X0516205Y0608436
X0465331Y0601014
X0470331Y0601014
X0467831Y0601014
X0462831Y0601014
X0465331Y0598514
X0470331Y0598514
X0467831Y0598514
X0462831Y0598514
X1527277Y0618118
X1524777Y0618118
X1527277Y0615618
X1524777Y0615618
X1590964Y0658741
X1590964Y0661741
X1623964Y0639741
X1623964Y0642741
X1558194Y0692501
X1558194Y0695501
X1558657Y0689696
R02X0002430
X1553727Y0684991
X1553657Y0681965
X1555893Y0683361
X1555893Y0686261
X1556027Y0680391
X1553827Y0687991
X1553657Y0678965
X1588663Y0652492
X1588663Y0649592
X1593857Y0655927
X1591427Y0655927
X1596287Y0655927
X1584397Y0649822
X1584397Y0652722
X1586597Y0654222
X1586497Y0651222
X1584397Y0655622
X1619497Y0632222
X1621663Y0633492
X1619597Y0635222
X1621663Y0630592
X1624427Y0636927
X1629287Y0636927
X1626857Y0636927
X1617397Y0633722
X1617397Y0636622
X1617397Y0630822
X1527277Y0613088
X1524777Y0613088
X1527277Y0610588
X1524777Y0610588
X1527277Y0607988
X1527277Y0605488
X1524777Y0607988
X1524777Y0605488
X0351632Y1359203
X0305163Y1386889
X0294684Y1387040
X0305163Y1389678
X0294683Y1390281
X0305012Y1384250
X0305204Y1381461
X0294533Y1384401
X0294725Y1381612
X0323709Y1379500
X0334189Y1378897
X0323751Y1370831
X0323559Y1373620
X0323710Y1376259
X0334230Y1370680
X0334038Y1373469
X0334189Y1376108
X0359764Y1359296
R02X0002500
X0354264Y1359296
X0356764Y1359296
X0364572Y1362085
X0362072Y1362085
X0359272Y1362085
R03X-0002500
X0364723Y1364724
X0362223Y1364724
X0359423Y1364724
R03X-0002500
X0253945Y1376307
X0253945Y1379207
X0258211Y1376077
X0256011Y1374577
X0258211Y1378977
X0256111Y1377577
X0258211Y1373177
X0246321Y1372872
X0252211Y1367332
X0252211Y1370232
X0251181Y1372872
X0248751Y1372872
X0418675Y1349266
X0418675Y1352166
X0421205Y1345686
X0421205Y1348586
X0421315Y1351376
X0421315Y1354276
X0417063Y1343423
X0417063Y1340523
X0411103Y1346172
R02X0002430
X0388771Y1334546
X0388771Y1337546
X0386611Y1336056
X0386145Y1330276
X0386145Y1333176
X0388311Y1331546
X0357611Y1332746
X0355511Y1331346
X0353345Y1330076
X0357611Y1329846
X0353345Y1332976
X0324707Y1329903
X0322607Y1331403
X0324707Y1332803
X0320441Y1333033
X0320441Y1330133
X0291811Y1329931
X0291811Y1332831
X0287545Y1333061
X0287545Y1330161
X0289711Y1331431
X0388211Y1328546
X0378521Y1326841
X0380951Y1326841
X0384481Y1324092
X0384481Y1321192
X0383381Y1326841
X0355411Y1328346
X0357611Y1326946
X0345721Y1326641
X0350581Y1326641
X0348151Y1326641
X0351651Y1323842
X0351651Y1320942
X0322507Y1328403
X0324707Y1327003
X0318811Y1323802
X0318811Y1320902
X0317677Y1326698
R02X-0002430
X0291811Y1327031
X0289611Y1328431
X0285891Y1323842
X0285891Y1320942
X0279921Y1326726
R02X0002430
X1352225Y1389788
X1352226Y1383804
X1352226Y1386804
X1362274Y1336057
X1341212Y1389804
X1346212Y1389804
X1348712Y1389804
X1343712Y1389804
X1337555Y1389658
X1349556Y1386674
X1349556Y1383674
X1343556Y1383674
X1343556Y1386674
X1346556Y1383674
X1346556Y1386674
X1337556Y1383674
X1337556Y1386674
X1340556Y1386674
X1340556Y1383674
X1229949Y1376058
X1229949Y1378958
X1227749Y1374558
X1225683Y1376288
X1227849Y1377558
X1225683Y1379188
X1229949Y1373158
X1218059Y1372853
X1223889Y1370088
X1223889Y1367188
X1220489Y1372853
X1222919Y1372853
X1397022Y1350858
X1394856Y1349588
X1396922Y1347858
X1399122Y1349358
X1399122Y1346458
X1394856Y1352488
X1399122Y1352258
X1387232Y1346153
X1393306Y1343415
X1393306Y1340515
X1389662Y1346153
X1392092Y1346153
X1362274Y1333157
X1362274Y1330257
X1364440Y1334527
X1364440Y1331527
X1364440Y1337527
X1329474Y1332957
X1329474Y1330057
X1331640Y1331327
X1333740Y1332727
X1333740Y1329827
X1300836Y1332784
X1300836Y1329884
X1298736Y1331384
X1296570Y1333014
X1296570Y1330114
X1263674Y1333042
X1263674Y1330142
X1265840Y1331412
X1267940Y1329912
X1267940Y1332812
X1364340Y1328527
X1354650Y1326822
X1357080Y1326822
X1360724Y1324084
X1360724Y1321184
X1359510Y1326822
X1331540Y1328327
X1333740Y1326927
X1327876Y1323834
X1327876Y1320934
X1321850Y1326622
R02X0002430
X1298636Y1328384
X1300836Y1326984
X1294956Y1323834
X1294956Y1320934
X1288946Y1326679
R02X0002430
X1265740Y1328412
X1267940Y1327012
X1262050Y1323778
X1262050Y1320878
X1258480Y1326707
X1260910Y1326707
X1256050Y1326707
X0352595Y0646054
X0355195Y0646094
X0350095Y0646054
R03X-0002500
X0355275Y0643534
X0355275Y0641034
X0414712Y0696540
X0414712Y0699440
X0381812Y0714160
X0381812Y0717060
X0348395Y0714160
X0348395Y0717060
X0315912Y0714500
X0315912Y0717400
X0283042Y0694380
X0283042Y0697280
X0250312Y0660180
X0250312Y0663080
X0412711Y0687301
X0412711Y0690201
X0408445Y0693331
X0408445Y0690431
X0410545Y0688931
X0408445Y0687531
X0410645Y0691931
X0375445Y0711131
X0377645Y0709731
X0375445Y0705331
X0377545Y0706731
X0375445Y0708231
X0379711Y0705101
X0379711Y0708001
X0384905Y0711436
X0387335Y0711436
X0382475Y0711436
X0342405Y0711063
R02Y-0002900
X0344605Y0709663
X0346671Y0707933
X0344505Y0706663
X0346671Y0705033
X0349435Y0711368
X0354295Y0711368
X0351865Y0711368
X0313611Y0705301
X0313611Y0708201
X0311445Y0706931
X0310445Y0703931
X0311545Y0709931
X0318805Y0711636
X0316375Y0711636
X0321235Y0711636
X0417905Y0693636
X0415475Y0693636
X0420335Y0693636
X0312611Y0702301
X0310445Y0700931
X0278775Y0689781
X0286035Y0691493
X0283605Y0691493
X0288465Y0691493
X0276575Y0691181
X0276575Y0688281
X0280841Y0685151
X0278675Y0686781
X0280841Y0688051
X0276575Y0685381
X0352675Y0643494
R04X-0002500
X0248111Y0650910
X0248111Y0653810
X0250875Y0657245
R02X0002430
X0245945Y0652540
X0243845Y0654040
X0243845Y0651140
X0246045Y0655540
X0243845Y0656940
X0352675Y0640994
R04X-0002500
X1446376Y0647770
X1446376Y0645270
X1443876Y0647770
X1443876Y0645270
X1443926Y0650370
X1446426Y0650370
X1459446Y0650370
X1456546Y0650370
X1451546Y0650370
X1454046Y0650370
X1449046Y0650370
X1525064Y0717444
X1525064Y0714544
X1492264Y0717444
X1492264Y0714544
X1458777Y0717094
X1458777Y0714194
X1426264Y0697854
X1426264Y0694954
X1393664Y0665284
X1393664Y0662384
X1360964Y0632414
X1360964Y0629514
X1518497Y0711331
X1520697Y0709931
X1518497Y0708431
X1520597Y0706931
X1518497Y0705531
X1522763Y0705301
X1522763Y0708201
X1527957Y0711636
X1525527Y0711636
X1530387Y0711636
X1485697Y0711331
X1485697Y0705531
X1485697Y0708431
X1489963Y0708201
X1487897Y0709931
X1487797Y0706931
X1489963Y0705301
X1492727Y0711636
R02X0002430
X1454815Y0709931
X1454715Y0703931
X1454715Y0706931
X1456881Y0705301
X1456881Y0708201
X1459615Y0711826
X1464475Y0711826
X1462045Y0711826
X1452615Y0705531
X1454715Y0700931
X1426757Y0692359
R02X0002430
X1419697Y0691754
X1419697Y0688854
X1423963Y0688624
X1421897Y0690354
X1419697Y0685954
X1423963Y0685724
X1421797Y0687354
X1387097Y0659174
X1396557Y0659479
X1398987Y0659479
X1394127Y0659479
X1459396Y0647770
X1456496Y0647770
X1459396Y0645270
X1456496Y0645270
X1451496Y0647770
X1453996Y0647770
X1453996Y0645270
X1451496Y0645270
X1448996Y0647770
X1448996Y0645270
X1391363Y0653144
X1389197Y0654774
X1387097Y0653374
X1391363Y0656044
X1389297Y0657774
X1387097Y0656274
X1358663Y0620244
X1354397Y0620474
X1356497Y0621874
X1358663Y0623144
X1356597Y0624874
X1354397Y0626274
X1354397Y0623374
X1361427Y0626579
R02X0002430
X0732418Y1420122
R02Y0003000
X0735418Y1420122
R02Y0003000
X0763283Y1394416
X0763283Y1397316
X0765449Y1395686
X0765349Y1392686
X0767549Y1394186
X0767549Y1397086
X0767549Y1391286
X0734767Y1391186
X0730501Y1394316
X0730501Y1397216
X0732667Y1395586
X0732567Y1392586
X0734767Y1394086
X0734767Y1396986
X0760980Y1388046
X0760980Y1385146
X0755659Y1390981
X0760519Y1390981
X0758089Y1390981
X0722877Y1390881
X0728198Y1385126
X0728198Y1388026
X0725307Y1390881
X0727737Y1390881
X1714447Y1423213
X1714447Y1420213
X1717447Y1420213
X1717447Y1423213
X1714447Y1417213
X1717447Y1417213
X1715282Y1393475
X1713182Y1394975
X1711016Y1396605
X1711016Y1393705
X1715282Y1390575
X1713082Y1391975
X1715282Y1396375
X1682500Y1393375
X1678234Y1396505
X1678234Y1393605
X1680400Y1394875
X1682500Y1396275
X1680300Y1391875
X1682500Y1390475
X1705822Y1390270
X1703392Y1390270
X1708713Y1387335
X1708713Y1384435
X1708252Y1390270
X1675931Y1387235
X1675931Y1384335
X1670610Y1390170
R02X0002430
X0797326Y0479344
X1400500Y0458377
X1705108Y1451774
X1547548Y1520070
X1390738Y1664938
X1385068Y1664907
X1382045Y1700038
X1545473Y1522117
X0858288Y0467048
X1406500Y0458362
X1702281Y1449801
X1390179Y1733118
X0156477Y1447733
X0093069Y1412500
X0093000Y1408000
X0154305Y1453101
X0351413Y1210052
X0093000Y1421500
X0357271Y1208988
X0093000Y1417000
X0349938Y1214563
X0154671Y1450019
X0361922Y1206891
X1194000Y1401000
X1300800Y1421800
X1318776Y1219566
X1194296Y1396500
X1193929Y1410000
X1295700Y1421800
X1322141Y1217365
X1194366Y1405500
X1301900Y1427700
X1324901Y1216419
X0351157Y0586415
X0351157Y0590415
X0338420Y0574500
X0342500Y0578500
X0342500Y0582500
X0341500Y0574500
X1198456Y0668138
X1464257Y0576977
X1464257Y0580977
X1204334Y0668138
X1464257Y0568977
X1209796Y0668115
X1464257Y0572977
X1580577Y1270937
X1036021Y0534990
X1567737Y1271411
X1555222Y1302757
X1572416Y1303160
X0725769Y0069737
X0994056Y0531074
X1009611Y0545074
X0666200Y0084862
X1009611Y0550074
X0667941Y0080142
X1024000Y0563000
X0658228Y0088447
X1016000Y0563107
X0674036Y0074522
X0994056Y0526074
X0994056Y0516014
X0675509Y0088173
X0680580Y0079230
X0994056Y0521014
X1002056Y0531074
X1017961Y0545074
X1024161Y0554757
X1019161Y0554757
X1002056Y0526074
X1002056Y0516014
X1002056Y0521014
X1586167Y1295478
X1043991Y0540979
X1580520Y1289900
X1039407Y0547723
X1028500Y0563000
X1577077Y1270937
X1574168Y1283300
X1042628Y0556845
X1037254Y0526074
X1556515Y1292232
X1574560Y1296410
X1036708Y0514883
X1596363Y1286296
X1037254Y0521014
X1071710Y0488782
X0692466Y0035950
X0697893Y0035950
X1071710Y0483655
X0047735Y1584885
X0051000Y1339200
X0084038Y0602233
X0084500Y1448500
X0368647Y0550422
X0047973Y1589981
X0350566Y0541882
X0084500Y1444500
X0053700Y1342300
X0084057Y0599372
X0692390Y0046939
X0382705Y0546433
X0870590Y0642420
X0988125Y0485193
X0697678Y0047132
X0379114Y0544866
X0864590Y0642420
X0991270Y0470212
X0692209Y1620037
X0709020Y1609101
X0924500Y1302000
X0745984Y1501052
X0900301Y0831221
X0806117Y0330102
X0651014Y0060820
X0924500Y1306000
X0746111Y1504125
X0900301Y0828248
X0808617Y0330102
X0660928Y0060707
X0689897Y1621781
X0713718Y1610235
X0714372Y1594679
X0718892Y1597152
X0646042Y0041545
X0647987Y0047606
X1018220Y0243638
X0618801Y0165356
X0618801Y0170415
X1024220Y0243638
X0835221Y0163862
X1084840Y0443515
X0838221Y0163862
X1084840Y0438234
X0635849Y1393376
X0073757Y1448500
X0630523Y1392554
X0073820Y1445945
X0093000Y1448500
X0093000Y1444500
X0936960Y0942898
X0929500Y0916500
X0942500Y0916340
X0960925Y0906500
X0942631Y0943162
X0957075Y0906500
X0950500Y0916150
X0934500Y0916500
X0927777Y0843416
X0910000Y0957500
X0920234Y0843349
X0910000Y0954500
X0943000Y0862823
X0945075Y0891500
X0938000Y0862620
X0934925Y0891425
X0591938Y0046308
X0597956Y0048047
X0618801Y0175534
X0822635Y0165468
X1023110Y0287311
X0599284Y0042481
X0603064Y0048023
X0615587Y0045611
X0619563Y0049193
X0651042Y0041545
X0654582Y0045448
X0674647Y0038190
X0666506Y0032750
X0563951Y0148640
X0680864Y0038190
X0690476Y0032684
X0563951Y0153640
X0597769Y0148640
X0597769Y0153640
X0251106Y0012615
X0246506Y0020365
X0605853Y0145640
X0246356Y0026855
X0255106Y0016615
X0605853Y0155131
X0719416Y0074036
X0720016Y0086952
X1066231Y0165078
X0719416Y0068738
X0725016Y0086952
X1066231Y0167578
X1619909Y0293742
X1619909Y0298742
X1717055Y0025908
X1627909Y0290742
X1722085Y0025908
X1627909Y0302742
X0589203Y0164356
X0653700Y0179962
X0572003Y0164356
X0589203Y0169415
X0649871Y0181942
X0572003Y0169415
X0712717Y0068541
X0714096Y0073686
X0622207Y0060573
X0624634Y0048104
X0887521Y0176862
X0917387Y0184114
X0887521Y0171362
X0922128Y0182486
X1553548Y1284991
X0759568Y0545867
X1381457Y0511050
X1553226Y1288814
X0748500Y0545862
X1373862Y0511052
X0733512Y0478121
X0760660Y0537862
X0748000Y0537862
X0733512Y0481271
X0925500Y0916500
X0831582Y0905153
X0938500Y0916500
X0831505Y0897291
X0951466Y0816400
X0946500Y0915988
X0934339Y0668533
X0948644Y0811190
X0954500Y0915988
X0934539Y0664648
X0923500Y0941500
X0905000Y0918500
X0928500Y0941500
X0917000Y0918500
X0698996Y0583081
X0704056Y0583081
X0711544Y0449854
X0694996Y0575081
X0714694Y0449854
X0708056Y0575081
X1593397Y1271458
X0865569Y0808545
X0696928Y0613207
X1590827Y1271378
X0865569Y0806045
X0702806Y0613264
X1517431Y0811466
X1512539Y0812920
X0667701Y1705043
X0659837Y1698400
X0887519Y1444625
X0379223Y1219527
X0926000Y0946500
X0881987Y1449608
X0926000Y0949500
X0380718Y1221906
X1323169Y1208995
X1325137Y1210653
X0903925Y0948500
X0940000Y0977500
X0915575Y0948500
X0940000Y0982500
X0627881Y0057120
X0662000Y0465862
X0640653Y0058274
X0666000Y0461862
X0163271Y1441588
X0863372Y0830718
X0734463Y0346712
X0611579Y0060277
X0082000Y1724331
X0863372Y0833469
X0161210Y1443542
X0616815Y0060277
X0738773Y0346716
X0146483Y1725636
X0082000Y1716331
X0146000Y1718241
X0639876Y0049193
X0626642Y0071365
X0670000Y0453844
X0642157Y0044695
X0642607Y0094116
X0666000Y0457862
X0158704Y1439411
X0863344Y0824713
X0726431Y0346384
X0601073Y0060301
X0143000Y1701011
X0863369Y0827461
X0160684Y1441046
X0729211Y0346379
X0606263Y0060301
X0082500Y1698511
X0143000Y1709166
X0082500Y1706511
X0695796Y0430957
X0672800Y0382362
X0670000Y0425894
X0680800Y0380280
X0698946Y0430957
X0705245Y0437256
X0675500Y0398862
X0714694Y0440405
X0591811Y0097421
X0666000Y0442362
X0679940Y0400933
X0698946Y0427807
X0708395Y0437256
X0684794Y0402268
X0702095Y0434106
X0670000Y0433844
X0599295Y0100747
X0618182Y0100786
X0670000Y0429864
X0303711Y0050860
X0691572Y0465214
X0298542Y0051088
X0702095Y0462373
X0687612Y0471850
X0301306Y0052485
X0296337Y0055855
X0705245Y0462373
X1780300Y0054400
X0666000Y0429844
X0705245Y0440405
X0657622Y0437819
X1769200Y0054300
X1773830Y0049000
X0670000Y0437844
X1769240Y0050788
X0702095Y0443555
X0662000Y0437844
X0753951Y0521801
X0742961Y0478121
X1594900Y0780112
X0848999Y0644995
X0752500Y0529862
X0779448Y0632498
X0695796Y0465523
X0582390Y0464701
X0708395Y0456074
X0666000Y0453844
X0567997Y0058992
X0711544Y0462373
X0714694Y0462373
X0702095Y0459223
X0654037Y0096041
X0549919Y0031048
X0628885Y0127057
X1255661Y0090470
X0666000Y0425862
X0641276Y0187557
X0534277Y0224930
X0464440Y0218253
X0657535Y0422694
X0548963Y0218441
X0471371Y0222764
X0534455Y0428561
X0535117Y0031340
X0746110Y0481271
X0748381Y0495244
X0588798Y0435949
X0655572Y0572603
X0751731Y0557714
X0748500Y0513362
X0722889Y1622491
X0651870Y1612986
X1151985Y1666685
X0687040Y1452300
X1126951Y1484646
X0639907Y1570443
X0718122Y1636332
X1084629Y1673002
X0943798Y1660762
X1071117Y1445005
X0690718Y0578913
X0553757Y0160075
X0235186Y0112022
X1499752Y0488424
X1800160Y0362542
X1083434Y0481500
X1111001Y0361272
X1007077Y0484937
X1011602Y0568473
X0705245Y0471822
X0553360Y0477822
X1794362Y1275546
X1700272Y1460547
X0715744Y1622842
X0784669Y1462178
X0235460Y0115790
X0241306Y0020325
X1722148Y0019910
X1829732Y0371329
X0887130Y0183169
X1027690Y0237902
X1023000Y0298311
X0755559Y0471822
X0830212Y0483892
X0770590Y0470940
X0752409Y0468672
X0162740Y1723886
X0212365Y1705403
X0203510Y1712441
X0171945Y1730693
X0203655Y1723000
X0211862Y1701100
X0323646Y0152120
X0304968Y0028365
X0783726Y0328467
X0846411Y0482128
X1775920Y0022031
X0323646Y0147120
X0304923Y0024657
X0847518Y0490905
X0791726Y0328467
X1787826Y0037548
X0323646Y0156120
X0235697Y0021585
X0846104Y0494661
X0799226Y0328467
X1712977Y0019986
X0239816Y0054365
X0323646Y0160120
X0847303Y0485788
X0787500Y0328362
X1715861Y0072593
X0937267Y0189010
X0654326Y0174437
X0550573Y0403586
X0626372Y0193431
X0742961Y0490070
X1585290Y1285098
X0696701Y0072462
X0745091Y0553563
X0646151Y0535227
X0055043Y1295676
X0610551Y1269888
X0712113Y0537797
X0427615Y1277917
X0598112Y1264365
X0424024Y1274644
X0708500Y0533862
X0655967Y0544375
X0274282Y0786741
X0716716Y0513368
X0448024Y0505345
X0704500Y0537862
X0714694Y0468672
X0465766Y0524991
X0424151Y0453174
X0704500Y0545862
X0708395Y0478121
X0699800Y0521760
X0700790Y0537732
X0757745Y0655353
X0822494Y0802941
X0636247Y0771179
X1203269Y0481237
X1598883Y1270766
X1155268Y0207344
X0704500Y0529862
X1125077Y0511498
X1521003Y1169488
X1543519Y1248205
X0933390Y0386405
X0933390Y0559943
X0712409Y0555413
X1207447Y0341381
X1230094Y0287948
X0282323Y0794867
X1271177Y0808963
X0772459Y0655290
X0443683Y0502256
X0720452Y0513362
X1104443Y0646983
X0705245Y0481271
X1599241Y1306622
X0696020Y0521844
X0839061Y0555808
X0711544Y0471822
X1095730Y0509362
X0703788Y0521817
X1693490Y0620672
X1685890Y0708610
X1567000Y1293446
X1034214Y0351601
X1039718Y0563268
X0723483Y0574890
X0714694Y0471822
X1645029Y1730759
X1645029Y1725759
X0802250Y0500504
X0550972Y0042902
X1013306Y0532501
X0764500Y0545862
X0926730Y0540897
X1025631Y0540104
X0757860Y0537859
X0779121Y0308755
X0860071Y0304850
X0644202Y0084604
X0647938Y0083795
X0779121Y0303410
X0855481Y0299692
X0661588Y0069662
X0777468Y0296315
X0799113Y0297733
X0803302Y0265848
X0656427Y0075431
X0754759Y0281007
X0843504Y0287602
X0657166Y0079131
X0804330Y0281380
X0853829Y0262057
X0810139Y0274098
X0656501Y0069662
X0650846Y0074074
X0102076Y1427833
X0770190Y0312563
X0795685Y0357498
X0780295Y0403538
X0780877Y0447344
X0378435Y0443386
X0081132Y1424195
X1203242Y1417440
X1164300Y1463300
X1188000Y1419800
X0851517Y0411745
X0884399Y1431507
X0910041Y1440536
X0359157Y0574415
X0695796Y0471822
X0550925Y0475178
X0375271Y0542191
X1472257Y0564977
X1456982Y0437362
X0758709Y0421508
X0102398Y1440000
X0838000Y0423362
X0081401Y1436105
X0375935Y0443386
X0829344Y0356224
X0826915Y0311842
X1202475Y1432468
X1160750Y1463250
X0913270Y1440429
X1495682Y0473302
X0854239Y0412911
X0886362Y1428973
X1184175Y1435600
X0360261Y0561044
X0796283Y0427344
X0378976Y0479226
X0590326Y0445015
X0355100Y0544390
X1472257Y0551241
X1462682Y0450372
X0758709Y0424657
X0866727Y0650739
X0799071Y1350088
X0735316Y0736742
X0712120Y0680287
X0780877Y0423344
X0775100Y0502504
X0302130Y0584160
X0551044Y0373085
X0311749Y0440921
X0822689Y0305148
X0813252Y0427060
X0783877Y0435444
X1151036Y0501627
X0625195Y1383457
X0779118Y0341749
X0783877Y0427344
X0681289Y1418291
X1635227Y1436528
X0796283Y0419344
X1497386Y0464980
X1625170Y1444016
X0573191Y0042912
X1618859Y0542820
X1742398Y0484304
X1586621Y0484304
X1776930Y0179051
X0796283Y0431344
X1818828Y0175241
X1028146Y0355960
X0855837Y0519713
X0962035Y0518988
X0572447Y0299470
X0841854Y0504972
X0736661Y0481271
X0283987Y0811342
X0708500Y0529862
X0457084Y0511870
X0325816Y0543012
X1263647Y0809118
X1539693Y0543613
X1135387Y0615658
X1032055Y0587260
X0707664Y0513375
X0716181Y0585562
X0791308Y0763525
X1767450Y0763524
X0761608Y0763525
X1737750Y0763524
X0731907Y0763525
X1708049Y0763524
X0702206Y0763525
X1678348Y0763524
X0672505Y0763525
X1648647Y0763524
X0642804Y0763525
X1618946Y0763524
X0749389Y0360816
X0673287Y0733156
X0624133Y0346520
X0751337Y0343849
X0635906Y0497964
X0686509Y0677440
X0841809Y0423219
X1776986Y0749023
X1081730Y0509172
X1057450Y0509242
X0056440Y0766180
X1040915Y0763524
X0094474Y0763525
X1070616Y0763524
X0124174Y0763525
X1100316Y0763524
X0153875Y0763525
X1130017Y0763524
X0183576Y0763525
X1159718Y0763524
X0213277Y0763525
X1189419Y0763524
X0560890Y0484664
X0206254Y0732537
X0340337Y0496462
X0838500Y0409500
X1068378Y0736795
X1072232Y0667749
X0782115Y1334173
X0862044Y1249687
X0799280Y1301009
X0799280Y1298509
X0807601Y1299241
X0804530Y1296259
X0802030Y1296259
X0799280Y1296009
X0796020Y1292160
R03X-0003500
X0783280Y1301009
X0783280Y1298509
X0780530Y1296259
X0778030Y1296259
X0783280Y1296009
X1036463Y1278949
X1036411Y1275658
X1033184Y1275996
X1033236Y1279287
X1042649Y1279152
X1042855Y1275552
X1039598Y1278765
X1039546Y1275474
X0941083Y1286156
X0101874Y1376408
X0134474Y1376408
X0167174Y1376408
X0200074Y1376408
X0111555Y1379562
X0098101Y1371559
X0144155Y1379562
X0130701Y1371559
X0176855Y1379562
X0163401Y1371559
X0209755Y1379562
X0196301Y1371559
X0141500Y1429500
X0108817Y1380530
X0207017Y1380530
X0174117Y1380530
X0141417Y1380530
X0112100Y1467500
X0112305Y1382130
X0121500Y1467400
X0144905Y1382130
X0177605Y1382130
X0124600Y1465100
X0210505Y1382130
X0128661Y1464000
X0124700Y1401000
X0104863Y1380085
X0129200Y1401000
X0137463Y1380085
X0134800Y1408100
X0170163Y1380085
X0138000Y1400600
X0203063Y1380085
X0780877Y0443344
X0788806Y0342236
X0446547Y0480123
X0661019Y0344831
X0080378Y1406676
X0218665Y1317880
X0221165Y1317880
X0221165Y1315380
X0202865Y1317880
X0205365Y1317880
X0216165Y1317880
X0188565Y1317880
X0188565Y1315380
X0200365Y1317880
X0200365Y1315380
X0172765Y1317880
X0186065Y1317880
X0183565Y1317880
X0170265Y1317880
X0167765Y1317880
X0167765Y1315380
X0153565Y1317880
X0151065Y1317880
X0156065Y1317880
X0156065Y1315380
X0137765Y1317880
X0140265Y1317880
X0132194Y1379933
X0135265Y1317880
X0135265Y1315380
X0123465Y1315380
X0123465Y1317880
X0118465Y1317880
X0120965Y1317880
X0102665Y1315380
X0099594Y1379933
X0102665Y1317880
X0107665Y1317880
X0105165Y1317880
X0218665Y1300380
X0218665Y1302880
X0221165Y1302880
X0221165Y1300380
X0218665Y1305380
X0221165Y1305380
X0221165Y1307880
R02Y0002500
X0202865Y1300380
X0202865Y1302880
X0205365Y1302880
X0205365Y1300380
X0202865Y1305380
X0205365Y1305380
X0216165Y1302880
X0216165Y1300380
X0216165Y1305380
X0216165Y1315380
X0202865Y1315380
X0205365Y1315380
X0216165Y1312880
R02Y-0002500
X0202865Y1307880
R02Y0002500
X0205365Y1312880
R02Y-0002500
X0218665Y1315380
X0218665Y1307880
X0218665Y1310380
X0218665Y1312880
X0188565Y1302880
X0188565Y1300380
X0188565Y1305380
R03Y0002500
X0200365Y1302880
X0200365Y1300380
X0200365Y1305380
R03Y0002500
X0172765Y1302880
X0172765Y1300380
X0172765Y1305380
X0186065Y1300380
X0186065Y1302880
X0183565Y1302880
X0183565Y1300380
X0186065Y1305380
X0183565Y1305380
X0170265Y1300380
X0170265Y1302880
X0167765Y1302880
X0167765Y1300380
X0170265Y1305380
X0167765Y1305380
X0167765Y1307880
R02Y0002500
X0170265Y1315380
X0170265Y1307880
X0170265Y1310380
X0170265Y1312880
X0183565Y1307880
X0172765Y1312880
R02Y-0002500
X0186065Y1315380
X0183565Y1315380
X0172765Y1315380
X0186065Y1307880
R02Y0002500
X0183565Y1312880
X0183565Y1310380
X0153565Y1300380
X0153565Y1302880
X0151065Y1302880
X0151065Y1300380
X0156065Y1302880
X0156065Y1300380
X0153565Y1305380
X0151065Y1305380
X0156065Y1305380
R03Y0002500
X0137765Y1300380
X0137765Y1302880
X0140265Y1302880
X0140265Y1300380
X0135265Y1302880
X0135265Y1300380
X0137765Y1305380
X0140265Y1305380
X0135265Y1305380
R03Y0002500
X0137765Y1315380
X0140265Y1315380
X0137765Y1307880
R02Y0002500
X0140265Y1312880
R02Y-0002500
X0153565Y1315380
X0151065Y1315380
X0153565Y1307880
R02Y0002500
X0151065Y1312880
R02Y-0002500
X0118465Y1302880
X0120965Y1302880
X0120965Y1300380
X0123465Y1312880
R03Y-0002500
X0118465Y1305380
X0120965Y1305380
X0123465Y1300380
X0123465Y1302880
X0118465Y1300380
X0107665Y1315380
X0105165Y1315380
X0107665Y1307880
R02Y0002500
X0105165Y1312880
R02Y-0002500
X0118465Y1307880
R02Y0002500
X0120965Y1312880
R02Y-0002500
X0118465Y1315380
X0120965Y1315380
X0102665Y1312880
R03Y-0002500
X0107665Y1305380
X0105165Y1305380
X0102665Y1300380
X0102665Y1302880
X0107665Y1300380
X0107665Y1302880
X0105165Y1302880
X0105165Y1300380
X0415318Y1017245
X0415318Y1024726
X0415318Y1020986
X0415318Y1028466
X0424873Y1018879
X0424873Y1023013
X0401341Y1022560
X0401341Y1019017
X0393861Y1019017
X0393861Y1022560
X0386381Y1019017
X0386381Y1022560
X0415318Y1013505
X0401341Y1015474
R02X-0007480
X0197794Y1379933
X0164894Y1379933
X1073612Y1376389
X1106212Y1376389
X1138912Y1376389
X1171812Y1376389
X1083293Y1379543
X1069839Y1371540
X1115893Y1379543
X1102439Y1371540
X1148593Y1379543
X1135139Y1371540
X1181493Y1379543
X1168039Y1371540
X1080555Y1380511
X1113155Y1380511
X1145855Y1380511
X1178755Y1380511
X1239242Y1418462
X1220200Y1449100
X1084043Y1382111
X1116643Y1382111
X1222700Y1446300
X1226200Y1444300
X1149343Y1382111
X1229661Y1442000
X1182243Y1382111
X1238200Y1395500
X1076601Y1380066
X1233700Y1395600
X1109201Y1380066
X1234900Y1404400
X1141901Y1380066
X1238500Y1400900
X1174801Y1380066
X0883562Y1440356
X0846000Y0418862
X1024443Y0424051
X0915334Y0639166
X0906313Y0825095
X1193403Y1315361
X1193403Y1317861
X1190903Y1317861
X1188403Y1317861
X1177603Y1317861
X1175103Y1317861
X1172603Y1315361
X1172603Y1317861
X1169532Y1379914
X1160503Y1315361
X1160503Y1317861
X1155503Y1317861
X1158003Y1317861
X1139703Y1315361
X1136632Y1379914
X1139703Y1317861
X1144703Y1317861
X1142203Y1317861
X1127803Y1315361
X1127803Y1317861
X1122803Y1317861
X1125303Y1317861
X1107003Y1315361
X1103932Y1379914
X1107003Y1317861
X1112003Y1317861
X1109503Y1317861
X1095203Y1315361
X1095203Y1317861
X1090203Y1317861
X1092703Y1317861
X1074403Y1315361
X1071332Y1379914
X1074403Y1317861
X1079403Y1317861
X1076903Y1317861
X1193403Y1312861
R03Y-0002500
X1190903Y1305361
X1193403Y1300361
X1193403Y1302861
X1190903Y1302861
X1190903Y1300361
X1188403Y1305361
X1188403Y1300361
X1188403Y1302861
X1177603Y1315361
X1175103Y1315361
X1188403Y1315361
X1177603Y1307861
R02Y0002500
X1175103Y1312861
R02Y-0002500
X1188403Y1307861
R02Y0002500
X1190903Y1315361
R03Y-0002500
X1177603Y1305361
X1175103Y1305361
X1177603Y1300361
X1177603Y1302861
X1175103Y1302861
X1175103Y1300361
X1172603Y1312861
R03Y-0002500
X1172603Y1300361
X1172603Y1302861
X1160503Y1312861
R03Y-0002500
X1160503Y1300361
X1160503Y1302861
X1155503Y1305361
X1158003Y1305361
X1155503Y1300361
X1155503Y1302861
X1158003Y1302861
X1158003Y1300361
X1144703Y1315361
X1142203Y1315361
X1144703Y1307861
R02Y0002500
X1142203Y1312861
R02Y-0002500
X1155503Y1315361
X1158003Y1315361
X1155503Y1307861
R02Y0002500
X1158003Y1312861
R02Y-0002500
X1139703Y1312861
R03Y-0002500
X1144703Y1305361
X1142203Y1305361
X1139703Y1300361
X1139703Y1302861
X1144703Y1300361
X1144703Y1302861
X1142203Y1302861
X1142203Y1300361
X1127803Y1312861
R03Y-0002500
X1122803Y1305361
X1125303Y1305361
X1127803Y1300361
X1127803Y1302861
X1122803Y1300361
X1122803Y1302861
X1125303Y1302861
X1125303Y1300361
X1109503Y1300361
X1112003Y1307861
R02Y0002500
X1109503Y1312861
R02Y-0002500
X1112003Y1315361
X1109503Y1315361
X1122803Y1310361
X1122803Y1312861
X1125303Y1312861
R02Y-0002500
X1122803Y1315361
X1125303Y1315361
X1122803Y1307861
X1107003Y1312861
R03Y-0002500
X1112003Y1305361
X1109503Y1305361
X1107003Y1300361
X1107003Y1302861
X1112003Y1300361
X1112003Y1302861
X1109503Y1302861
X1095203Y1312861
R03Y-0002500
X1090203Y1305361
X1092703Y1305361
X1095203Y1300361
X1095203Y1302861
X1090203Y1300361
X1090203Y1302861
X1092703Y1302861
X1092703Y1300361
X1076903Y1307861
R02Y0002500
X1079403Y1312861
R02Y-0002500
X1076903Y1315361
X1079403Y1315361
X1092703Y1315361
X1090203Y1315361
X1092703Y1307861
R02Y0002500
X1090203Y1312861
R02Y-0002500
X1074403Y1312861
R03Y-0002500
X1079403Y1305361
X1076903Y1305361
X1074403Y1300361
X1074403Y1302861
X1079403Y1300361
X1079403Y1302861
X1076903Y1302861
X1076903Y1300361
X1401015Y1018878
X1401015Y1023012
X1391460Y1017244
X1391460Y1028465
X1391460Y1024725
X1391460Y1020985
X1370003Y1019016
X1370003Y1022559
X1377483Y1019016
X1377483Y1022559
X1362523Y1019016
X1362523Y1022559
X1391460Y1013504
X1370003Y1015473
X1377483Y1015473
X1362523Y1015473
X0532082Y0604900
X0498782Y0639000
X0466182Y0665500
X0535855Y0609749
X0522401Y0601746
X0502555Y0643849
X0489101Y0635846
X0456501Y0662346
X0469955Y0670349
X0459239Y0661378
X0394168Y0568482
X0491839Y0634878
X0525139Y0600778
X0521651Y0599178
X0380157Y0553090
X0383071Y0553738
X0488351Y0633278
X0385318Y0555238
X0455751Y0659778
X0529235Y0601543
X0387103Y0584506
X0391021Y0588788
X0495839Y0635323
X0392471Y0596988
X0463193Y0661823
X0393481Y0571239
X0371962Y0524954
X0702095Y0465523
X0547751Y0472678
X0499862Y0705160
X0497362Y0705028
X0499862Y0702660
X0529958Y0678460
X0532462Y0675960
X0534962Y0675960
X0534962Y0673460
X0534962Y0663460
X0423811Y1005800
X0438359Y0997766
X0438434Y0989766
X0438359Y0993766
X0438359Y1001766
X0438771Y1005800
R02X-0003740
X0434716Y1014745
X0427551Y1005800
X0443574Y1018879
X0453810Y1018879
X0442511Y1005800
X0446252Y1005800
X0443574Y1014745
X0453732Y1005800
X0449992Y1005800
X0453810Y1014745
X0465965Y1017245
X0465965Y1028466
X0465965Y1024726
X0465965Y1020986
X0465965Y1013505
X0465965Y1006025
X0465965Y1009765
X0457472Y1005800
X0480803Y1015474
R02Y0003543
X0495884Y1019017
X0495884Y1022560
X0488384Y1019017
X0488384Y1022560
X0495884Y1015474
X0488384Y1015474
X0467490Y0726660
X0462486Y0724028
R02X0002500
X0464990Y0726528
X0464990Y0729028
X0462490Y0729028
X0462490Y0726528
X0451686Y0724028
R02X-0002500
X0451690Y0726528
R02Y0002500
X0449190Y0731528
R02Y-0002500
X0446686Y0731660
R02Y-0002500
X0451690Y0734028
X0449190Y0734028
X0446686Y0734160
X0446686Y0739160
X0446686Y0736660
X0446686Y0741660
X0451686Y0736660
X0451686Y0739160
X0449186Y0736660
R02Y0002500
X0534362Y0601375
X0529958Y0663428
X0527458Y0663428
X0516658Y0663428
X0514158Y0663428
X0527462Y0670928
R02Y-0002500
X0527462Y0673428
X0516662Y0665928
R02Y0002500
X0514162Y0670928
R02Y-0002500
X0516662Y0673428
X0514162Y0673428
X0529962Y0665928
R03Y0002500
X0484058Y0697528
R02X-0002500
X0481562Y0700028
R02Y0002500
X0484062Y0705028
R02Y-0002500
X0479058Y0700160
R02Y0002500
X0481562Y0707528
X0484062Y0707528
X0481558Y0715160
X0484058Y0715160
X0481558Y0712660
X0481558Y0710160
X0484058Y0712660
X0484058Y0710160
X0479058Y0715160
X0479058Y0710160
X0479058Y0712660
X0479058Y0707660
X0499862Y0700160
X0494858Y0697528
R02X0002500
X0494862Y0700028
X0494862Y0702528
X0497362Y0702528
X0497362Y0700028
X0532462Y0663460
X0532462Y0673460
X0532462Y0670960
X0529958Y0675960
X0527458Y0675960
X0532462Y0665960
X0532462Y0668460
X0534962Y0668460
X0534962Y0665960
X0534962Y0670960
X0514158Y0675960
X0516658Y0675960
X0527458Y0678460
X0514158Y0680960
X0516658Y0680960
X0516658Y0683460
X0514158Y0683460
X0514158Y0678460
X0516658Y0678460
X0468462Y0661975
X0501062Y0635475
X0462490Y0731528
X0479058Y0717660
X0494862Y0705028
X0451686Y0741660
X1642734Y0633391
X1609734Y0652391
X1576964Y0686160
X1646507Y0638240
X1633053Y0630237
X1613507Y0657240
X1600053Y0649237
X1580737Y0691009
X1567283Y0683006
X1635791Y0629269
X1602791Y0648269
X1570021Y0682038
X1508281Y0559390
X1492514Y0539657
X1632303Y0627669
X1599303Y0646669
X1494967Y0541898
X1566533Y0680438
X1497310Y0543960
X1639745Y0629714
X1501821Y0577664
X1606745Y0648714
X1502757Y0570977
X1509757Y0575477
X1573975Y0682483
X1441898Y0576755
X1506337Y0561677
X1411000Y0460362
X0755559Y0424657
X1025830Y0449022
X1605618Y0728512
X1610618Y0723512
X1605618Y0726012
X1608118Y0726012
X1605618Y0723512
X1608118Y0723512
X1592188Y0731012
R03Y-0002500
X1594688Y0731012
R03Y-0002500
X1407433Y1005799
R02X-0003740
X1419716Y1018878
X1422394Y1005799
X1419716Y1014744
X1414501Y1001765
X1411173Y1005799
R02X0003740
X1410858Y1014744
X1414501Y0997765
X1414501Y0993765
X1414576Y0989765
X1429952Y1018878
X1429874Y1005799
X1426134Y1005799
X1433614Y1005799
X1429952Y1014744
X1442107Y1017244
X1442107Y1028465
X1442107Y1024725
X1442107Y1020985
X1442107Y1006024
R02Y0003740
X1464526Y1022559
X1464526Y1019016
X1456945Y1022559
X1456945Y1019016
X1464526Y1015473
X1456945Y1015473
X1471526Y1022559
R02Y-0003543
X1556708Y0767282
X1556708Y0769782
X1556708Y0764782
X1556708Y0759782
X1556708Y0762282
R02Y-0005000
X1556708Y0754782
X1556708Y0749782
X1556688Y0744688
X1556708Y0747282
X1559208Y0764782
X1561708Y0764782
X1559208Y0767282
X1561708Y0767282
X1559208Y0769782
X1561708Y0769782
X1559214Y0754688
X1561714Y0754688
X1559214Y0749688
X1559214Y0752188
X1561714Y0752188
X1561714Y0749688
X1572514Y0754688
X1572514Y0749688
X1572514Y0752188
X1559208Y0762282
X1561708Y0762282
X1559208Y0759782
X1561708Y0759782
X1559208Y0757282
X1561708Y0757282
X1572588Y0759782
X1572588Y0757282
X1572498Y0744688
X1559188Y0744688
X1561688Y0744688
X1559214Y0747188
X1561714Y0747188
X1572514Y0747188
X1575014Y0754688
R02Y-0002500
X1577588Y0752282
X1577588Y0754782
X1577588Y0749782
X1575088Y0757282
X1574998Y0744688
X1577498Y0744688
X1575014Y0747188
X1577588Y0747282
X1592188Y0733512
X1594688Y0733512
X1592188Y0736012
X1594688Y0736012
X1579244Y0682635
X1612014Y0648866
X1645014Y0629866
X1638427Y0691919
X1625117Y0691919
X1627617Y0691919
X1640927Y0691919
X1643427Y0691919
X1643517Y0697013
X1643517Y0694513
X1643517Y0699513
X1643517Y0702013
X1610718Y0716013
X1610718Y0713513
X1610718Y0718513
X1610718Y0721013
X1594818Y0710919
X1610628Y0710919
X1608128Y0710919
X1605628Y0710919
X1592344Y0720919
X1594844Y0720919
X1592344Y0713419
R02Y0002500
X1594844Y0718419
R02Y-0002500
X1608144Y0720919
R03Y-0002500
X1605644Y0720919
X1605644Y0713419
X1605644Y0715919
X1605644Y0718419
X1625143Y0701919
X1627643Y0701919
X1625143Y0694419
R02Y0002500
X1627643Y0699419
R02Y-0002500
X1640943Y0701919
R03Y-0002500
X1638443Y0701919
X1638443Y0694419
X1638443Y0696919
X1638443Y0699419
X1643377Y0712010
X1627617Y0712012
X1638377Y0711972
X1640877Y0711972
X1643377Y0707010
X1643377Y0704510
X1643377Y0709510
X1640877Y0704472
X1638377Y0706972
X1638377Y0704472
X1638377Y0709472
X1640877Y0709472
X1627617Y0707012
X1627617Y0704512
X1627617Y0709512
X1640877Y0706972
X1625117Y0712012
X1625117Y0707012
X1625117Y0704512
X1625117Y0709512
X0397656Y1349708
X0365074Y1330377
X0232874Y1376408
X0266474Y1330262
X0299370Y1330234
X0332274Y1330177
X0141514Y1436500
X0138013Y1440487
X0133100Y1444100
X0137463Y1382593
X0104863Y1382593
X0235863Y1382593
X0170163Y1382593
X0269463Y1336447
X0400645Y1355893
X0368063Y1336562
X0203063Y1382593
X0335263Y1336362
X0302359Y1336419
X0393883Y1344859
X0407337Y1352862
X0361301Y1325528
X0374755Y1333531
X0242555Y1379562
X0229101Y1371559
X0276155Y1333416
X0262701Y1325413
X0295597Y1325385
X0309051Y1333388
X0328501Y1325328
X0341955Y1333331
X0139500Y1446000
X0141500Y1433500
X0239817Y1380530
X0306313Y1334356
X0372017Y1334499
X0404599Y1353830
X0339217Y1334299
X0273417Y1334384
X0717712Y0346103
X0658905Y0341885
X0727292Y0434106
X0449496Y0474009
X0081052Y1427410
X0101637Y1432938
X0083441Y1430500
X0346751Y0515376
X0119100Y1460300
X0408087Y1355430
X0375505Y1336099
X0116122Y1458000
X0116900Y1449000
X0243305Y1382130
X0113600Y1449100
X0276905Y1335984
X0112481Y1452424
X0309801Y1335956
X0113500Y1455600
X0342705Y1335899
X0262701Y1322872
X0295597Y1322844
X0328501Y1322787
X0361301Y1322987
X0393883Y1342318
X0229101Y1369018
X0196301Y1369018
X0163401Y1369018
X0130701Y1369018
X0098101Y1369018
X0453269Y0478388
X0666552Y0346115
X0703700Y0386832
X0156174Y1435396
X0120700Y1408100
X0400645Y1353385
X0122050Y1403750
X0368063Y1334054
X0116700Y1410500
X0235863Y1380085
X0116700Y1415700
X0269463Y1333939
X0113500Y1398600
X0302359Y1333911
X0111600Y1403100
X0335263Y1333854
X0101500Y1436000
X0136000Y1432000
X0073820Y1442893
X0419247Y1268662
X0416747Y1268662
X0419247Y1271162
X0320961Y1246631
X0337965Y1246631
X0370461Y1246688
X0386361Y1246688
X0248765Y1317880
X0251265Y1317880
X0232965Y1315380
X0251265Y1300380
X0251265Y1302880
X0248765Y1302880
X0248765Y1300380
X0251265Y1305380
X0248765Y1305380
X0235465Y1315380
X0237965Y1315380
X0235465Y1307880
R02Y0002500
X0237965Y1312880
R02Y-0002500
X0251265Y1315380
X0248765Y1315380
X0251265Y1307880
R02Y0002500
X0248765Y1312880
R02Y-0002500
X0232965Y1312880
R03Y-0002500
X0232965Y1300380
X0232965Y1302880
X0237965Y1305380
X0235465Y1305380
X0237965Y1300380
X0237965Y1302880
X0235465Y1302880
X0235465Y1300380
X0419361Y1286219
X0416861Y1291219
X0414361Y1291219
X0419361Y1291219
X0419361Y1288719
X0400961Y1291319
X0403461Y1291319
X0395376Y1353233
X0398461Y1291319
X0398447Y1288762
X0398447Y1286262
X0251265Y1292880
X0251265Y1295380
X0248765Y1295380
X0248765Y1292880
X0251265Y1297880
X0248765Y1297880
X0235465Y1297880
X0237965Y1297880
X0232965Y1297880
X0419361Y1281219
X0419361Y1283719
X0414247Y1273662
R02Y0002500
X0416747Y1273662
X0419247Y1273662
X0419247Y1276162
X0419247Y1278662
X0416747Y1276162
X0416747Y1278662
X0414247Y1271162
X0416747Y1271162
X0403447Y1286180
X0400947Y1286180
X0403447Y1288680
X0400947Y1288680
X0403447Y1281180
X0403447Y1283680
X0400947Y1283680
X0400947Y1281180
X0416747Y1286180
X0414247Y1286180
X0416747Y1288680
X0414247Y1288680
X0416747Y1281180
X0416747Y1283680
X0414247Y1283680
X0414247Y1281180
X0398447Y1283762
X0398447Y1281262
X0398347Y1276162
X0398347Y1278662
X0400847Y1276162
X0400847Y1278662
X0403347Y1278662
X0403347Y1276162
X0398347Y1273662
X0400847Y1273662
X0398347Y1271162
X0400847Y1271162
X0403347Y1273662
X0403347Y1271162
X0383861Y1271788
X0386361Y1271788
X0381361Y1271788
X0368061Y1271788
X0370561Y1271788
X0353861Y1271688
X0351361Y1271688
X0365561Y1271788
X0362794Y1333902
X0348861Y1271688
X0337961Y1271688
X0335461Y1271688
X0332961Y1271688
X0329994Y1333702
X0318375Y1271688
X0315875Y1271688
X0320875Y1271688
X0300075Y1271688
X0297090Y1333759
X0302575Y1271688
X0305075Y1271688
X0287979Y1271773
X0282979Y1271773
X0285479Y1271773
X0272179Y1271773
X0269679Y1271773
X0264194Y1333787
X0267179Y1271773
X0414247Y1268662
X0398347Y1268662
X0400847Y1268662
X0398347Y1266162
X0400847Y1266162
X0403347Y1268662
X0403347Y1266162
X0386361Y1264288
X0386361Y1266788
X0386361Y1261788
X0386361Y1269288
X0383861Y1259188
X0383861Y1256688
X0386361Y1259188
X0386361Y1256688
X0381361Y1259188
X0381361Y1256688
X0370561Y1261706
R02Y0002500
X0368061Y1266706
R02Y-0002500
X0370561Y1269206
X0368061Y1269206
X0383861Y1261706
R02Y0002500
X0381361Y1266706
R02Y-0002500
X0383861Y1269206
X0381361Y1269206
X0370461Y1256688
X0370461Y1259188
X0367961Y1259188
X0367961Y1256688
X0365561Y1261788
X0365561Y1266788
X0365561Y1264288
X0365561Y1269288
X0353865Y1256631
X0353865Y1259131
X0351365Y1256631
X0351365Y1259131
X0353865Y1269131
X0353865Y1261631
X0353865Y1264131
X0353865Y1266631
X0365461Y1259188
X0365461Y1256688
X0348865Y1256631
X0348865Y1259131
X0337965Y1259131
X0337965Y1256631
X0332961Y1264188
X0332961Y1261688
X0332961Y1266688
X0332961Y1269188
X0335565Y1266649
R02Y-0002500
X0335565Y1269149
X0338065Y1261649
R03Y0002500
X0348865Y1266649
R02Y-0002500
X0348865Y1269149
X0351365Y1261649
R03Y0002500
X0332965Y1256631
X0332965Y1259131
X0335465Y1256631
X0335465Y1259131
X0315961Y1259131
X0315961Y1256631
X0320961Y1266631
X0320961Y1264131
X0318461Y1259131
X0318461Y1256631
X0320961Y1261631
R02Y-0002500
X0320961Y1269131
X0302561Y1259131
X0302561Y1256631
X0300061Y1264131
R03Y-0002500
X0305061Y1256631
X0305061Y1259131
X0300061Y1266631
X0300061Y1269131
X0305161Y1261649
R02Y0002500
X0302661Y1266649
R02Y-0002500
X0305161Y1269149
X0302661Y1269149
X0318461Y1261649
R02Y0002500
X0315961Y1266649
R02Y-0002500
X0318461Y1269149
X0315961Y1269149
X0288065Y1269216
X0288065Y1261716
X0288065Y1264216
X0288065Y1266716
X0288065Y1259216
R02X-0002500
X0288065Y1256716
R02X-0002500
X0267179Y1261773
R03Y0002500
X0272265Y1261734
R02Y0002500
X0269765Y1266734
R02Y-0002500
X0272265Y1269234
X0269765Y1269234
X0285565Y1261734
R02Y0002500
X0283065Y1266734
R02Y-0002500
X0285565Y1269234
X0283065Y1269234
X0272165Y1259216
X0269665Y1259216
X0272165Y1256716
X0383861Y1246688
X0386361Y1251688
X0383861Y1251688
X0386361Y1249188
X0383861Y1249188
X0386361Y1254188
X0383861Y1254188
X0381361Y1246688
X0381361Y1251688
X0381361Y1249188
X0381361Y1254188
X0370461Y1251688
X0370461Y1249188
X0370461Y1254188
X0367961Y1246688
R03Y0002500
X0351365Y1254131
X0353865Y1254131
X0351365Y1249131
X0353865Y1249131
X0351365Y1251631
X0353865Y1251631
X0353865Y1246631
X0351365Y1246631
X0365461Y1246688
R03Y0002500
X0348865Y1254131
X0348865Y1249131
X0348865Y1251631
X0348865Y1246631
X0337965Y1254131
X0337965Y1249131
X0337965Y1251631
X0332965Y1254131
X0335465Y1254131
X0332965Y1251631
X0335465Y1251631
X0332965Y1249131
X0335465Y1249131
X0332965Y1246631
X0335465Y1246631
X0318461Y1246631
X0315961Y1246631
X0320961Y1251631
R02X-0002500
X0320961Y1249131
R02X-0002500
X0315961Y1254131
X0320961Y1254131
X0318461Y1254131
X0302561Y1246631
X0300061Y1246631
X0305061Y1246631
X0302561Y1249131
X0300061Y1249131
X0302561Y1251631
X0300061Y1251631
X0305061Y1251631
X0305061Y1249131
X0302561Y1254131
X0300061Y1254131
X0305061Y1254131
X0285565Y1254216
X0288065Y1254216
X0283065Y1254216
X0283065Y1249216
X0285565Y1249216
X0288065Y1249216
X0283065Y1251716
R02X0002500
X0283065Y1246716
X0288065Y1246716
X0285565Y1246716
X0441159Y1051541
X0230594Y1379933
X1373785Y1349689
X1341203Y1330358
X1204612Y1376389
X1242603Y1330243
X1275499Y1330215
X1308403Y1330158
X1376774Y1355874
X1344192Y1336543
X1207601Y1382574
X1174801Y1382574
X1141901Y1382574
X1076601Y1382574
X1311392Y1336343
X1278488Y1336400
X1245592Y1336428
X1109201Y1382574
X1239550Y1437050
X1370012Y1344840
X1383466Y1352843
X1350884Y1333512
X1337430Y1325509
X1214293Y1379543
X1200839Y1371540
X1252284Y1333397
X1238830Y1325394
X1285180Y1333369
X1271726Y1325366
X1318084Y1333312
X1304630Y1325309
X1211555Y1380511
X1249546Y1334365
X1282442Y1334337
X1348146Y1334480
X1380728Y1353811
X1315346Y1334280
X1238731Y1422362
X1203040Y1437500
X1194000Y1437500
X1287600Y1427600
X0727292Y0430957
X1511917Y0483878
X1203117Y1422452
X1194000Y1424000
X1287600Y1423100
X1551779Y0530698
X1221837Y1438800
X1384216Y1355411
X1219500Y1436000
X1351634Y1336080
X1215043Y1382111
X1214900Y1439800
X1210400Y1440000
X1253034Y1335965
X1285930Y1335937
X1213000Y1435000
X1318834Y1335880
X1210100Y1436500
X1069839Y1368999
X1135139Y1368999
X1168039Y1368999
X1200839Y1368999
X1102439Y1368999
X1271726Y1322825
X1304630Y1322768
X1370012Y1342299
X1337430Y1322968
X1238830Y1322853
X1271042Y1418748
X1534584Y0467067
X0707500Y0386862
X1235400Y1391200
X1376774Y1353366
X1224200Y1393500
X1344192Y1334035
X1219500Y1398900
X1207601Y1380066
X1219650Y1392050
X1245592Y1333920
X1228800Y1391300
X1278488Y1333892
X1239800Y1389500
X1311392Y1333835
X1202411Y1427410
X1235679Y1418908
X1163422Y1445000
X1221203Y1317861
X1223703Y1317861
X1210403Y1317861
X1207903Y1317861
X1205403Y1315361
X1202332Y1379914
X1205403Y1317861
X1221203Y1305361
X1221203Y1300361
X1221203Y1302861
X1223703Y1305361
R02Y-0002500
X1205403Y1312861
R03Y-0002500
X1205403Y1300361
X1205403Y1302861
X1210403Y1315361
X1207903Y1315361
X1210403Y1307861
R02Y0002500
X1207903Y1312861
R02Y-0002500
X1223703Y1315361
X1221203Y1315361
X1223703Y1312861
R02Y-0002500
X1221203Y1307861
R02Y0002500
X1210403Y1305361
X1207903Y1305361
X1210403Y1300361
X1210403Y1302861
X1207903Y1302861
X1207903Y1300361
X1392876Y1291243
X1395376Y1291243
X1395376Y1286243
X1395376Y1288743
X1390376Y1291243
X1371505Y1353214
X1374576Y1291243
X1374576Y1286243
X1374576Y1288743
X1377076Y1291243
X1379576Y1291243
X1392876Y1278643
X1392876Y1276143
X1395376Y1278643
X1395376Y1276143
X1395376Y1283743
X1395376Y1281243
X1395376Y1271143
X1392876Y1271143
X1395376Y1273643
X1392876Y1273643
X1390376Y1278643
X1390376Y1276143
X1390376Y1271143
X1390376Y1273643
X1379476Y1276143
X1379476Y1278643
X1376976Y1278643
X1376976Y1276143
X1377076Y1288661
X1379576Y1281161
X1379576Y1283661
X1377076Y1283661
X1377076Y1281161
X1379576Y1286161
X1377076Y1286161
X1379576Y1288661
X1390376Y1286161
X1390376Y1288661
X1392876Y1286161
X1392876Y1288661
X1390376Y1283661
X1390376Y1281161
X1392876Y1281161
X1392876Y1283661
X1379476Y1271143
X1379476Y1273643
X1376976Y1271143
X1376976Y1273643
X1374476Y1278643
X1374476Y1276143
X1374576Y1281243
X1374576Y1283743
X1374476Y1271143
X1374476Y1273643
X1359990Y1271769
X1362490Y1271769
X1344190Y1271769
X1346690Y1271769
X1357490Y1271769
X1329990Y1271669
X1341690Y1271769
X1338923Y1333883
X1324990Y1271669
X1314090Y1271669
X1327490Y1271669
X1311590Y1271669
X1309090Y1271669
X1306123Y1333683
X1294504Y1271669
X1292004Y1271669
X1297004Y1271669
X1273219Y1333740
X1276204Y1271669
R02X0002500
X1261608Y1271754
X1259108Y1271754
X1264108Y1271754
X1240323Y1333768
X1243308Y1271754
R02X0002500
X1395376Y1268643
R02X-0002500
X1379476Y1268643
R02X-0002500
X1379476Y1266143
R02X-0002500
X1359990Y1259169
X1359990Y1256669
X1362490Y1259169
X1362490Y1256669
X1362490Y1264269
X1362490Y1266769
X1362490Y1261769
X1362490Y1269269
X1346590Y1256669
X1346590Y1259169
X1344090Y1259169
X1344090Y1256669
X1357490Y1259169
X1357490Y1256669
X1357490Y1266687
R02Y-0002500
X1357490Y1269187
X1346690Y1261687
R02Y0002500
X1344190Y1266687
R02Y-0002500
X1346690Y1269187
X1344190Y1269187
X1359990Y1261687
R03Y0002500
X1341590Y1259169
X1341590Y1256669
X1329994Y1269112
X1329994Y1261612
X1329994Y1264112
X1329994Y1266612
X1329994Y1256612
X1329994Y1259112
X1341690Y1261769
X1341690Y1266769
X1341690Y1264269
X1341690Y1269269
X1324994Y1256612
X1324994Y1259112
X1314094Y1259112
X1314094Y1256612
X1327494Y1256612
X1327494Y1259112
X1309094Y1256612
X1309094Y1259112
X1311594Y1256612
X1311594Y1259112
X1311694Y1266630
R02Y-0002500
X1311694Y1269130
X1327494Y1261630
R03Y0002500
X1314194Y1261630
R03Y0002500
X1324994Y1266630
R02Y-0002500
X1324994Y1269130
X1309090Y1264169
X1309090Y1261669
X1309090Y1266669
X1309090Y1269169
X1292090Y1259112
X1292090Y1256612
X1297090Y1266612
X1297090Y1264112
X1294590Y1259112
X1294590Y1256612
X1297090Y1261612
R02Y-0002500
X1297090Y1269112
X1281290Y1261630
R02Y0002500
X1278790Y1266630
R02Y-0002500
X1281290Y1269130
X1278790Y1269130
X1294590Y1261630
R02Y0002500
X1292090Y1266630
R02Y-0002500
X1294590Y1269130
X1292090Y1269130
X1278690Y1259112
X1278690Y1256612
X1276190Y1264112
R03Y-0002500
X1281190Y1256612
X1281190Y1259112
X1276190Y1266612
X1276190Y1269112
X1259194Y1259197
X1259194Y1256697
X1264194Y1266697
X1264194Y1264197
X1261694Y1259197
X1261694Y1256697
X1264194Y1261697
R02Y-0002500
X1264194Y1269197
X1248394Y1261715
R02Y0002500
X1245894Y1266715
R02Y-0002500
X1248394Y1269215
X1245894Y1269215
X1261694Y1261715
R02Y0002500
X1259194Y1266715
R02Y-0002500
X1261694Y1269215
X1259194Y1269215
X1245794Y1259197
X1243294Y1264197
X1243294Y1261697
X1248294Y1256697
X1248294Y1259197
X1243294Y1266697
X1243294Y1269197
X1359990Y1246669
X1362490Y1246669
X1362490Y1251669
X1359990Y1251669
X1362490Y1249169
X1359990Y1249169
X1362490Y1254169
X1359990Y1254169
X1346590Y1246669
X1346590Y1251669
X1346590Y1249169
X1346590Y1254169
X1344090Y1246669
R03Y0002500
X1357490Y1246669
X1357490Y1251669
X1357490Y1249169
X1357490Y1254169
X1341590Y1246669
R03Y0002500
X1329994Y1254112
X1329994Y1249112
X1329994Y1251612
X1329994Y1246612
X1324994Y1254112
X1324994Y1249112
X1324994Y1251612
X1324994Y1246612
X1314094Y1254112
X1314094Y1249112
X1314094Y1251612
X1314094Y1246612
X1327494Y1254112
X1327494Y1249112
X1327494Y1251612
X1327494Y1246612
X1309094Y1249112
X1311594Y1249112
X1309094Y1246612
X1311594Y1246612
X1309094Y1254112
X1311594Y1254112
X1309094Y1251612
X1311594Y1251612
X1294590Y1246612
X1297090Y1246612
X1292090Y1246612
X1297090Y1251612
R02X-0002500
X1297090Y1249112
R02X-0002500
X1292090Y1254112
X1297090Y1254112
X1294590Y1254112
X1278690Y1246612
X1276190Y1246612
X1281190Y1246612
X1278690Y1249112
X1276190Y1249112
X1278690Y1251612
X1276190Y1251612
X1281190Y1251612
X1281190Y1249112
X1278690Y1254112
X1276190Y1254112
X1281190Y1254112
X1264194Y1249197
R02X-0002500
X1259194Y1254197
X1264194Y1254197
X1261694Y1254197
X1261694Y1246697
X1264194Y1246697
X1259194Y1246697
X1264194Y1251697
R02X-0002500
X1417301Y1051540
X0269182Y0653709
X0301912Y0687950
X0433782Y0690100
X0400782Y0707900
X0367742Y0707832
X0334682Y0708100
X0395669Y0563328
X0395171Y0559463
X0388985Y0554870
X0331693Y0701915
X0529153Y0598735
X0463193Y0659315
X0298923Y0681765
X0266193Y0647524
X0430793Y0683915
X0397793Y0701715
X0364753Y0701647
X0495793Y0632815
X0272955Y0658558
X0259501Y0650555
X0305685Y0692799
X0292231Y0684796
X0437555Y0694949
X0424101Y0686946
X0404555Y0712749
X0391101Y0704746
X0371515Y0712681
X0358061Y0704678
X0338455Y0712949
X0325001Y0704946
X0426839Y0685978
X0393839Y0703778
X0262239Y0649587
X0294969Y0683828
X0327739Y0703978
X0360799Y0703710
X0404871Y0567338
X0359200Y0566990
X0322955Y0556148
X0349397Y0564459
X0258751Y0647987
X0377502Y0554193
X0291481Y0682228
X0375410Y0552254
X0423351Y0684378
X0371971Y0553138
X0370271Y0555038
X0390351Y0702178
X0357311Y0702110
X0368371Y0553038
X0365071Y0551038
X0324251Y0702378
X0272955Y0661099
X0371515Y0715222
X0469955Y0672890
X0502555Y0646390
X0539657Y0607658
X0535855Y0612290
X0437555Y0697490
X0404555Y0715290
X0338455Y0715490
X0305685Y0695340
X0364047Y0556773
X0351157Y0550415
X0733512Y0430957
X0735500Y0386862
X0650404Y0496102
X0384827Y0507057
X0395157Y0573815
X0410111Y0572608
X0640784Y0395957
X0266193Y0650032
X0379689Y0586040
X0377577Y0590126
X0298923Y0684273
X0430793Y0686423
X0378577Y0593026
X0397793Y0704223
X0373477Y0593338
X0364753Y0704155
X0369271Y0600138
X0331693Y0704423
X0368798Y0587938
X0362200Y0566750
X0587829Y0445138
X0345521Y0564388
X0636055Y0528605
X0796283Y0423344
X0263391Y0722237
X0265891Y0722237
X0263287Y0732260
X0265787Y0732260
X0263287Y0729760
X0265787Y0729760
X0263287Y0727260
X0265787Y0727260
X0263287Y0724760
X0265787Y0724760
X0250091Y0722237
X0252591Y0722237
X0252587Y0729760
X0252587Y0727260
X0250087Y0727260
X0247587Y0729760
X0250087Y0729760
X0247587Y0727260
X0247587Y0722260
X0250087Y0724760
X0252587Y0724760
X0247587Y0724760
X0263287Y0734760
X0265787Y0734760
X0263287Y0737260
X0265787Y0737260
X0282817Y0761610
X0280317Y0761610
X0280317Y0749110
X0280317Y0754110
X0280317Y0751610
X0280317Y0756610
X0280317Y0746478
R02X0002500
X0282821Y0756478
X0285321Y0756478
X0282821Y0748978
R02Y0002500
X0285321Y0753978
R02Y-0002500
X0285317Y0761610
X0282817Y0759110
X0285317Y0759110
X0280317Y0759110
X0298621Y0751478
X0298621Y0748978
X0298617Y0761610
X0301117Y0761610
X0298617Y0759110
X0301117Y0759110
X0296117Y0761610
X0296117Y0759110
X0301117Y0746478
X0296117Y0746478
X0298617Y0746478
X0301117Y0764110
X0298617Y0764110
X0298617Y0766610
X0296117Y0769110
X0296117Y0771610
X0301117Y0769110
X0298617Y0769110
X0298617Y0771610
X0301117Y0771610
X0296117Y0764110
X0296117Y0766610
X0301117Y0766610
X0301121Y0756496
R03Y-0002500
X0296121Y0756478
X0298621Y0756478
X0296121Y0748978
R02Y0002500
X0298621Y0753978
X0318087Y0781660
X0318087Y0779160
X0318087Y0784160
X0318087Y0786660
X0313087Y0779160
X0315587Y0781660
X0313087Y0781660
X0315587Y0786660
X0313087Y0786660
X0315587Y0784160
X0313087Y0784160
X0315587Y0779160
X0315587Y0789160
X0313087Y0789160
X0318087Y0789160
X0315587Y0791660
X0313087Y0791660
X0318087Y0791660
X0318087Y0766628
X0315587Y0766628
X0313087Y0766628
X0315591Y0776628
X0318091Y0776628
X0315591Y0769128
R02Y0002500
X0318091Y0774128
R02Y-0002500
X0313087Y0776660
R03Y-0002500
X0331387Y0784160
X0328887Y0784160
X0333887Y0784160
X0331387Y0786660
X0328887Y0786660
X0333887Y0786660
X0331387Y0781660
X0328887Y0781660
X0328887Y0779160
X0331387Y0779160
X0333887Y0781660
X0333887Y0779160
X0331387Y0789160
X0328887Y0789160
X0333887Y0789160
X0331387Y0791660
X0328887Y0791660
X0333887Y0791660
X0333891Y0769146
R03Y0002500
X0331387Y0766628
X0328887Y0766628
X0333887Y0766628
X0328891Y0776628
X0331391Y0776628
X0328891Y0769128
R02Y0002500
X0331391Y0774128
R02Y-0002500
X0351051Y0781558
X0351051Y0779058
X0351051Y0786558
X0351051Y0784058
X0351051Y0789058
X0348551Y0781558
X0346051Y0781558
X0348551Y0779058
X0346051Y0779058
X0348551Y0786558
X0346051Y0786558
X0348551Y0784058
X0346051Y0784058
X0348551Y0789058
X0346051Y0789058
X0351051Y0791558
R02X-0002500
X0346147Y0766540
R02X0002500
X0348651Y0776540
X0351151Y0776540
X0348651Y0769040
R02Y0002500
X0351151Y0774040
R02Y-0002500
X0346051Y0776558
R03Y-0002500
X0361951Y0784058
X0361951Y0779058
X0364451Y0781558
X0364451Y0779058
X0361951Y0781558
X0364451Y0784058
X0361951Y0786558
X0361951Y0789058
X0364451Y0789058
X0364451Y0786558
X0361951Y0791558
X0364451Y0791558
X0361947Y0766540
X0364447Y0766540
X0361951Y0776540
X0364451Y0776540
X0361951Y0769040
R02Y0002500
X0364451Y0774040
R02Y-0002500
X0366951Y0779058
X0379187Y0791460
X0366951Y0791558
X0366947Y0766540
X0379187Y0776460
R03Y-0002500
X0379187Y0766428
X0366951Y0776558
R03Y-0002500
X0379187Y0781460
X0379187Y0778960
X0379187Y0788960
X0379187Y0783960
X0379187Y0786460
X0366951Y0784058
X0366951Y0789058
X0366951Y0786558
X0366951Y0781558
X0384187Y0781460
X0384187Y0778960
X0384187Y0783960
R02Y0002500
X0381687Y0781460
X0381687Y0788960
X0381687Y0783960
X0381687Y0786460
X0381687Y0778960
X0394987Y0786560
X0394987Y0789060
X0394987Y0781560
X0394987Y0779060
X0394987Y0784060
X0384187Y0791460
X0381687Y0791460
X0381691Y0776428
X0384191Y0776428
X0381691Y0768928
R02Y0002500
X0384191Y0773928
R02Y-0002500
X0394991Y0776428
X0394991Y0768928
X0394991Y0771428
X0394991Y0773928
X0384187Y0766428
X0381687Y0766428
X0394987Y0766428
X0399991Y0774060
X0399987Y0766428
X0399991Y0769060
X0399991Y0771560
X0397487Y0766428
X0399991Y0781560
X0399991Y0779060
X0399991Y0784060
X0397487Y0784060
X0397487Y0786560
X0397487Y0781560
X0397487Y0779060
X0397491Y0776428
R03Y-0002500
X0399991Y0776560
X0415158Y0766175
X0415158Y0763675
X0417662Y0758643
X0420162Y0758643
X0417662Y0751143
R02Y0002500
X0420162Y0756143
R02Y-0002500
X0415158Y0758675
X0417658Y0761175
X0420158Y0761175
X0415158Y0761175
X0415158Y0748643
X0417658Y0748643
X0415158Y0753675
X0415158Y0751175
X0415158Y0756175
X0420158Y0748643
X0417658Y0766175
X0417658Y0763675
X0415158Y0768675
X0417658Y0768675
X0420158Y0766175
X0420158Y0763675
X0415158Y0771175
X0430962Y0758643
X0430962Y0751143
X0430962Y0753643
X0430962Y0756143
X0433462Y0756143
R02Y-0002500
X0433458Y0748643
X0430958Y0748643
X0440159Y0985341
R02Y-0007500
X0271462Y0650184
X0370022Y0704307
X0436062Y0686575
X0252587Y0712237
R02X-0002500
X0265887Y0712237
X0263387Y0712237
X0250091Y0714737
R02Y0002500
X0252591Y0719737
R02Y-0002500
X0263391Y0714737
R02Y0002500
X0265891Y0719737
R02Y-0002500
X0247587Y0717260
X0247587Y0714760
X0247587Y0719760
X0403062Y0704375
X0336962Y0704575
X0304192Y0684425
X1379734Y0623043
X1412434Y0655943
X1543834Y0708100
X1511034Y0708100
X1477952Y0708100
X1445034Y0688523
X1507644Y0554372
X1507109Y0550059
X1442045Y0682338
X1639745Y0627206
X1376745Y0616858
X1409445Y0649758
X1540845Y0701915
X1508045Y0701915
X1606745Y0646206
X1573975Y0679975
X1474963Y0701915
X1502085Y0545432
X1370053Y0619889
X1383507Y0627892
X1416207Y0660792
X1402753Y0652789
X1547607Y0712949
X1534153Y0704946
X1514807Y0712949
X1501353Y0704946
X1481725Y0712949
X1468271Y0704946
X1448807Y0693372
X1435353Y0685369
X1504091Y0703978
X1536891Y0703978
X1405491Y0651821
X1372791Y0618921
X1519457Y0556338
X1438091Y0684401
X1471009Y0703978
X1473362Y0558380
X1539693Y0558943
X1462497Y0555021
X1369303Y0617321
X1490602Y0544755
X1402003Y0650221
X1488510Y0542816
X1533403Y0702378
X1484416Y0541658
X1500603Y0702378
X1482044Y0542517
X1467521Y0702378
X1481257Y0544977
X1434603Y0682801
X1478257Y0543977
X1547607Y0715490
X1514807Y0715490
X1646507Y0640781
X1613507Y0659781
X1580737Y0693550
X1481725Y0715490
X1448807Y0695913
X1416207Y0663333
X1383507Y0630433
X1478147Y0547728
X1472647Y0539478
X1473408Y0547948
X1417000Y0460362
X0765008Y0424657
X1023320Y0451112
X1507468Y0564357
X1519120Y0479215
X1519317Y0561977
X0715500Y0386862
X1376757Y0619497
X1492789Y0576602
X1409445Y0652266
X1490677Y0580688
X1540845Y0704423
X1491677Y0583588
X1487660Y0585748
X1508045Y0704423
X1475009Y0704488
X1484347Y0580388
X1481898Y0585476
X1442091Y0684846
X1473444Y0555208
X1456500Y0457000
X0698946Y0471822
X1406643Y0721971
X1406643Y0724471
X1395843Y0721971
X1395843Y0724471
X1409143Y0721971
X1409143Y0724471
X1409167Y0727023
X1406667Y0729523
X1406667Y0732023
X1409167Y0729523
X1409167Y0732023
X1406667Y0727023
X1395867Y0729523
X1395867Y0727023
X1395867Y0732023
X1390853Y0727053
X1390807Y0724553
X1390807Y0722053
X1393343Y0721971
X1393343Y0724471
X1393367Y0729523
X1393367Y0727023
X1348301Y0871265
R02X-0003500
X1406667Y0739523
R02Y-0002500
X1409167Y0737023
X1409167Y0734523
X1409167Y0739523
X1423407Y0754633
R02Y-0002500
X1423407Y0757133
X1423417Y0747051
X1416301Y0985340
R02Y-0007500
X1439257Y0767133
X1439257Y0769633
X1439257Y0764633
X1439243Y0754551
R02Y-0002500
X1439243Y0757051
X1428443Y0749551
R02Y0002500
X1425943Y0754551
R02Y-0002500
X1428443Y0757051
X1425943Y0757051
X1439257Y0759633
X1439257Y0762133
X1425907Y0759633
X1428407Y0759633
X1428407Y0762133
X1428417Y0747051
X1425917Y0747051
X1439227Y0747051
X1441757Y0767133
X1441757Y0769633
X1441757Y0764633
X1441757Y0772133
X1444257Y0767133
X1444257Y0769633
X1444257Y0764633
X1444257Y0772133
X1441743Y0749551
R03Y0002500
X1441757Y0762133
X1441757Y0759633
X1444257Y0762133
R02Y-0002500
X1441727Y0747051
X1456335Y0769210
X1456335Y0774210
X1456335Y0776710
X1458835Y0766628
X1461335Y0766628
X1461361Y0769128
R02Y0002500
X1458861Y0774128
R02Y-0002500
X1461361Y0776628
X1458861Y0776628
X1456371Y0784210
R02Y-0002500
X1461371Y0781696
X1461371Y0786696
X1461371Y0784196
X1458871Y0786696
X1458871Y0781696
X1458871Y0784196
X1461371Y0779196
X1458871Y0779196
X1461371Y0789196
X1461371Y0791696
X1456335Y0766628
X1456335Y0771710
X1474671Y0784196
X1477171Y0784196
X1474671Y0779196
X1477171Y0779196
X1474671Y0789196
X1477171Y0789196
X1472171Y0781696
X1472171Y0786696
X1472171Y0784196
X1472171Y0779196
X1472171Y0789196
X1474671Y0781696
X1477171Y0781696
X1474671Y0786696
X1477171Y0786696
X1472171Y0791696
R02X0002500
X1477145Y0766628
R02X-0002500
X1472161Y0774128
R02Y-0002500
X1472161Y0776628
X1474661Y0769128
R03Y0002500
X1477171Y0776696
X1477171Y0769196
X1477171Y0771696
X1477171Y0774196
X1489487Y0781710
X1489487Y0786710
X1489487Y0784210
X1489487Y0779210
X1491987Y0781710
X1491987Y0786710
X1491987Y0784210
X1491987Y0779210
X1494487Y0781710
X1494487Y0786710
X1494487Y0784210
X1494487Y0779210
X1489417Y0766628
X1489417Y0771710
X1489417Y0769210
X1489417Y0774210
X1489417Y0776710
X1491917Y0766628
X1494417Y0766628
X1494443Y0769128
R02Y0002500
X1491943Y0774128
R02Y-0002500
X1494443Y0776628
X1491943Y0776628
X1507787Y0784210
X1507787Y0779210
X1510287Y0781710
X1510287Y0786710
X1510287Y0784210
X1510287Y0779210
X1505287Y0781710
X1505287Y0786710
X1505287Y0784210
X1505287Y0779210
X1507787Y0781710
X1507787Y0786710
X1510227Y0766628
R02X-0002500
X1505243Y0774128
R02Y-0002500
X1505243Y0776628
X1507743Y0769128
R03Y0002500
X1510287Y0776710
X1510287Y0774210
X1510287Y0769210
X1510287Y0771710
X1522217Y0781710
X1524717Y0781710
X1522217Y0786710
X1522217Y0784210
X1524717Y0786710
X1524717Y0784210
X1522217Y0779210
X1524717Y0779210
X1527217Y0781710
X1527217Y0786710
X1527217Y0784210
X1527217Y0779210
X1527243Y0769128
R02Y0002500
X1524743Y0774128
R02Y-0002500
X1527243Y0776628
X1524743Y0776628
X1522217Y0776710
X1522217Y0774210
X1522217Y0766628
X1524717Y0766628
X1522217Y0769210
X1527217Y0766628
X1522217Y0771710
X1540527Y0781710
X1538027Y0781710
X1540527Y0779210
X1538027Y0779210
X1538027Y0784710
X1538043Y0774128
R02Y-0002500
X1538043Y0776628
X1540543Y0769128
R03Y0002500
X1540527Y0766628
X1538027Y0766628
X1382014Y0619518
X1447314Y0684998
X1360935Y0681573
X1358435Y0681573
X1376745Y0681573
X1363435Y0681573
X1374245Y0681573
X1406627Y0714471
X1393317Y0714471
X1395817Y0714471
X1409127Y0714471
X1390817Y0714471
X1390807Y0717053
X1390807Y0719553
X1374261Y0689073
R02Y-0002500
X1374261Y0691573
X1363461Y0684073
R02Y0002500
X1360961Y0689073
R02Y-0002500
X1363461Y0691573
X1360961Y0691573
X1376761Y0684073
R03Y0002500
X1406643Y0719471
X1406643Y0716971
X1395843Y0716971
X1395843Y0719471
X1393343Y0719471
X1393343Y0716971
X1409143Y0716971
X1409143Y0719471
X1358461Y0686651
X1358461Y0684151
X1363461Y0699151
X1360961Y0696651
X1363461Y0696651
X1358461Y0691651
X1358461Y0689151
X1360961Y0694151
X1363461Y0694151
X1358461Y0694151
X1374261Y0704151
X1374261Y0701651
X1374261Y0706651
X1376761Y0704151
X1376761Y0701651
X1376761Y0706651
X1374261Y0699151
X1376761Y0699151
X1374261Y0696651
X1376761Y0696651
X1374261Y0694151
X1376761Y0694151
X1546114Y0704575
X1513314Y0704575
X1480232Y0704575
X1414714Y0653008
X0811771Y1355488
X0754532Y0735859
X0854484Y0647436
X0833807Y0423257
X0712164Y0676912
X0267601Y0608378
X0771718Y0426804
X0752409Y0440405
X0273208Y0588237
X0803412Y0403978
X0785529Y0270459
X0294299Y0577188
X0366671Y0803588
X0371671Y0803588
X0517009Y0856494
X0588500Y0812093
X0596821Y0802688
X0615571Y0788448
X0609402Y0788678
X0600337Y0800649
X0592572Y0809088
X0376671Y0803588
X0351671Y0803588
X0356671Y0803588
X0361671Y0803588
X0925500Y0907500
X0938500Y0907500
X0211326Y0606918
X0208326Y0606918
X0223202Y0609681
R03X-0003000
X0226599Y0570970
X0150900Y1425500
X0097800Y1433000
X0086827Y1404080
X0824444Y1249420
X0443764Y1179395
X0606619Y1278302
X0605771Y1263098
X0618761Y1278668
X0618761Y1266988
X0595532Y1262668
X0574200Y1229900
X0570775Y1263008
X0616629Y1375082
X0035040Y1295380
X0035080Y1298360
X0035040Y1292433
X0376271Y1207488
X0367931Y1196981
X0370316Y1204673
X0363236Y1199632
X0347107Y1174343
X0057747Y1270470
X0035010Y1289485
X0211254Y0603245
X0208254Y0603245
X0208254Y0595145
X0211254Y0595145
X0220111Y0603782
X0228895Y0609691
X0225895Y0609691
X0223111Y0603782
X0214202Y0606943
X0223202Y0606943
X0220202Y0606943
X0217202Y0606943
X0220999Y0585668
X0223999Y0585668
X0217999Y0585668
X0206933Y0737277
X0260971Y0777988
X0270850Y0797605
X0281449Y0809609
X0424873Y1014745
X0415318Y1006025
X0415318Y1009765
X0453723Y0526558
X0359657Y0570702
X0403381Y0573516
X0351157Y0566936
X0227024Y0622385
X0224024Y0622385
X0227024Y0632385
X0224024Y0632385
X0221024Y0622385
X0218024Y0622385
X0218024Y0632385
X0221024Y0632385
X0208009Y0610001
X0211009Y0610001
X0214999Y0585668
X0716313Y0610134
X0720500Y0546211
X0529317Y0403784
X1090086Y0370417
X0515523Y0335613
X0661813Y1370081
X0940937Y1294191
X0866294Y1255903
X1329585Y0561806
X1309870Y0552788
X1141267Y0500296
X0780577Y0435564
X1309776Y0559831
X1401015Y1014744
X0571427Y0217771
X0504351Y0215901
X0487442Y0223377
X0480715Y0211099
X0480700Y0208200
X1313544Y0613100
X0987581Y0408332
X0984605Y0408480
X1009815Y0404896
X1071656Y0366726
X1007080Y0367087
X0949500Y0886500
X0913000Y0909000
X0951169Y0910425
X0953925Y0900500
X0964075Y0900500
X0921000Y0921925
X0940919Y1290152
X0960313Y1362654
X1198800Y1421500
X1183000Y1422900
X1253100Y1413500
X1464257Y0557498
X1472757Y0561264
X1308776Y0599181
X1309166Y0601713
X1317266Y0597213
X1317266Y0600213
X1321300Y0625200
R02Y-0003000
X1318300Y0619200
R02Y0003000
X1308800Y0625200
R02Y-0003000
X1337801Y0867765
X1341301Y0867765
X1334301Y0867765
X1391460Y1006024
X1391460Y1009764
X1266677Y0802988
X1251177Y0794878
X1259297Y0798784
X1254981Y0787578
X1238257Y0779728
X1244127Y0784598
X1322420Y0656867
X1474177Y0816872
X1481177Y0803488
X1502177Y0817013
X1551124Y0801289
X1570583Y0800104
X1556121Y0798542
X1487923Y0816770
X1485177Y0803488
X1309600Y0667700
X1292297Y0657206
X1295000Y0655200
X1301900Y0660699
X1297400Y0599413
X1300400Y0599413
X1307544Y0607100
X1307544Y0604100
X1307544Y0616100
R02Y-0003000
X1310544Y0604100
X1313544Y0604100
X1310544Y0607100
X1313544Y0607100
X1310544Y0610100
X1313544Y0610100
X1310544Y0613100
X1313544Y0616100
X1310544Y0616100
X1325366Y0597213
X1325366Y0600213
X1150118Y0212344
X1150118Y0207344
X0471015Y0527283
X0909747Y0628426
X0906706Y0614062
X0706387Y0621686
X0715037Y0606428
X0748482Y0557085
X0756500Y0545862
X0758103Y0556873
X0724433Y0530870
X0845094Y0535110
X0860658Y0515961
X0827832Y0554269
X0905526Y0594657
X0835519Y0580056
X0909747Y0579695
X0930406Y0577308
X1072135Y0396908
X1074736Y0396929
X1121628Y0401915
X1124270Y0404640
X1049573Y0406586
X1006206Y0510304
X1045254Y0516014
X1045254Y0526074
X1045254Y0534074
X1037301Y0539685
X1047200Y0543090
X1047335Y0549574
X1154145Y0586339
X1154145Y0583339
X1157038Y0586298
X1157038Y0583298
X1031000Y0568500
X0532222Y0207849
X0533543Y0404130
X0722201Y0579306
X1039000Y0555000
X0720500Y0555862
X1684925Y0123762
X1684925Y0145762
X1572549Y0257491
X1572502Y0254250
X1533160Y0231250
X1527392Y0238017
X1537450Y0226293
X1517708Y0216505
X1554360Y0207251
X1449769Y0182217
X1439769Y0182217
X1453974Y0174414
X1444769Y0174217
X1456226Y0152166
X1440871Y0152166
X1429169Y0107313
X1463017Y0139518
X1596462Y0229790
X1578336Y1359253
X1586557Y1304509
X1605360Y1294595
X1608901Y1285887
X1591005Y1288892
X1580010Y1296100
X1568100Y1290418
X1594152Y1282578
X1578690Y1283310
X1588832Y1269083
X1557559Y1269095
X1543772Y1241016
X1631928Y1260917
R02X-0002500
X1634428Y1260917
X1692974Y0553115
R03X0004000
X1575570Y0497847
X1570570Y0497847
X1573070Y0497847
X1568070Y0497847
X1595438Y1370603
X1605648Y1437305
X1627217Y1428366
X1562937Y1341609
X1355641Y1210674
X1672501Y1416678
X1333977Y1222158
X1331202Y1206478
X0742212Y1394517
X0709430Y1394417
X0652651Y1375308
X0653117Y1378037
X0745201Y1400702
X0712419Y1400602
X0647401Y1384160
X0738439Y1389668
X0751893Y1397671
X0705657Y1389568
X0719111Y1397571
X0653101Y1369862
X0653149Y1372500
X0716373Y1398539
X0749155Y1398639
X0624795Y1373257
X0753309Y0655515
X0717843Y0468672
X0733382Y0633574
X0822794Y0795011
X0608148Y1373890
X0685448Y1423137
X0752643Y1400239
X0638053Y1384491
X0634995Y1384457
X0719861Y1400139
X0738439Y1387127
X0705657Y1387027
X0630195Y1384263
X0875412Y0797350
X0731208Y0398737
X0870064Y0427703
X0622352Y1393285
X0714259Y1447483
X0651973Y1363038
X0822794Y0800011
X0640076Y0497964
X0711500Y0386862
X0730837Y0678940
X0661719Y1363394
X0745201Y1398194
X0634776Y1353739
X0712419Y1398094
X0633406Y1358576
X0624976Y1378313
X0781812Y0341863
X0780877Y0427344
X0683391Y1420531
X0653376Y1365793
X0823927Y0907676
X0919500Y0941500
X0901842Y0936863
X0932500Y0941500
X0770881Y1343344
X0770881Y1345844
X0762261Y1343424
X0762261Y1345924
X0730795Y1342444
X0739501Y1342244
X0735739Y1323048
X0739501Y1344744
X0730795Y1344944
X0706351Y1397588
X0710221Y1344988
X0701771Y1344988
X0683052Y1345048
X0674552Y1344988
X0762754Y1332314
X0762754Y1329814
X0762754Y1334814
X0762844Y1339824
X0762844Y1337324
X0742971Y1332124
X0742971Y1329624
X0742971Y1334624
X0742971Y1339624
X0742971Y1337124
X0748188Y1335517
X0745691Y1337424
X0745691Y1339924
X0739932Y1398042
X0748188Y1330517
X0748188Y1333017
X0745691Y1334924
X0745691Y1329924
X0745691Y1332424
X0757638Y1335517
X0760194Y1337524
X0760194Y1340024
X0757638Y1330517
X0757638Y1333017
X0760204Y1335014
X0760204Y1330014
X0760204Y1332514
X0730021Y1332230
X0730021Y1329730
X0730021Y1334730
X0730021Y1339730
X0730021Y1337230
X0710288Y1329677
R02Y0002500
X0710221Y1342488
X0710288Y1337177
X0710288Y1339677
X0715828Y1335377
X0713008Y1339877
X0713008Y1337377
X0715828Y1330377
X0715828Y1332877
X0713008Y1334877
R02Y-0002500
X0724788Y1335377
X0727401Y1337430
X0727401Y1339930
X0724788Y1332877
X0724788Y1330377
X0727401Y1334930
X0727401Y1329930
X0727401Y1332430
X0699868Y1334627
X0702388Y1334627
X0699868Y1332127
X0702388Y1332127
X0699868Y1329627
X0702388Y1329627
X0699868Y1339627
X0699868Y1337127
X0702388Y1339627
X0702388Y1337127
X0701771Y1342488
X0682348Y1337117
X0684868Y1339617
X0684868Y1337117
X0682348Y1334617
X0684868Y1334617
X0682348Y1332117
X0684868Y1332117
X0682348Y1329617
X0684868Y1329617
X0683052Y1342548
X0682348Y1339617
X0674552Y1342488
X0769439Y1316948
X0769439Y1322948
X0769439Y1319948
X0759839Y1322948
X0757638Y1327317
X0759839Y1316948
X0762754Y1327314
X0760204Y1327314
X0759839Y1319948
X0745439Y1317048
R02Y0003000
X0742971Y1327124
X0745491Y1327124
X0748188Y1327317
X0730021Y1327230
X0727501Y1327230
X0724788Y1327277
X0735739Y1317048
X0735739Y1320048
X0711839Y1317348
R02Y0003000
X0713008Y1327177
X0710488Y1327177
X0715828Y1327277
X0721339Y1317048
R02Y0003000
X0697461Y1317008
X0699868Y1327127
X0702388Y1327127
X0697461Y1323008
X0697461Y1320008
X0682348Y1327117
X0684868Y1327117
X0687961Y1317308
X0687961Y1323308
X0687961Y1320308
X0769439Y1313948
X0828109Y1234504
X0759839Y1313948
X0745439Y1314048
X0735739Y1314048
X0711839Y1314348
X0721339Y1314048
X0697461Y1314008
X0687961Y1314308
X0457472Y1032431
X0465965Y1032206
X0449992Y1032431
X0446252Y1032431
X0442884Y1042766
X0442511Y1032431
X0442884Y1038766
X0453732Y1032431
X0427551Y1032431
X0438771Y1032431
R02X-0003740
X0423811Y1032431
X0418918Y1032206
X0443574Y1023013
X0453810Y1023013
X0434716Y1023013
X0434716Y1018879
X0314780Y0545716
X0716721Y0627907
X0720787Y0627907
X0722129Y0666725
X0685786Y0680936
X0701233Y0655355
X0649922Y0545610
X0718129Y0666725
X0667101Y0736071
X0182500Y0672500
X0172500Y0684799
X0131960Y0679290
X1689945Y1393806
X1657163Y1393706
X1663239Y1428592
X1671079Y1435069
X1692934Y1399991
X1658089Y1437444
X1660152Y1399891
X1686172Y1388957
X1699626Y1396960
X1666844Y1396860
X1653390Y1388857
X1662487Y1424178
X1664106Y1397828
X1696888Y1397928
X1664237Y1426278
X1635281Y1422450
X0822982Y0791245
X0750062Y0655415
X0717843Y0471822
X1134183Y1483926
X1650400Y1437820
X1700376Y1399528
X1645979Y1437950
X1667594Y1399428
X1653390Y1386316
X1686172Y1386416
X1642400Y1439674
X1639834Y1434478
X0727292Y0437256
X1503785Y0464815
X1636167Y1446746
X1661807Y1416948
X0715500Y0390862
X0714867Y0344943
X1672401Y1423365
X1063356Y0318297
X1614701Y0422587
X1011423Y0282889
X0779681Y0313053
X0758245Y0343763
X1646483Y1412741
X1692934Y1397483
X1644001Y1408069
X1660152Y1397383
X1635619Y1430536
X1505974Y0470636
X0796283Y0415344
X1622697Y1440797
X1663777Y1421568
X1732702Y1313007
X1732702Y1319007
X1732702Y1322007
X1732702Y1316007
X1718706Y1344129
X1718706Y1341629
X1710176Y1344589
X1710176Y1342089
X1699072Y1313737
X1811526Y1281671
X1792895Y0683536
X1745484Y0668216
X1709759Y0670221
X1442107Y1032205
X1411173Y1032430
X1399953Y1032430
X1395060Y1032205
X1403693Y1032430
X1407433Y1032430
X1429952Y1023012
X1410858Y1018878
X1419716Y1023012
X1410858Y1023012
X1654883Y1397231
X1658677Y1344488
R02X-0008500
X1717396Y1331559
X1717396Y1334059
X1719916Y1334059
X1719916Y1331559
X1710536Y1331619
X1710536Y1334119
X1717396Y1336559
X1719916Y1336559
X1717396Y1339059
X1719916Y1339059
X1710536Y1339119
X1710536Y1336619
X1690697Y1339066
X1679028Y1344233
X1687234Y1344033
X1687234Y1341533
X1679028Y1341733
X1690697Y1331566
R02Y0002500
X1677754Y1334019
X1677754Y1331519
X1677754Y1336519
X1677754Y1339019
X1658015Y1333966
X1658015Y1331466
X1658015Y1338966
X1658015Y1336466
X1658277Y1341888
X1650177Y1341488
X1641677Y1341488
X1708672Y1316737
X1717396Y1329059
X1719916Y1329059
X1717396Y1326559
X1719916Y1326559
X1722672Y1322237
X1722672Y1319237
X1710536Y1326619
X1708016Y1326619
X1710536Y1329119
X1708672Y1319737
X1708672Y1322737
X1722672Y1316237
X1699072Y1316737
R02Y0003000
X1693217Y1326566
X1687665Y1397331
X1693417Y1339266
X1693417Y1336766
X1705383Y1332176
X1696047Y1329676
X1696047Y1332176
X1705383Y1329676
X1696047Y1334676
X1705383Y1334676
X1693417Y1331766
X1693417Y1334266
X1693417Y1329266
X1707916Y1336819
X1707916Y1339319
X1707916Y1331819
X1707916Y1334319
X1707916Y1329319
X1705383Y1326576
X1696047Y1326576
X1684672Y1316837
R02Y0003000
X1690697Y1326566
X1690697Y1329066
X1677754Y1329019
X1677754Y1326519
X1674972Y1322837
X1674972Y1319837
X1663437Y1326526
X1672623Y1326476
X1674972Y1316837
X1675234Y1326519
X1658115Y1326466
X1658015Y1328966
X1660572Y1316837
X1660635Y1326466
X1660572Y1319837
X1660572Y1322837
X1651072Y1317137
R02Y0003000
X1708672Y1313737
X1722672Y1313237
X1684672Y1313837
X1674972Y1313837
X1660572Y1313837
X1651072Y1314137
X1539301Y1175765
X1537301Y1178265
X1540801Y1178265
X1660635Y1336666
X1660635Y1339166
X1660635Y1334166
R02Y-0002500
X1675134Y1329219
X1675134Y1339219
X1675134Y1336719
R02Y-0002500
X1672623Y1329676
X1663437Y1332226
X1672623Y1332176
X1663437Y1329726
X1672623Y1334676
X1663437Y1334726
X1429874Y1032430
X1433614Y1032430
X1426134Y1032430
X1418653Y1032430
X1414913Y1032430
X1419026Y1042765
X1419026Y1038765
X1422394Y1032430
X1326636Y0656800
X1166131Y0580602
X1205900Y0582443
X1419335Y0533958
X1600918Y0521688
X1166026Y0669006
X1228372Y0688501
X1501500Y0799948
X1539972Y0807319
X1231397Y0769667
X0976528Y0808541
X0940000Y0986500
X0940000Y0973500
X0899500Y0853000
X0918500Y0860075
X0917000Y0853000
X0976528Y0806041
R02Y-0002500
X0936454Y0184015
X0373330Y1668539
X0765008Y0481271
X0772390Y0491047
X0984272Y0349293
X0990292Y0494420
X1603970Y0222956
X1673100Y0131762
X0271245Y0785474
X0659095Y0381020
X0447084Y0511870
X1673100Y0136762
X1435400Y0530800
X1303250Y0655149
X0747488Y0071429
X0596944Y1270115
X0791308Y0766871
X1767450Y0766870
X0761608Y0766871
X1737850Y0766794
X0731462Y0766871
X1708049Y0766870
X0702206Y0766871
X1678348Y0766870
X0672505Y0766871
X1648647Y0766870
X0642804Y0766871
X1617200Y0766870
X0061620Y0768510
X1040915Y0766870
X0094474Y0766871
X1070616Y0766870
X0124174Y0766871
X1100316Y0766870
X0153875Y0766871
X1130017Y0766870
X0183576Y0766871
X1159718Y0766870
X0212772Y0766871
X1188805Y0766870
X1045545Y1663089
X0921289Y1666337
X0663915Y0234476
X0702095Y0440405
X1635697Y0561253
X1604890Y0531226
X1616198Y0556364
X1616084Y0549105
X0542071Y0593089
X0815287Y0580401
X0653368Y0581468
X0414402Y0544690
X1609044Y0600986
X1618434Y0605753
X1636022Y0606126
X1367950Y0066886
X1355750Y0066886
X1263472Y0092864
X0553578Y0193541
X0554196Y0190256
X0550553Y0197778
X0550553Y0200304
X0559484Y0156667
X1438262Y0052892
X1673403Y0199997
X1631200Y0164110
X0412370Y0188210
X1654147Y0616523
X1628512Y0603015
R02X-0003500
X1632012Y0603015
X1651194Y0609450
X1635944Y0612510
X1635944Y0609510
X1618356Y0609137
X1618356Y0612137
X1651194Y0599956
X1657194Y0599956
X1654194Y0599956
X1657194Y0609450
X1660194Y0599956
X1654194Y0609450
X1660194Y0609450
X1516336Y0551977
X0924367Y0503407
X0924430Y0507156
X0921367Y0503407
X0921430Y0507156
X1085622Y0520652
X1085438Y0524033
X1082438Y0524033
X1082622Y0520652
X0940994Y1265636
X0973650Y1431424
X1262310Y1428303
X0692376Y1438326
X0665167Y1376836
X0697731Y1397513
X0040167Y1632405
X0048907Y1554972
X0019230Y1446459
X0097546Y1385912
X1058143Y1433809
X1266996Y1423617
X1775682Y1466568
X1687783Y1472068
X1788376Y0558324
X1782376Y0558324
X1785376Y0558324
X1779376Y0558324
X1614767Y1443512
X1649197Y1396743
X1675641Y1432891
X1257594Y1417000
X1730202Y1602093
X1768929Y1651956
X0493824Y1452895
X0487124Y1462595
X0480424Y1472295
X0467024Y1452895
X0460324Y1462595
X0453624Y1472295
X0440224Y1452895
X0433524Y1462595
X0427286Y1480190
X0544794Y1494082
X0544794Y1484082
X0534024Y1452895
X0520624Y1452895
X0513924Y1462595
X0507224Y1472295
X0427286Y1505390
X0497224Y1452895
X0490524Y1462595
X0483824Y1472295
X0470424Y1452895
X0463724Y1462595
X0457024Y1472295
X0443624Y1452895
X0436924Y1462595
X0427286Y1483590
X0544794Y1497482
X0544794Y1480682
X0537424Y1452895
X0524024Y1452895
X0517324Y1462595
X0510624Y1472295
X0427286Y1501990
X0621886Y1452895
X0615186Y1462595
X0608486Y1472295
X0595086Y1452895
X0588386Y1462595
X0581686Y1472295
X0568286Y1452895
X0561586Y1462595
X0555348Y1480190
X0672856Y1494082
X0672856Y1480682
X0662086Y1452895
X0648686Y1452895
X0641986Y1462595
X0635286Y1472295
X0555348Y1505390
X0625286Y1452895
X0618586Y1462595
X0611886Y1472295
X0598486Y1452895
X0591786Y1462595
X0585086Y1472295
X0571686Y1452895
X0564986Y1462595
X0555348Y1483590
X0672856Y1497482
X0672856Y1484082
X0665486Y1452895
X0652086Y1452895
X0645386Y1462595
X0638686Y1472295
X0555348Y1501990
X0357713Y1452895
X0351013Y1462595
X0344313Y1472295
X0330913Y1452895
X0324213Y1462595
X0317513Y1472295
X0304113Y1452895
X0297413Y1462595
X0291175Y1480190
X0408683Y1494082
X0408683Y1484082
X0397913Y1452895
X0384513Y1452895
X0377813Y1462595
X0371113Y1472295
X0291175Y1505390
X0361113Y1452895
X0354413Y1462595
X0347713Y1472295
X0334313Y1452895
X0327613Y1462595
X0320913Y1472295
X0307513Y1452895
X0300813Y1462595
X0291175Y1483590
X0408683Y1497482
X0408683Y1480682
X0401313Y1452895
X0387913Y1452895
X0381213Y1462595
X0374513Y1472295
X0291175Y1501990
X0229651Y1452895
X0222951Y1462595
X0216251Y1472295
X0202851Y1452895
X0196151Y1462595
X0189451Y1472295
X0176051Y1452895
X0169351Y1462595
X0163113Y1480190
X0280621Y1494082
X0280621Y1480682
X0273251Y1452895
X0256451Y1452895
X0249751Y1462595
X0243051Y1472295
X0163113Y1505390
X0233051Y1452895
X0226351Y1462595
X0219651Y1472295
X0206251Y1452895
X0199551Y1462595
X0192851Y1472295
X0179451Y1452895
X0172751Y1462595
X0163113Y1483590
X0280621Y1497482
X0280621Y1484082
X0269851Y1452895
X0259851Y1452895
X0253151Y1462595
X0246451Y1472295
X0163113Y1501990
X1488298Y1505295
X1474898Y1485895
X1468198Y1495595
X1461498Y1505295
X1491698Y1505295
X1478298Y1485895
X1471598Y1495595
X1464898Y1505295
X1629760Y1485895
X1623060Y1495595
X1616360Y1505295
X1602960Y1485895
X1596260Y1495595
X1589560Y1505295
X1576160Y1485895
X1569460Y1495595
X1563222Y1513190
X1680730Y1527082
X1680730Y1513682
X1669960Y1485895
X1656560Y1485895
X1649860Y1495595
X1643160Y1505295
X1563222Y1538390
X1633160Y1485895
X1626460Y1495595
X1619760Y1505295
X1606360Y1485895
X1599660Y1495595
X1592960Y1505295
X1579560Y1485895
X1572860Y1495595
X1563222Y1516590
X1680730Y1530482
X1680730Y1517082
X1673360Y1485895
X1659960Y1485895
X1653260Y1495595
X1646560Y1505295
X1563222Y1534990
X1365586Y1485895
X1358886Y1495595
X1352186Y1505295
X1338786Y1485895
X1332086Y1495595
X1325386Y1505295
X1311986Y1485895
X1305286Y1495595
X1299048Y1513190
X1416556Y1527082
X1416556Y1517082
X1405786Y1485895
X1392386Y1485895
X1385686Y1495595
X1378986Y1505295
X1299048Y1538390
X1368986Y1485895
X1362286Y1495595
X1355586Y1505295
X1342186Y1485895
X1335486Y1495595
X1328786Y1505295
X1315386Y1485895
X1308686Y1495595
X1299048Y1516590
X1416556Y1530482
X1416556Y1513682
X1409186Y1485895
X1395786Y1485895
X1389086Y1495595
X1382386Y1505295
X1299048Y1534990
X1237524Y1485895
X1230824Y1495595
X1224124Y1505295
X1210724Y1485895
X1204024Y1495595
X1197324Y1505295
X1183924Y1485895
X1177224Y1495595
X1170986Y1513190
X1288494Y1527082
X1288494Y1513682
X1281124Y1485895
X1264324Y1485895
X1257624Y1495595
X1250924Y1505295
X1170986Y1538390
X1240924Y1485895
X1234224Y1495595
X1227524Y1505295
X1214124Y1485895
X1207424Y1495595
X1200724Y1505295
X1187324Y1485895
X1180624Y1495595
X1170986Y1516590
X1288494Y1530482
X1288494Y1517082
X1277724Y1485895
X1267724Y1485895
X1261024Y1495595
X1254324Y1505295
X1170986Y1534990
X1604962Y0069343
X1615966Y0075340
X1626962Y0069343
X1639170Y0075340
X1650170Y0069340
X1661166Y0075343
X1672170Y0069340
X1683304Y0075340
X1694300Y0069343
X1538966Y0069340
X1549962Y0075343
X1560966Y0069340
X1571966Y0075340
X1582966Y0069340
X1593966Y0075340
X1705304Y0075340
X1601562Y0069343
X1612566Y0075340
X1623562Y0069343
X1635770Y0075340
X1646770Y0069340
X1657766Y0075343
X1668770Y0069340
X1679904Y0075340
X1690900Y0069343
X1535566Y0069340
X1546562Y0075343
X1557566Y0069340
X1568566Y0075340
X1579566Y0069340
X1590566Y0075340
X1701904Y0075340
X1591794Y0026477
X1598899Y0019541
X1627660Y0026477
X1634765Y0019541
X1641833Y0026477
X1648938Y0019541
X1671794Y0026477
X1678899Y0019541
X1685967Y0026477
X1549274Y0026477
X1556379Y0019541
X1563447Y0026477
X1570552Y0019541
X1577620Y0026477
X1584725Y0019541
X1693072Y0019541
X1595194Y0026477
X1602299Y0019541
X1631060Y0026477
X1638165Y0019541
X1645233Y0026477
X1652338Y0019541
X1675194Y0026477
X1682299Y0019541
X1689367Y0026477
X1552674Y0026477
X1559779Y0019541
X1566847Y0026477
X1573952Y0019541
X1581020Y0026477
X1588125Y0019541
X1696472Y0019541
X0586394Y0095948
X1208431Y0133866
X0854201Y0143062
X1275981Y0085114
X1190587Y0099694
X1220931Y0131307
X0365739Y0221871
X1707568Y0420370
X0320095Y0231810
X0296474Y0158706
X0348107Y0220420
X0598552Y0159066
X0605853Y0152140
X0408603Y0152278
X0317472Y0225217
X0319970Y0228167
X0317472Y0222262
X0605853Y0149640
X0298716Y0040020
R02X-0008000
X0266420Y0039120
X0300230Y0014820
X0235697Y0039755
X0238059Y0037165
X0254046Y0039425
X0250216Y0039365
R02X-0004000
X0245486Y0159705
X0365559Y0238896
X1692450Y0436772
X1802565Y0156557
X1690208Y0421855
X1698220Y0369652
X1719200Y0371162
X1713720Y0384652
X1713720Y0388152
X1717220Y0388152
X1717220Y0384652
X1713720Y0381152
X1717220Y0381152
X1713720Y0391652
X1717220Y0391652
X1627909Y0294742
X1619909Y0303596
X1627909Y0298742
X1787390Y0151834
X1721628Y0147312
X1777720Y0037792
X1710106Y0039768
X1710106Y0048978
X1768956Y0037558
X0377118Y0222229
X1707544Y0431745
X0370352Y0235455
X1695455Y0422287
X0352000Y0235643
X1697161Y0406602
X1694050Y0416643
X1707780Y0410738
X0355910Y0223847
X0352000Y0230643
X1702959Y0404243
X0389912Y0280345
X0234331Y0103286
X0370327Y0228951
X1701124Y0423802
X0587710Y0404287
X0665651Y0147692
X0662881Y0146912
X0662881Y0149912
X0640084Y0227113
X0662781Y0210362
X0662781Y0205362
X0662781Y0207862
X0659881Y0210762
X0659881Y0205762
X0659881Y0208262
X0866619Y0286801
X0867701Y0267537
X0978269Y0264929
X0868104Y0273103
X0856244Y0286447
X0863104Y0273103
X0881354Y0267407
X0877448Y0284825
X0885764Y0284361
X0863230Y0280001
X0783877Y0475344
X0752409Y0456074
X0855934Y0215375
X0867529Y0231788
X0944520Y0182094
X0922341Y0263875
X0935771Y0191419
X0939271Y0191419
X0878221Y0187449
X0896621Y0209662
X0894121Y0209662
X0894121Y0207162
X0896621Y0207162
X0888930Y0209323
X0891621Y0209662
X0888930Y0206823
X0891621Y0207162
X0878328Y0183169
X0876696Y0171362
X0876696Y0176862
X0871145Y0163862
X1784915Y0186053
X1816190Y0208879
X1811274Y0198098
X1802570Y0186913
X1806470Y0186866
X1785320Y0193072
X0071779Y0165194
X0101679Y0151191
X0079726Y0145191
X0166670Y0502900
X0166760Y0506880
X0172120Y0412350
X0846895Y1295981
X0846931Y1291468
X0616037Y1367166
X0616615Y1386232
X0651877Y1391074
X0701689Y1399545
X0832342Y1274626
X0832274Y1277301
X0635092Y1277102
X1379804Y1733118
X1390045Y1712038
X1382045Y1704038
X1391750Y1697747
X1449070Y1686722
X1445079Y1686678
X1381918Y1676875
X1392068Y1676875
X0828259Y0501027
X0813114Y0495344
X0787092Y0490681
X0755559Y0468672
X0702095Y0468672
X0755559Y0449854
X0702095Y0456074
X0755559Y0437256
X0742961Y0446705
X0742961Y0443555
X0742961Y0449854
X0742961Y0456074
X0742961Y0462373
X0742961Y0459223
X0739811Y0440405
X0736661Y0440405
X0733512Y0440405
X0724143Y0449854
X0727292Y0449854
X0724143Y0456074
X0724143Y0459223
X0727292Y0456074
X0736661Y0446705
X0724143Y0446705
X0736661Y0449854
X0733512Y0449854
X0733512Y0456074
X0736661Y0456074
X0736661Y0459223
X0727292Y0440405
X0717843Y0449854
X0717843Y0456074
X0717843Y0462373
X0714694Y0459223
X0714694Y0446705
X0717843Y0443555
X0702095Y0437256
X0733512Y0424657
X0727500Y0390862
X0671500Y0390862
X0649500Y0373500
X0642171Y0311280
X0626473Y0305338
X0479148Y0315502
X0483823Y0285893
X1001196Y0223898
X0758163Y1490789
X0907031Y1457231
X0278425Y0230925
X0266971Y0140110
X0244818Y0115546
X0244818Y0111546
X0738075Y1718082
X0741025Y1718195
X0738108Y1721157
X0741160Y1721150
X0741030Y1726903
X0738030Y1726903
X0741030Y1723903
X0738030Y1723903
X1080966Y1691320
X1078016Y1691207
X1080933Y1688245
X1077881Y1688252
X1078011Y1682499
X1081011Y1682499
X1078011Y1685499
X1081011Y1685499
X0754839Y1678069
X0752187Y1682994
X0758030Y1668583
X0745075Y1665675
X0713771Y1654927
X0674908Y1644481
X0660058Y1648889
X0679413Y1653251
X0686075Y1657082
X0673548Y1669550
X0703102Y1665554
X0675497Y1687253
X0691560Y1682047
X0640865Y1719684
X0641825Y1730516
X0635210Y1718395
X0640690Y1703547
X0649464Y1691180
X0658491Y1688965
X0692390Y1687594
X0673113Y1716599
X0671798Y1704542
X0673113Y1727261
X0668058Y1720092
X0647630Y1641522
X0640242Y1639951
X0711298Y1632534
X0702683Y1633715
X0693451Y1628733
X0673960Y1633042
X0751521Y1656008
X0731119Y1647997
X0755261Y1628208
X0722104Y1626253
X0717798Y1607335
X1782337Y1453191
X1785408Y1453385
X1782530Y1456229
X1785634Y1456326
X0863055Y0941441
X0866005Y0941554
X0863088Y0944516
X0866140Y0944509
X0866010Y0950262
X0863010Y0950262
X0866010Y0947262
X0863010Y0947262
X0824003Y0930319
X0826953Y0930432
X0824036Y0933394
X0827088Y0933387
X0826958Y0939140
X0823958Y0939140
X0826958Y0936140
X0823958Y0936140
X0949195Y1655145
X1116917Y1512644
X1119912Y1512644
X1119912Y1506936
X1116917Y1515644
X1119912Y1515644
X1119912Y1509891
X1116917Y1509898
X1116917Y1506823
X1081005Y1425458
X0963500Y0854719
X0949500Y0870500
X0929603Y0879000
X0907000Y0899777
X0920897Y0881879
X0948500Y0937000
X0919272Y0986782
X0891996Y1149707
X0902382Y1137558
X0933234Y1145058
X0949407Y1137558
X0946730Y1290719
X0946730Y1293219
X1160163Y1445627
X1166350Y1454234
X1184900Y1428500
X1194000Y1414500
X1106700Y1526591
X1114617Y1526318
X1113887Y1543447
X1135033Y1556112
X1133765Y1568952
X1115027Y1598788
X1202697Y1673059
X1190616Y1670641
X1126000Y1672419
X1142033Y1682412
X1154500Y1677000
X1175726Y1686726
X1092980Y1699179
X1105148Y1696029
X1194478Y1699936
X1189462Y1700334
X1199612Y1691366
X1204804Y1700343
X1214954Y1691375
X1100998Y1715841
X1119361Y1713734
X1207770Y1706861
X1216738Y1717011
X1100998Y1725991
X1189407Y1717518
X1207770Y1720861
X1216738Y1731011
X1205638Y1732766
X1112500Y1671107
X1109000Y1671107
X1096500Y1639000
X1114394Y1695936
X1114414Y1698859
X1256600Y1434500
X1109811Y1615917
X1107181Y1615917
X1214611Y0763524
X1262457Y0798814
X1256447Y0798828
X1184910Y0763524
R02X-0029701
X1095808Y0763524
X1066107Y0763524
X1072673Y0428791
X0704056Y0575081
X0698996Y0575081
X1566442Y0294816
X1544489Y0288816
X1536542Y0308819
X1290127Y0401125
X1268174Y0395125
X1260227Y0415128
X0148340Y1454674
X0101955Y1448660
X0079055Y1434000
X0093000Y1426000
X1080574Y0471500
X1080640Y0467000
X1695020Y1465621
X1625285Y1433384
X1641087Y1396118
X1670147Y1444311
X1627174Y1420450
X1563967Y1363205
X1554692Y1269688
X1301642Y0537299
X1712870Y1586615
X1570068Y0534095
X0598496Y0451421
X0622174Y0438925
X0617998Y0415546
X0599884Y0412000
X0802462Y0387756
X0802660Y0381020
X0838575Y0477554
X0833097Y0393000
X0854552Y0381000
X0858925Y0398537
X0652425Y0385924
X0410000Y0304000
X0395053Y0318125
X0072462Y0268223
X0191264Y0147768
X0193610Y0153951
X0221051Y0153167
X0336000Y0284000
X0344034Y0282609
X1661125Y1690751
X0549854Y0406298
X1828483Y0431678
X0884986Y0198829
X0631075Y0429888
X0654248Y0422500
X1747120Y1710824
X1750380Y1707468
X1710230Y1729654
X1685383Y1729559
X1735463Y1694465
X1771038Y1692956
X1773929Y1654956
X1773929Y1657465
X1724263Y1672465
X1691952Y1698947
X1692415Y1663740
X1604991Y0536344
X0272054Y0801112
X0246371Y0772388
X0238469Y0763525
R03X-0029701
X0119666Y0763525
X0089965Y0763525
X0152822Y0665500
X0403657Y0546915
X0760614Y0284100
X1731117Y1730415
X1656997Y1733909
X1749480Y1718158
X1731117Y1715265
X1722149Y1720265
X1692218Y1717539
X1675360Y1721252
X1656997Y1718759
X1648029Y1723759
X1721912Y1705115
X1710360Y1706502
X1683029Y1708609
X1672500Y1708927
X1648029Y1708609
X0558379Y0482096
X0567297Y0487551
X0757629Y0239295
X1663310Y0215488
X1792642Y0763524
X1762942Y0763524
X1733241Y0763524
R03X-0029701
X1726409Y0653641
X1647158Y0618971
X0711702Y0646533
X0703781Y0641805
X0581421Y0813078
X0714583Y0590792
X1188267Y0571807
X1821073Y0565157
R02X0003000
X1785336Y1450065
X1782385Y1450095
X1785336Y1447565
X1782369Y1447581
X1012925Y0558000
X1021425Y0568614
X1017718Y0541201
X1004527Y0553224
X1004527Y0541924
X0035952Y0551605
X0039952Y0551605
X0053299Y0552365
X0058365Y0552365
X0789125Y0529425
X0772000Y0529862
X1441053Y0560535
X1464257Y0560977
X1463647Y0544977
X1516757Y0537477
X1013306Y0518146
X0986056Y0516014
X0659425Y0521075
X0631510Y0510613
X0064442Y0510667
X0028562Y0517025
X1175181Y0481691
X1144663Y0492319
X1245752Y0470733
X1195767Y0465272
X1195767Y0470392
X1175181Y0469841
X1265227Y0454372
X1195767Y0460202
X1185952Y0452202
X1175181Y0453341
X1175181Y0464341
X1175181Y0458841
X1236879Y0449755
X1242429Y0435255
X1185952Y0436202
X1185952Y0444202
X1175181Y0442341
X1175181Y0447841
X0063540Y0438802
X1825874Y0424948
X1815724Y0423932
X1782324Y0425432
X1690140Y0434160
X1242429Y0431255
X1816224Y0410432
X1782324Y0418932
X1782324Y0410432
X1709000Y0413362
X1709000Y0415862
X1706500Y0413362
X1706500Y0415862
X1650020Y0411452
X1650020Y0408952
X1647310Y0411422
X1647310Y0408922
X1816994Y0398052
X1782324Y0403932
X1695579Y0403985
X1699809Y0403985
X0087520Y0395865
X0087520Y0391391
X0087520Y0382219
X0077680Y0380895
X0077680Y0378395
X1817157Y0373829
X0063429Y0360702
X0059322Y0360702
X0051114Y0360862
X0115016Y0320715
X0059780Y0312866
X0034281Y0307798
X0034281Y0312916
X0115016Y0300281
X0066289Y0298207
X0035689Y0298207
X0059780Y0282866
X0057271Y0272357
X0034281Y0282916
X0034281Y0277798
X0855859Y0212425
X1186821Y0181930
X1186821Y0185430
X1808622Y0170869
X0825332Y0166862
X1827580Y0151834
X1301743Y0162055
X1189727Y0160987
X1189727Y0164987
X0848745Y0160137
X0772270Y0153728
X1815005Y0149325
X1784006Y0137395
X1788204Y0078108
X1788204Y0082338
X1652525Y0146762
X0994257Y0154895
X0999580Y0154895
X1087421Y0149716
X0829115Y0147123
X0751221Y0137864
X0757694Y0100653
X0757694Y0098108
X1684925Y0136762
X1684925Y0131762
X1483820Y0132405
X1455667Y0125733
X1199756Y0128748
X0200577Y0125502
X0184930Y0125502
X1719909Y0116713
X1719909Y0112713
X1454549Y0107443
X1448549Y0114643
X1443049Y0107443
X1439049Y0107443
X0839361Y0114862
X0823115Y0115223
X0677738Y0115428
X0677561Y0118409
X0602328Y0109062
X0591385Y0109165
X0796021Y0395924
X0811224Y0395974
X0816991Y0395337
X0552510Y0446490
X0498500Y0419425
X1693000Y0234000
X0776500Y0371000
X0769000Y0364000
X0803500Y0366000
X0833000Y0409500
X0807564Y0403805
X0787000Y0407500
X0663374Y0484295
X0085736Y1391597
X0068354Y1314097
X0095790Y1278014
X0339532Y1218605
X0034584Y1315244
R03Y-0002500
X0395048Y0121178
X0826912Y0475989
X0752409Y0424657
X0538067Y0592652
X0458725Y0524480
X0566148Y0324502
X0570823Y0294893
X0834251Y0455578
X0834106Y0439279
X0495500Y0161386
X0583485Y0133056
X0583485Y0130530
X0580485Y0130530
X0580485Y0133056
X0426011Y0524888
X0412771Y0524820
X0146982Y0530997
X0289393Y0498960
X0429784Y0466315
X0415984Y0466392
X0402184Y0466469
X0444310Y0243370
X0580343Y0217771
X0568736Y0235821
X0582816Y0228696
X0447840Y0275970
X0455422Y0244103
X0412715Y0266165
X0412715Y0251165
X0412715Y0258165
X0550196Y0190256
X0547196Y0190256
X0547196Y0199256
X0503507Y0185516
X0495232Y0185516
X0495232Y0193516
X0486682Y0193516
X0437997Y0170701
X0403141Y0148300
X0461997Y0166400
X0449997Y0166400
X0453997Y0166400
R02X-0008000
X0433997Y0166400
X0468574Y0213104
X0424815Y0217646
X0447299Y0220046
X0443299Y0220046
X0411610Y0223140
X0513772Y0121220
X0530567Y0125914
X0524993Y0125914
X0519268Y0167428
X1095448Y0479426
X1214094Y0258633
X0607868Y0257562
X1366094Y0258633
X1350094Y0258633
X1358094Y0258633
R02X-0016000
X1334094Y0258633
X1310094Y0258633
X1318094Y0258633
X1294094Y0258633
X1302094Y0258633
X1278094Y0258633
X1286094Y0258633
X1270094Y0258633
X1262094Y0258633
X1250285Y0303307
X1254094Y0258633
X1222094Y0314216
X1230094Y0258633
X1222094Y0258633
X0637160Y0405449
X1793444Y0178083
X1780929Y0179408
X1755022Y0266794
X1755022Y0269794
X1758022Y0266794
X1758022Y0269794
X1752022Y0266794
X1752022Y0269794
X1752772Y0281859
X1752772Y0278859
X1764573Y0269657
X1761573Y0269657
X1761772Y0281859
R02X-0003000
X1775633Y0264166
R02Y0002500
X1764573Y0266657
X1761573Y0266657
X1775633Y0271666
X1761772Y0278859
R02X-0003000
X1807596Y0269133
R02Y-0002500
X1807596Y0271633
X1801174Y0274499
X1797674Y0274499
X1783896Y0269133
X1783896Y0266633
X1783896Y0271633
X1790674Y0274499
X1794174Y0274499
X1778796Y0264133
X1778796Y0269133
X1778796Y0266633
X1778796Y0271633
X1767573Y0269657
X1775633Y0261666
X1767573Y0266657
X1778796Y0261633
X0254694Y0378523
X0250194Y0378523
X0247694Y0378523
X0837501Y0229642
X0620455Y0219277
X0998326Y0499675
X1087963Y0489641
X1087963Y0494641
X1087963Y0484605
X1080420Y0487782
X1055905Y0492537
X0998359Y0484675
X1087963Y0468105
X1071470Y0475525
X1080416Y0482772
X0998359Y0473675
X0998359Y0468175
X0998359Y0479175
X0654014Y0473862
X0654000Y0465824
X0587795Y0479631
X1087940Y0452110
X1087963Y0457105
X1087963Y0462605
X1062741Y0457959
X1062642Y0444859
X0998359Y0457175
X0998359Y0462675
X0653449Y0458542
X0635690Y0461441
X0592529Y0461563
X1087963Y0446105
X1087963Y0440605
X0998359Y0451675
X0786203Y0447054
X0654441Y0449618
X0639500Y0442362
X1057798Y0429618
X1057798Y0427059
X1020748Y0425902
X1003651Y0433426
X0639211Y0433862
X1052505Y0406576
X1034855Y0411704
X0773181Y0415197
X0617985Y0407346
X0588723Y0415846
X0550573Y0414274
X0763500Y0390862
X0581985Y0401158
X0550573Y0399586
X0770000Y0380787
X0617985Y0376427
X0617985Y0387227
X0581985Y0376427
X0581985Y0387227
X0759652Y0374362
X0743500Y0374362
X0731406Y0374331
X0254859Y0375389
X0250359Y0375389
X0247859Y0375389
X0118407Y0526766
X0750717Y0319907
X1586291Y0303596
X0806461Y0310610
X1033590Y0287311
X1033590Y0298311
X1017835Y0291236
X0872508Y0302273
X0870008Y0302273
X0873172Y0295485
X0870672Y0295485
X0874244Y0287047
X0819828Y0288063
X0369671Y0294614
X0369671Y0292114
X0369171Y0297114
X0366671Y0297114
X0884004Y0274482
X0884004Y0278712
X0763463Y0281840
X0763508Y0284404
X0763384Y0279231
X0761067Y0280355
X0853621Y0269057
X0539217Y0245270
X1654419Y0229912
X0549248Y0234152
X0555567Y0236970
X0491577Y0238120
X0483227Y0233000
X0463240Y0244980
X0471371Y0235764
X0460624Y0240953
X0411940Y0235442
X0420115Y0226323
X0380012Y0239615
X0348645Y0229180
X0717021Y0220862
X0588554Y0225277
X0588554Y0217277
X0540695Y0217874
X0461931Y0212703
X0358671Y0220614
X0361171Y0220614
X0358618Y0223129
X0361171Y0223114
X0344106Y0222659
X1728300Y0377787
X1770280Y0372452
X1756800Y0368048
X1756800Y0364048
X0588244Y0208991
X0616357Y0182229
X0710284Y0169826
X0641111Y0158300
X0643800Y0166053
X0563951Y0157494
X0370888Y0155250
X0334339Y0162580
X0625532Y0146982
X0386350Y0138980
X0384375Y0147365
X0296478Y0149203
X0363621Y0127665
X1352199Y0098050
X1360109Y0098050
X1348199Y0098084
X1341399Y0098084
X1333399Y0098084
X1259472Y0092864
X1253152Y0095525
X0615772Y0106645
X0410400Y0107383
X0410500Y0104883
X1253152Y0084895
X0843856Y0087711
X0585000Y0082500
X1331930Y0066945
X1308110Y0066911
X1320020Y0066979
X1296200Y0066911
X1162086Y0076509
X0640670Y0074369
X0627496Y0074977
X0603350Y0073642
X0579561Y0073090
X0491849Y0064965
X0462653Y0072525
X0433673Y0073960
X0323113Y0076941
X1464830Y0059054
X1434262Y0052892
X1343840Y0066911
X1184194Y0061515
X1184194Y0057015
X1119676Y0054132
X0828601Y0061752
X0702481Y0048327
X0687018Y0058357
X0665469Y0058525
X0624689Y0058262
X0491849Y0060105
X0491849Y0055095
X0424975Y0054762
X0677476Y0033317
X0638490Y0033340
X0546350Y0039562
X0657921Y0030864
X0351157Y0570415
X0351018Y0554896
X0297815Y0580384
X0273500Y0207500
X0258439Y0214000
X0290000Y0222575
X0387805Y1614802
X0387805Y1617302
X0431000Y1640500
X0409552Y1633606
X0478500Y1733500
X0478500Y1710500
X0466000Y1714575
X0478500Y1697000
X0462500Y1697000
X0467500Y1678500
X0415500Y1672500
X0413000Y1683500
X0409000Y1683500
X0397324Y1680495
X0382642Y1680979
X0392324Y1680495
X0387324Y1680495
X0477538Y1661463
X0464925Y1662500
X0470463Y1670038
X0411500Y1657500
X0420000Y1664925
X0382115Y1661545
X0457000Y1650000
X0467500Y1651500
X0446000Y1650000
X0436925Y1649500
X0411448Y1650598
X0434500Y1641500
X0414500Y1639075
X0397822Y1629615
X0408856Y1623435
X0211000Y1717675
X0194000Y1720551
X0185760Y1731666
X0171925Y1717984
X0166467Y1720973
X0152496Y1722941
X0145267Y1722241
X0082500Y1720331
X0199843Y1709837
X0183813Y1705404
X0156825Y1705510
X0129493Y1711846
X0142293Y1705166
X0095342Y1713741
X0082945Y1702511
X0207807Y1696409
X0185173Y1695138
X0179999Y1699156
X0155353Y1687843
X0147253Y1696343
X0127353Y1696062
X0123353Y1695941
X0090127Y1687362
X0082127Y1687362
X0066127Y1687362
X0207807Y1681302
X0110378Y1674313
X0062202Y1684579
X0210217Y1668603
X0180103Y1668921
X0142465Y1662493
X0143778Y1685087
X0126428Y1658587
X0126760Y1682383
X0110378Y1670313
X0032927Y1668587
X0210833Y1660867
X0152353Y1646612
X0136353Y1646612
X0132353Y1646612
X0112353Y1646612
X0077427Y1644410
X0056815Y1643431
X0065257Y1652941
X0061927Y1643496
X0064462Y1655624
X0064427Y1643496
X0035167Y1629405
X0035167Y1626896
X0084833Y1611896
X0038058Y1591405
X0068133Y1587896
X0048758Y1559295
X0446653Y1573264
X0381607Y1590393
X0445800Y1636000
X0445800Y1633200
X1440027Y1667945
X1457940Y1675710
X1482798Y1685982
X1399599Y1657583
X1433911Y1649037
X1424315Y1646967
X1410315Y1646967
X1406814Y1652439
X1411113Y1637767
X1408208Y1628651
X1398058Y1628651
X1408023Y1638705
X1450500Y1614500
X1434316Y1616909
X1419622Y1616000
X1423722Y1616780
X1430244Y1609966
X1412467Y1602234
X0816500Y0763525
X0786800Y0763525
X0757099Y0763525
R03X-0029701
X0800409Y0763765
X0770708Y0763766
X0741007Y0763766
X0711307Y0763766
R02X-0029701
X0073960Y0766090
X0073933Y0768706
X0103574Y0763766
X0133124Y0763766
X0162975Y0763766
R02X0029701
X0188055Y0731734
X0059259Y0737422
X1168818Y0763765
X1139117Y0763765
X1079716Y0763765
X1050015Y0763765
X1109416Y0763765
X1198519Y0763765
X1091270Y0668286
X1062873Y0490180
X0932000Y0850500
X0949000Y0850500
X0930575Y0864075
X0951000Y0855425
X0674123Y0736083
X0531753Y0453232
X0679047Y0678733
X0235913Y0360867
X0233413Y0360867
X0090225Y0622351
R03Y-0004000
X0429784Y0506947
X0324406Y0367744
X0240413Y0360867
X1246094Y0258633
X1261969Y0219505
X1301582Y0166051
X0620455Y0228777
X0640804Y0243371
X0640804Y0239371
X0637804Y0243371
X0637804Y0239371
X0640804Y0235371
X0637804Y0235371
X1628046Y0763765
R04X0029701
X1776550Y0763765
X1740391Y0305692
X1737891Y0305692
X1740391Y0302692
R02X-0002500
X1735391Y0305692
X1730251Y0302732
X1732751Y0302732
X1730251Y0305732
X1732751Y0305732
X1745671Y0293682
X1745671Y0290682
X1732831Y0293722
X1732831Y0299722
X1730331Y0299722
X1732831Y0296722
X1730331Y0296722
X1730331Y0293722
X1751352Y0293386
X1737971Y0293682
X1735471Y0299682
X1735471Y0296682
X1737971Y0296682
X1740471Y0296682
X1737971Y0299682
X1740471Y0299682
X1740471Y0290682
X1740471Y0293682
X1737971Y0290682
X1735471Y0290682
X1735471Y0293682
X1742971Y0290682
X1742971Y0293682
X1678809Y0206451
X0157511Y1663933
X0523143Y0071436
X0154111Y1663933
X0519743Y0071436
X0109073Y1660235
X0112473Y1660235
X0110969Y1685763
X0107569Y1685763
X0157410Y1676811
X0523165Y0040328
X0154010Y1676811
X0519765Y0040328
X1342507Y1187848
X1037895Y1251517
X0595253Y1266668
X0826728Y1246315
X1405811Y1430021
X1521217Y1190088
X1608652Y1303338
X1645163Y1276184
X1195488Y0093550
X1311045Y0104739
X1313951Y0104739
X1307857Y0103353
X1627156Y0238303
X1709339Y0637251
X1600531Y1404710
X0741309Y0108742
X0745031Y0161463
X0739824Y0091052
X0704709Y0125586
X0730660Y0108484
X0735771Y0094988
X0820901Y0147112
X0780159Y0146961
X0782819Y0149471
X0712291Y0106722
X0750034Y0092888
X0750034Y0089988
X0699221Y0102162
X0694221Y0104862
X0695721Y0102162
X0697721Y0104862
X0701221Y0104862
X0702721Y0102162
X0706721Y0100462
X0696728Y0084052
X0696728Y0081552
X0696371Y0078512
X0698711Y0086035
X0754783Y0096553
X0699398Y0123668
X0750701Y0106642
X0712341Y0128093
X0736650Y0102350
X0763221Y0065132
X0788941Y0118637
R02X-0002500
X0787681Y0120947
R02X0002500
X0785181Y0120947
X0781441Y0118637
X0760221Y0064632
X0757721Y0064632
X0758621Y0051602
X0755621Y0051602
X0762721Y0062132
R02X-0002500
X0788710Y1488821
X1097399Y1586043
X1097399Y1589043
X1085399Y1586043
X1088399Y1586043
X1088399Y1589043
X1085399Y1589043
X1094399Y1586043
X1091399Y1586043
X1091399Y1589043
X1094399Y1589043
X1066219Y1588883
X1063219Y1588883
X1063219Y1585883
X1066219Y1585883
X1060219Y1588883
X1060219Y1585883
X1057219Y1588883
X1051219Y1588883
X1054219Y1588883
X1048219Y1588883
X1048219Y1585883
X1054219Y1585883
X1051219Y1585883
X1057219Y1585883
X1031750Y1588710
X1031750Y1585710
X1028750Y1588710
X1028750Y1585710
X1025750Y1588710
X1019750Y1588710
X1022750Y1588710
X1016750Y1588710
X1016750Y1585710
X1022750Y1585710
X1019750Y1585710
X1025750Y1585710
X1000160Y1585710
X1000160Y1588710
X0994160Y1585710
X0997160Y1585710
X0988160Y1585710
X0991160Y1585710
X0985160Y1585710
X0985160Y1588710
X0991160Y1588710
X0988160Y1588710
X0997160Y1588710
X0994160Y1588710
X0968520Y1585570
X0968520Y1588570
X0959520Y1585570
X0956520Y1585570
X0965520Y1585570
X0962520Y1585570
X0962520Y1588570
X0965520Y1588570
X0956520Y1588570
X0959520Y1588570
X0953520Y1585570
X0950520Y1585570
X0950520Y1588570
X0953520Y1588570
X1097399Y1577043
R02Y-0003000
X1097399Y1580043
X1097399Y1583043
X1088399Y1577043
X1085399Y1577043
X1088399Y1574043
X1085399Y1574043
X1085399Y1571043
X1088399Y1571043
X1085399Y1580043
X1088399Y1580043
X1088399Y1583043
X1085399Y1583043
X1091399Y1577043
R02Y-0003000
X1094399Y1577043
R02Y-0003000
X1094399Y1580043
X1091399Y1580043
X1091399Y1583043
X1094399Y1583043
X1066219Y1582883
X1063219Y1582883
X1063219Y1579883
X1066219Y1579883
X1066219Y1570883
R02Y0003000
X1063219Y1570883
R02Y0003000
X1060219Y1582883
X1060219Y1579883
X1060219Y1570883
R02Y0003000
X1057219Y1582883
X1051219Y1582883
X1054219Y1582883
X1048219Y1582883
X1048219Y1579883
X1054219Y1579883
X1051219Y1579883
X1057219Y1579883
X1054219Y1570883
X1051219Y1570883
X1057219Y1570883
X1057219Y1573883
X1051219Y1573883
X1054219Y1573883
X1057219Y1576883
X1051219Y1576883
X1054219Y1576883
X1048219Y1570883
R02Y0003000
X1031750Y1582710
X1031750Y1579710
X1031750Y1570710
R02Y0003000
X1028750Y1582710
X1028750Y1579710
X1028750Y1570710
R02Y0003000
X1025750Y1582710
X1019750Y1582710
X1022750Y1582710
X1016750Y1582710
X1016750Y1579710
X1022750Y1579710
X1019750Y1579710
X1025750Y1579710
X1022750Y1570710
X1019750Y1570710
X1025750Y1570710
X1025750Y1573710
X1019750Y1573710
X1022750Y1573710
X1025750Y1576710
X1019750Y1576710
X1022750Y1576710
X1016750Y1570710
R02Y0003000
X1000160Y1576710
R02Y-0003000
X1000160Y1579710
X1000160Y1582710
X0985160Y1576710
R02Y-0003000
X0991160Y1576710
X0988160Y1576710
X0997160Y1576710
X0994160Y1576710
X0991160Y1573710
X0988160Y1573710
X0997160Y1573710
X0994160Y1573710
X0994160Y1570710
X0997160Y1570710
X0988160Y1570710
X0991160Y1570710
X0994160Y1579710
X0997160Y1579710
X0988160Y1579710
X0991160Y1579710
X0985160Y1579710
X0985160Y1582710
X0991160Y1582710
X0988160Y1582710
X0997160Y1582710
X0994160Y1582710
X0968520Y1570570
R04Y0003000
X0959520Y1570570
X0956520Y1570570
X0965520Y1570570
X0962520Y1570570
X0962520Y1573570
X0965520Y1573570
X0956520Y1573570
X0959520Y1573570
X0962520Y1576570
X0965520Y1576570
X0956520Y1576570
X0959520Y1576570
X0959520Y1579570
X0956520Y1579570
X0965520Y1579570
X0962520Y1579570
X0962520Y1582570
X0965520Y1582570
X0956520Y1582570
X0959520Y1582570
X0953520Y1570570
X0950520Y1570570
X0950520Y1573570
X0953520Y1573570
X0950520Y1576570
X0953520Y1576570
X0953520Y1579570
X0950520Y1579570
X0950520Y1582570
X0953520Y1582570
X1097399Y1568043
X1088399Y1568043
X1085399Y1568043
X1091399Y1568043
X1094399Y1568043
X1066219Y1567883
R03X-0003000
X1051219Y1567883
X1054219Y1567883
X1048219Y1567883
X1028750Y1567710
X1031750Y1567710
X1025750Y1567710
X1019750Y1567710
X1022750Y1567710
X1016750Y1567710
X1000160Y1567710
X0985160Y1567710
X0991160Y1567710
X0988160Y1567710
X0997160Y1567710
X0994160Y1567710
X0968520Y1567570
X0962520Y1567570
X0965520Y1567570
X0956520Y1567570
X0959520Y1567570
X0950520Y1567570
X0953520Y1567570
X0920550Y1606533
X0920550Y1603533
X0917550Y1606533
X0917550Y1603533
X0905550Y1606533
R02X0003000
X0911550Y1603533
R02X-0003000
X0914550Y1606533
X0914550Y1603533
X0902550Y1606533
X0902550Y1603533
X0899550Y1606533
X0875550Y1603533
X0878550Y1603533
X0878550Y1606533
X0875550Y1606533
X0860550Y1603533
R03X0003000
X0860550Y1606533
X0869550Y1606533
X0866550Y1606533
X0863550Y1606533
X0872550Y1603533
X0872550Y1606533
X0857550Y1606533
X0833550Y1606533
X0830550Y1606533
X0833550Y1603533
X0836550Y1603533
X0836550Y1606533
X0830550Y1603533
X0824550Y1603533
X0827550Y1603533
X0821550Y1606533
R02X0003000
X0818550Y1603533
X0821550Y1603533
X0818550Y1606533
X0815550Y1606533
X0785550Y1603533
R02X0003000
X0785550Y1606533
R02X0003000
X0782550Y1606533
X0776550Y1603533
X0776550Y1606533
X0779550Y1603533
X0782550Y1603533
X0779550Y1606533
X0739998Y1606663
R02X0003000
X0739998Y1603663
R02X0003000
X0730998Y1606663
X0730998Y1603663
X0736998Y1606663
X0733998Y1606663
X0736998Y1603663
X0733998Y1603663
X0917550Y1594533
X0917550Y1600533
X0917550Y1597533
X0905550Y1597533
X0908550Y1594533
X0908550Y1600533
X0908550Y1597533
X0911550Y1594533
X0911550Y1600533
X0911550Y1597533
X0905550Y1594533
X0905550Y1600533
X0914550Y1594533
X0914550Y1600533
X0914550Y1597533
X0875550Y1594533
R02Y0003000
X0872550Y1597533
X0872550Y1600533
X0872550Y1594533
X0863550Y1600533
X0863550Y1594533
X0869550Y1597533
X0869550Y1600533
X0869550Y1594533
X0866550Y1597533
X0866550Y1600533
X0866550Y1594533
X0863550Y1597533
X0833550Y1594533
X0830550Y1594533
X0833550Y1600533
X0833550Y1597533
X0830550Y1600533
X0830550Y1597533
X0821550Y1597533
X0824550Y1594533
X0824550Y1600533
X0824550Y1597533
X0827550Y1594533
X0827550Y1600533
X0827550Y1597533
X0821550Y1594533
X0821550Y1600533
X0788550Y1597533
X0785550Y1597533
X0791550Y1594533
R02X-0003000
X0791550Y1600533
R02X-0003000
X0791550Y1597533
X0779550Y1600533
X0782550Y1597533
X0779550Y1597533
X0776550Y1594533
X0776550Y1600533
X0776550Y1597533
X0782550Y1594533
X0779550Y1594533
X0782550Y1600533
X0739998Y1594463
R02Y0003000
X0742998Y1594463
X0745998Y1594463
X0742998Y1597463
X0745998Y1597463
X0742998Y1600463
X0745998Y1600463
X0733998Y1594463
X0730998Y1594463
X0736998Y1594463
X0733998Y1597463
X0730998Y1597463
X0733998Y1600463
X0730998Y1600463
X0736998Y1597463
X0736998Y1600463
X0917077Y1582363
X0917077Y1587493
X0917077Y1577233
X0911577Y1587493
X0911577Y1577233
X0905977Y1582363
X0905977Y1587493
X0905977Y1577233
X0869577Y1587493
X0869577Y1577233
X0863977Y1587493
R02Y-0005130
X0875077Y1587493
R02Y-0005130
X0827577Y1587493
X0821977Y1587493
X0821977Y1582363
X0827577Y1577233
X0821977Y1577233
X0833077Y1587493
R02Y-0005130
X0779977Y1587493
R02Y-0005130
X0791077Y1587493
X0785577Y1587493
X0791077Y1582363
X0785577Y1577233
X0791077Y1577233
X0727780Y1577231
X0727780Y1582361
X0733380Y1577231
X0727780Y1587491
X0733380Y1587491
X0738880Y1577231
R02Y0005130
X0307816Y0095727
X1773577Y0088339
X0241271Y0130719
X1263146Y0121022
X1278137Y0176051
X0243813Y0132383
X1233668Y0128239
X0235147Y0124435
X1269146Y0121022
X1267037Y0175030
X0238297Y0121555
X1221512Y0128239
X0275793Y0120248
X0101675Y0160694
X0306470Y0065160
X0303852Y0065042
X0273616Y0096665
X0269916Y0097965
R02X-0003500
X0268416Y0100665
R02X-0003500
X0263182Y0073396
X0263316Y0087665
X0262893Y0080029
X0262893Y0077529
X0314653Y0068906
X0314653Y0071806
X0305820Y0073693
X0262500Y0161100
X1787390Y0156834
X1770334Y0072737
X0269487Y0121095
X1744976Y0122998
X0264293Y0120972
X1739686Y0120938
X1267037Y0180565
X1268941Y0206017
X1717384Y0135373
X1721384Y0135373
X1233668Y0132739
X1306300Y0203917
X1279447Y0213292
X1278137Y0180565
X1716609Y0141297
X1221411Y0134230
X1705120Y0143610
X1269360Y0219632
X1571516Y0319099
X1741621Y0074113
X1748686Y0097408
X1736731Y0102293
X1743731Y0102293
X1740231Y0102293
X1745435Y0100244
R02X-0003500
X1741621Y0080113
X1741621Y0082613
X1741621Y0076613
X1774291Y0057191
X1779744Y0070073
X1779744Y0072973
X1774294Y0060133
X1774294Y0063033
X0238600Y0130400
X0299002Y0088700
X1713399Y0132858
X1761417Y0090017
X0301107Y0075676
X1767956Y0076843
X0320190Y0077648
X1785108Y0076078
X0310455Y0075895
X1775546Y0073376
X0266000Y0125800
X0316982Y0089003
X1781451Y0088238
X0252800Y0114800
X1729046Y0118178
X0322871Y0084321
X1787756Y0085178
X1750786Y0120018
X0662000Y0433862
X0711544Y0443555
X0301780Y0082900
X1767136Y0083653
X1002827Y0172479
X0997300Y0234876
X0985922Y0171861
X1011120Y0198114
X1011068Y0207667
X1002921Y0178799
X1019531Y0230423
X0989605Y0175400
X0986447Y0158209
X0988751Y0167541
X1008121Y0203525
X1010909Y0213708
X1005641Y0214969
X0995181Y0157689
X1008918Y0192994
X0996416Y0176579
X0772677Y0451374
X1019356Y0222423
X1021440Y0226423
X1011721Y0233699
X1008707Y0230423
X0987321Y0205599
X0990221Y0203199
X0990221Y0206699
X0987321Y0202099
X0987321Y0198599
X0990221Y0199699
X0983879Y0202162
X0986021Y0195099
X0979849Y0202049
X0977221Y0205399
X0975749Y0202049
X0971943Y0204813
X0967943Y0204813
X0981112Y0161204
X0975691Y0161220
X1005307Y0155043
X1290127Y0410635
X0174320Y0395040
X0139890Y0503440
X0139980Y0507420
X0140360Y0430160
X0183890Y0388180
X1774338Y1676865
X0357208Y1395223
X0359859Y1395223
X0352313Y1395223
X0330109Y0605883
X0330109Y0602883
X0333502Y0603019
X0333502Y0600019
X0349032Y1392675
X0348828Y1395392
X0346302Y1395242
X0343777Y1395166
X0368355Y1395505
X0365792Y1395507
X0363003Y1395393
X0365980Y1390406
X0365980Y1392906
X0365979Y1387641
X0368543Y1392904
X0368543Y1390404
X0368542Y1387639
X0363191Y1392792
X0363191Y1390292
X0363190Y1387527
X0359832Y1391886
R03X-0002500
X0359567Y1387665
R03X-0002500
X0208061Y1418605
X0933778Y1501204
R04Y-0002500
X1786624Y1637021
X1786588Y1634472
X0090649Y1598507
X0098937Y1598606
X0101637Y1598606
X0096237Y1598506
X0093537Y1598506
X0035167Y1598896
X0346464Y1382602
X0343964Y1382602
X0346464Y1387602
X0346464Y1390102
X0346464Y1385102
X0346464Y1392602
X0343964Y1392602
X0343964Y1387602
X0343964Y1390102
X0343964Y1385102
X0353964Y1382602
R03X0002500
X0348964Y1382602
X0351464Y1382602
X0358964Y1385102
X0356464Y1385102
X0361464Y1385102
X0353964Y1385102
X0348964Y1385102
X0351464Y1385102
X0348964Y1387602
X0348964Y1390102
X0366464Y1382602
X0363964Y1382602
X0348964Y1380102
X0343964Y1380102
X0346464Y1380102
X0363964Y1380102
X0351464Y1380102
X0353964Y1380102
X0361464Y1380102
R02X-0002500
X0366464Y1380102
X0368964Y1380102
X0363964Y1385102
R02X0002500
X0368964Y1382602
X1723184Y0093313
X1722984Y0101713
X0248093Y0092146
X0985445Y0185389
X0247893Y0100546
X0295755Y0072800
X1256224Y1430075
X0154443Y1441195
X0699500Y1608500
X1683741Y1443075
X0042491Y1638656
X0090675Y1595783
X0093424Y1595958
X0090675Y1593283
X0093424Y1593458
X0101524Y1596058
X0096124Y1595958
X0098824Y1596058
X0101524Y1593558
X0096124Y1593458
X0098824Y1593558
X0090675Y1590783
X1765854Y1646456
X0791867Y1524254
X0983125Y1074534
R02X0003000
X0989125Y1070984
X0992125Y1070984
X0992125Y1074534
X0989125Y1064984
X0989125Y1067984
X0992125Y1067984
X0992125Y1064984
X0983125Y1061434
R03X0003000
X0873582Y1061983
X0873582Y1071533
X0873582Y1068533
X0873582Y1065533
X0876582Y1065533
R02Y0003000
X0876582Y1061983
R02X0003000
X0873582Y1075083
R03X0003000
X0807866Y1366677
X0802866Y1367093
X0805366Y1367093
X0807866Y1369177
X0208058Y1416060
X0185558Y1428560
X0183058Y1428560
X0183058Y1423560
X0183058Y1426060
X0183058Y1421060
X0183058Y1416060
X0183058Y1418560
X1778723Y1636894
X1776023Y1636894
X1776023Y1634294
X1778723Y1634294
X1786615Y1631800
X1784048Y1634375
X1784048Y1636875
X1781423Y1636894
X1781423Y1634394
X1770649Y1634438
X1770649Y1631938
X1773349Y1636938
R02Y-0002500
X1613169Y0531819
X1611775Y0524700
X1609166Y0524700
X1611775Y0527300
X1609166Y0527300
X0740328Y1698376
X0919850Y1565133
R02Y-0003000
X0922850Y1565133
R02Y-0003000
X0919850Y1571133
X0919850Y1568133
X0919850Y1556133
X0922850Y1556133
X0916850Y1565133
R02Y-0003000
X0913850Y1565133
R02Y-0003000
X0916850Y1571133
X0916850Y1568133
X0913850Y1571133
X0913850Y1568133
X0904850Y1565133
R02Y-0003000
X0910850Y1565133
X0907850Y1565133
X0910850Y1562133
X0910850Y1559133
X0907850Y1562133
X0907850Y1559133
X0904850Y1571133
X0904850Y1568133
X0910850Y1571133
X0910850Y1568133
X0907850Y1571133
X0907850Y1568133
X0913850Y1556133
X0916850Y1556133
X0907850Y1556133
X0910850Y1556133
X0904850Y1556133
X0877850Y1568133
X0874850Y1568133
X0877850Y1571133
X0874850Y1571133
X0880850Y1559133
R02X-0003000
X0880850Y1562133
R02X-0003000
X0880850Y1565133
R02X-0003000
X0880850Y1556133
X0874850Y1556133
X0877850Y1556133
X0871850Y1568133
X0868850Y1568133
X0871850Y1571133
X0868850Y1571133
X0862850Y1568133
X0862850Y1571133
X0865850Y1568133
X0865850Y1571133
X0871850Y1559133
X0868850Y1559133
X0871850Y1562133
X0868850Y1562133
X0871850Y1565133
X0868850Y1565133
X0862850Y1559133
R02Y0003000
X0865850Y1559133
R02Y0003000
X0868850Y1556133
X0862850Y1556133
X0871850Y1556133
X0865850Y1556133
X0829850Y1568133
X0829850Y1571133
X0835850Y1568133
X0832850Y1568133
X0835850Y1571133
X0832850Y1571133
X0838850Y1559133
R02Y0003000
X0829850Y1559133
R02Y0003000
X0835850Y1559133
X0832850Y1559133
X0835850Y1562133
X0832850Y1562133
X0835850Y1565133
X0832850Y1565133
X0838850Y1556133
X0832850Y1556133
X0829850Y1556133
X0835850Y1556133
X0823850Y1568133
X0823850Y1571133
X0826850Y1568133
X0826850Y1571133
X0820850Y1568133
X0820850Y1571133
X0823850Y1559133
X0823850Y1562133
X0826850Y1559133
X0826850Y1562133
X0823850Y1565133
X0826850Y1565133
X0820850Y1559133
R02Y0003000
X0826850Y1556133
X0820850Y1556133
X0823850Y1556133
X0790850Y1565133
X0793850Y1565133
X0790850Y1562133
X0793850Y1562133
X0790850Y1559133
X0793850Y1559133
X0787850Y1565133
R02Y-0003000
X0796850Y1565133
R02Y-0003000
X0790850Y1571133
X0793850Y1571133
X0790850Y1568133
X0793850Y1568133
X0787850Y1571133
X0787850Y1568133
X0784850Y1565133
R02Y-0003000
X0784850Y1571133
X0784850Y1568133
X0793850Y1556133
X0787850Y1556133
X0790850Y1556133
X0796850Y1556133
X0784850Y1556133
X0778850Y1565133
R02Y-0003000
X0781850Y1565133
R02Y-0003000
X0778850Y1571133
X0778850Y1568133
X0781850Y1571133
X0781850Y1568133
X0781850Y1556133
X0778850Y1556133
X0748782Y1564496
R02Y-0003000
X0742782Y1570496
X0742782Y1567496
X0739782Y1567496
X0739782Y1570496
X0742782Y1564496
X0745782Y1564496
X0742782Y1561496
X0745782Y1561496
X0742782Y1558496
X0745782Y1558496
X0739782Y1564496
R02Y-0003000
X0745782Y1555496
X0739782Y1555496
X0742782Y1555496
X0748782Y1555496
X0730782Y1564496
R02Y-0003000
X0736782Y1564496
X0733782Y1564496
X0736782Y1561496
X0736782Y1558496
X0733782Y1561496
X0733782Y1558496
X0730782Y1567496
X0736782Y1567496
X0733782Y1567496
X0733782Y1570496
X0736782Y1570496
X0730782Y1570496
X0727571Y1555353
X0733782Y1555496
X0730782Y1555496
X0736782Y1555496
X0727571Y1558353
X0665167Y1380836
X0185558Y1426060
X0185558Y1423560
X0188058Y1426060
X0185558Y1416060
R02Y0002500
X0197983Y1420068
X0195483Y1417568
X0197983Y1417568
X0190483Y1422568
R02Y-0002500
X0188058Y1423560
X0188058Y1418560
X0188058Y1421060
X0188058Y1416060
X0192983Y1422568
X0197983Y1422568
X0195483Y1422568
X0192983Y1420068
X0192983Y1417568
X0195483Y1420068
X0200408Y1418749
X0200408Y1416249
X0202945Y1418410
X0202945Y1415910
X0205558Y1416060
X0205558Y1418560
X0200558Y1421551
X0575075Y0451263
X0831798Y0515314
X0805940Y0534500
X1129845Y1431058
X1129815Y1426818
X1126915Y1431168
X1126915Y1433668
X1129815Y1433668
X1126915Y1426168
X1126915Y1428668
X1124415Y1433668
R03Y-0002500
X1132345Y1431058
X1132315Y1426818
X1134845Y1431058
X1137345Y1431058
X1134815Y1426818
X1137315Y1426818
X1132315Y1433668
X1142715Y1433668
X1142715Y1431168
R02Y-0002500
X1140215Y1431168
X1140215Y1433668
X1137315Y1433668
X1134815Y1433668
X1140215Y1426168
X1140215Y1428668
X1145755Y1433735
R03Y-0002500
X1145715Y1423555
X1140175Y1423488
X1142675Y1423488
X1129775Y1424138
X1126875Y1423488
X1124375Y1423488
X1132275Y1424138
R02X0002500
X1735266Y1413062
X1735266Y1410562
X1732766Y1413062
X1732766Y1410562
X1735266Y1428862
X1735266Y1426362
X1732766Y1428862
X1732766Y1426362
X1740266Y1418462
X1740266Y1415962
X1742766Y1420962
X1740266Y1420962
X1740266Y1423462
X1740266Y1426362
X1742766Y1423462
X1737766Y1428862
X1737766Y1426362
X1742766Y1410562
X1742766Y1413062
X1740266Y1413062
X1740266Y1410562
X1737766Y1413062
X1737766Y1410562
X1742766Y1415962
X1742766Y1418462
X1340509Y1416486
X1331509Y1411318
X1331469Y1413828
X1337509Y1408818
X1334509Y1408818
X1334469Y1413828
X1337469Y1413828
X1337509Y1411318
X1334509Y1411318
X1331509Y1408818
X1334509Y1416486
X1337509Y1416486
X1331509Y1416486
X1341353Y1413866
X1341323Y1409626
X1340549Y1419016
X1340579Y1421536
X1337549Y1419016
X1334549Y1419016
X1334579Y1421536
X1337579Y1421536
X1331549Y1419016
X1331579Y1421536
X1355549Y1419016
X1343579Y1421536
X1343549Y1419016
X1346549Y1419016
X1346579Y1421536
X1352549Y1419016
X1349549Y1419016
X1349579Y1421536
X1352579Y1421536
X1355509Y1408818
X1355509Y1413818
X1355509Y1411318
X1355509Y1416486
X1352509Y1408818
X1352509Y1413818
X1352509Y1411318
X1343509Y1416486
X1352509Y1416486
X1349509Y1416486
X1346509Y1416486
X1343853Y1413866
X1343823Y1409626
X1346353Y1413866
X1346323Y1409626
X1348853Y1413866
X1348823Y1409626
X1358509Y1408818
R02Y0002500
X1358509Y1416486
X1328609Y1421496
X1328539Y1416446
X1328579Y1418976
X1328499Y1413788
X1328539Y1411278
X1322609Y1421496
X1325609Y1421496
X1322579Y1418976
X1322539Y1416446
X1325579Y1418976
X1325539Y1416446
X1325539Y1411278
X1325499Y1413788
X1322499Y1413788
X1322539Y1411278
X0709599Y1414473
X0709599Y1416973
X0717099Y1414473
R02X-0002500
X0717099Y1416973
R02X-0002500
X0709599Y1422373
X0709599Y1419873
X0709599Y1430273
X0709599Y1424873
X0709599Y1427373
X0709599Y1432773
X0714599Y1430273
X0712099Y1430273
X0717099Y1430273
X0714599Y1432773
X0712099Y1432773
X0717099Y1432773
X0941402Y1491204
R02X-0002500
X0943902Y1491204
X0946402Y1491204
X0941402Y1501204
R03Y-0002500
X0938902Y1501204
R03Y-0002500
X0936402Y1501204
R03Y-0002500
X0943902Y1501204
R03Y-0002500
X0946402Y1493704
R03Y0002500
X0961402Y1491204
R02X-0002500
X0948902Y1491204
R02X0002500
X0961402Y1493704
R02X-0002500
X0948902Y1493704
R03Y0002500
X0951402Y1493704
R03Y0002500
X0953902Y1493704
R03Y0002500
X0963902Y1491204
X0977268Y1491204
X0974768Y1491204
R03X-0002500
X0963902Y1493704
X0977268Y1501204
R03Y-0002500
X0974768Y1501204
R03Y-0002500
X0972268Y1501204
R03Y-0002500
X0969768Y1501204
R03Y-0002500
X0967268Y1493704
R03Y0002500
X0987268Y1491204
R03X-0002500
X0990634Y1491204
X0987268Y1493704
R03X-0002500
X0990634Y1501204
R03Y-0002500
X1005634Y1491204
X1003134Y1491204
X0993134Y1491204
R03X0002500
X0993134Y1498704
X0993134Y1501204
X0995634Y1493704
R03Y0002500
X0998134Y1493704
R03Y0002500
X1000634Y1493704
R03Y0002500
X1005634Y1493704
X1003134Y1493704
X0993134Y1493704
X0993134Y1496204
X1010634Y1491204
X1008134Y1491204
X1014000Y1491204
R03X0002500
X1010634Y1493704
X1008134Y1493704
X1014000Y1501204
R03Y-0002500
X1016500Y1493704
R03Y0002500
X1019000Y1493704
R03Y0002500
X1021500Y1493704
R03Y0002500
X1034000Y1493704
R04X-0002500
X1024000Y1496204
R02Y0002500
X1034000Y1491204
R04X-0002500
X1049866Y1491204
X1039866Y1491204
X1042366Y1491204
X1037366Y1491204
X1044866Y1491204
X1047366Y1491204
X1049866Y1493704
X1037366Y1501204
X1039866Y1493704
R03Y0002500
X1042366Y1493704
R03Y0002500
X1044866Y1498704
X1044866Y1501204
X1047366Y1501204
X1037366Y1498704
R02Y-0002500
X1044866Y1493704
X1044866Y1496204
X1047366Y1493704
R02Y0002500
X1057366Y1491204
R02X-0002500
X1060732Y1491204
R02X0002500
X1057366Y1493704
R02X-0002500
X1060732Y1501204
R03Y-0002500
X1063232Y1493704
R03Y0002500
X1065732Y1493704
R03Y0002500
X1080732Y1493704
R03X-0002500
X1068232Y1493704
R03Y0002500
X1070732Y1493704
R03Y0002500
X1080732Y1491204
R03X-0002500
X1068232Y1491204
X1070732Y1491204
X1084098Y1491204
R03X0002500
X1084098Y1496204
X1084098Y1501204
X1084098Y1498704
X1084098Y1493704
X1086598Y1493704
R03Y0002500
X1089098Y1493704
R03Y0002500
X1091598Y1493704
R03Y0002500
X0058751Y0775218
X0061251Y0775218
X0061251Y0777718
X0058751Y0777718
X0058751Y0787718
R02Y-0002500
X0056057Y0782750
X0061251Y0782718
X0061251Y0785218
X0056057Y0785250
X0061251Y0787718
X0056057Y0787750
X0056057Y0790250
X0061251Y0790218
X0061251Y0792718
X0056057Y0792750
X0061251Y0780218
X0058751Y0780218
X0058751Y0792718
X0058751Y0790218
X1802050Y0710940
X1812502Y0715945
R02Y-0002500
X1805502Y0715945
R02Y-0002500
X1809002Y0715945
R02Y-0002500
X1805462Y0708055
R02X-0003500
X1805462Y0705555
R02X-0003500
X1798462Y0703055
R02X0003500
X1798462Y0700555
R02X0003500
X1805462Y0698055
R02X-0003500
X1812462Y0708055
X1808962Y0708055
X1812462Y0705555
X1808962Y0705555
X1808962Y0703055
X1812462Y0703055
X1808962Y0700555
X1812462Y0700555
X1812462Y0698055
X1808962Y0698055
X1497986Y0610338
R02Y-0002500
X1497986Y0612838
X1502486Y0612838
X1502486Y0610338
R02Y-0002500
X1450398Y0621844
X1452898Y0621844
X1450438Y0617364
X1452938Y0617364
X1457898Y0621844
X1455398Y0621844
X1457938Y0617364
X1455438Y0617364
X1443708Y0607954
X1440708Y0607954
X1443708Y0610954
X1440708Y0610954
X1449708Y0607954
X1446708Y0607954
X1446708Y0610954
X1449708Y0610954
X1452708Y0607954
X1452708Y0610954
X1458708Y0607954
X1455708Y0607954
X1461708Y0607954
X1461708Y0610954
X1455708Y0610954
X1458708Y0610954
X1464708Y0607954
X1464708Y0610954
X1467708Y0607954
X1467708Y0610954
X1492636Y0612758
R03Y-0002500
X1495236Y0610338
X1495236Y0607838
X1495486Y0602438
X1495236Y0605338
X1497986Y0599938
X1497986Y0602438
X1495486Y0599938
X1495236Y0612838
X1500486Y0599938
X1500486Y0602438
X1502986Y0599938
X1502986Y0602438
X1443708Y0622954
X1440708Y0622954
X1446708Y0622954
X1443708Y0613954
X1440708Y0613954
X1446708Y0613954
X1449708Y0613954
X1443708Y0619954
X1443708Y0616954
X1440708Y0616954
X1440708Y0619954
X1446708Y0619954
X1446708Y0616954
X1452708Y0613954
X1464708Y0622954
X1461708Y0622954
X1467708Y0622954
X1461708Y0613954
X1455708Y0613954
X1458708Y0613954
X1464708Y0613954
X1464708Y0619954
X1464708Y0616954
X1461708Y0619954
X1461708Y0616954
X1467708Y0613954
X1467708Y0619954
X1467708Y0616954
X1492886Y0615908
X1492886Y0618408
X1497986Y0618488
X1497986Y0615988
X1495486Y0618488
X1495486Y0615988
X1502986Y0618488
X1502986Y0615988
X1500486Y0618488
X1500486Y0615988
X0361031Y0616498
X0361031Y0619398
X0355031Y0616498
X0355031Y0619398
X0358031Y0616498
X0358031Y0619398
X0337031Y0616498
X0337031Y0619398
X0340031Y0616498
X0340031Y0619398
X0331391Y0619398
X0331391Y0616498
X0334031Y0616498
X0334031Y0619398
X0358031Y0604498
X0358031Y0610498
X0358031Y0613498
X0358031Y0607498
X0361031Y0610498
X0361031Y0613498
X0361031Y0607498
X0355031Y0604498
X0352031Y0604498
X0355031Y0610498
X0355031Y0613498
X0355031Y0607498
X0352031Y0610498
X0352031Y0607498
X0340031Y0604498
X0349031Y0604498
X0343031Y0604498
X0346031Y0604498
X0340031Y0613498
R02Y-0003000
X0349031Y0610498
X0343031Y0610498
X0346031Y0610498
X0349031Y0607498
X0343031Y0607498
X0346031Y0607498
X0337031Y0610498
X0337031Y0613498
X0337031Y0607498
X0331391Y0613498
X0331391Y0610498
X0334031Y0610498
X0334031Y0613498
X0351221Y0618348
X0351191Y0614018
X0348721Y0618348
R02X-0002500
X0348691Y0614018
R02X-0002500
X0825200Y0580300
X0465331Y0569132
X0459931Y0569132
X0457431Y0569132
X0462831Y0569132
X0457431Y0566632
X0459931Y0566632
X0459931Y0576632
X0457431Y0576632
X0459931Y0574132
X0459931Y0571632
X0457431Y0574132
X0457431Y0571632
X0470331Y0569132
X0467831Y0569132
X0475731Y0569132
X0473231Y0569132
X0473231Y0576632
X0475731Y0576632
X0473231Y0571632
X0473231Y0574132
X0475731Y0571632
X0475731Y0574132
X0462831Y0566632
X0467831Y0566632
X0465331Y0566632
X0470331Y0566632
X0473231Y0566632
X0475731Y0566632
X0462831Y0576132
X0462831Y0571632
X0470331Y0571632
X0465331Y0576132
X0467831Y0576132
X0465331Y0571632
X0467831Y0571632
X0470331Y0576132
X0408550Y0557850
X1516257Y0547977
X1306815Y0522726
X1308926Y0524111
X1304347Y0523237
X1304566Y0525743
X1302160Y0524916
X1307117Y0525897
X0547529Y0425411
X0608886Y0494400
X0348890Y0411620
X0348890Y0409120
X0351390Y0411620
X0353890Y0411620
X0353890Y0409120
X0351390Y0409120
X0457248Y0282643
X0457248Y0280143
X0454518Y0280793
X0544628Y0289133
X0544628Y0291633
X0541808Y0289743
X0456720Y0285158
X0543780Y0294168
X1301582Y0184051
X1817196Y0159947
X1817196Y0163797
X1719493Y0166478
X1716893Y0166478
X1716893Y0163978
X1719493Y0163978
X1716893Y0161478
X1719493Y0161478
X1722093Y0166478
R02Y-0002500
X1716893Y0158878
R02X0002600
X1725093Y0166478
R02Y-0002500
X1725093Y0158878
X1714293Y0166478
X1711293Y0166478
X1714293Y0163978
X1711293Y0163978
X1714293Y0161478
X1711293Y0161478
X1714293Y0158878
X1711293Y0158878
X1722093Y0156278
R02X-0002600
X1725093Y0156278
X1711293Y0156278
X1714293Y0156278
X1813224Y0194699
X1800554Y0177229
X1014828Y0258970
X1014828Y0268427
X0980377Y0215740
X0980406Y0218283
X1000706Y0203278
X0998206Y0203278
X1000706Y0206821
X0998206Y0206821
X1017701Y0189059
X1014901Y0189299
X1011991Y0189019
X1006161Y0189019
X1002721Y0189299
X0999221Y0189299
X1000706Y0196191
X1000706Y0199735
X0998206Y0196191
X0998206Y0199735
X1022801Y0179799
X1019901Y0179799
X1017201Y0179699
X1014301Y0179699
X1013221Y0164799
X1009721Y0164799
X1002721Y0164799
X1006221Y0164799
X0728734Y0126388
X0728734Y0129288
X0728734Y0132088
X0723134Y0124488
X0719934Y0124488
X0717434Y0135088
X0720434Y0135088
X0748261Y0112552
X0748034Y0116288
X0712734Y0114588
X0712734Y0117488
X0715934Y0114588
X0715934Y0117488
X0695056Y0115178
X0695056Y0112678
X0702142Y0112678
X0705686Y0112678
X0698599Y0112678
X0702142Y0115178
X0705686Y0115178
X0698599Y0115178
X0748125Y0170618
X0681054Y0104668
X1778205Y0090982
X1763644Y0106173
X1760444Y0106173
X1778544Y0097973
X1736986Y0112223
X1736986Y0109723
X1747616Y0109723
X1747616Y0112223
X1744072Y0109723
X1744072Y0112223
X1740529Y0109723
X1740529Y0112223
X1757944Y0116773
X1760944Y0116773
X1755944Y0108473
X1755944Y0111073
X1769244Y0108073
X1769244Y0110973
X1769244Y0113773
X1784144Y0108273
X1784144Y0111173
X1784144Y0113973
X0729918Y0090998
X1757923Y0072637
X0239988Y0141986
X0257252Y0156730
X0311053Y0107106
X0311053Y0110006
X0311053Y0112806
X0301179Y0107106
X0301179Y0110006
X0301179Y0112806
X0280853Y0107306
X0285853Y0115606
X0282853Y0115606
X0280853Y0109906
X0272525Y0111056
X0265438Y0111056
X0261895Y0111056
X0261895Y0108556
X0265438Y0108556
X0268981Y0111056
X0268981Y0108556
X0272525Y0108556
X0285353Y0105006
X0288553Y0105006
X0312410Y0089060
X0543170Y0434737
X0632984Y0471462
X0587500Y0470308
X0746110Y0474971
X0760500Y0521189
X1013396Y0280806
X1377682Y0087587
X0983358Y0449026
X0760500Y0529845
X0987440Y0504742
X0795921Y0312662
X0562208Y0383668
X0779884Y0281705
X0798493Y0301377
X0562030Y0372872
X0065933Y0028406
X1020748Y0420902
X0490419Y0362138
X0041492Y0292892
X0585585Y0372052
X0042449Y0277798
X0065933Y0048720
X0233335Y0017665
X0042449Y0282916
X0042449Y0307798
X0147920Y0028261
X0042449Y0312916
X0148780Y0048720
X0319075Y0260075
X0341895Y0233980
X0303252Y0038199
X0705245Y0443555
X0658949Y0139840
X0306566Y0050225
X0238846Y0072977
X0242920Y0067915
X0248487Y0068690
X0299496Y0022865
X0777421Y0277962
X0748915Y0158608
X0805871Y0304812
X0756303Y0158417
X0300244Y0028365
X0295516Y0026365
X0293157Y0050525
X0288000Y0209000
X0235186Y0098067
X0238059Y0026235
X0680828Y0363500
X0860372Y0375195
X1625000Y0383399
X1692429Y0403985
X0645752Y0134988
X1831166Y0149986
X0823038Y0276301
X0760462Y0295662
X0598208Y0383668
X0586157Y0366827
X0613482Y0383668
X0577482Y0383668
X0619035Y0369542
X0641013Y0324459
X0598414Y0372357
X1472129Y0056083
X1538342Y0028406
X0062567Y0295103
X0621585Y0331358
X1717148Y0019910
X1540342Y0048720
X1654419Y0224597
X1792507Y0403932
X1707186Y0015708
X1792450Y0410615
X1650023Y0221842
X1636047Y0224597
X0703486Y0345507
X1622329Y0028261
X1792335Y0418775
X1629597Y0227157
X1623189Y0048720
X1792220Y0425432
X1636047Y0229912
X1650023Y0227157
X0706139Y0345597
X1779377Y0050738
X1006468Y0301857
X0999320Y0394480
X0723632Y0386862
X1794099Y0050461
X1716558Y0067866
X1712686Y0111908
X1721646Y0068115
X0823067Y0273225
X1770920Y0017031
X0757937Y0303908
X1775920Y0017031
X1770920Y0022031
X1767266Y0048748
X0842257Y0350376
X1712486Y0117908
X1789771Y0367866
X0848425Y0378089
X0126000Y1418000
X0126000Y1414000
X1227000Y1404500
X1227000Y1401300
X0292056Y0024475
X0290795Y0028365
X0286996Y0020365
X0291379Y0055746
X0287988Y0054893
X0275896Y0048875
X0813676Y0266065
X1765920Y0022031
X1765980Y0027031
X0836181Y0275686
X1765920Y0017031
X0836305Y0268624
X1765527Y0053692
X0793855Y0305316
X1763010Y0051223
X0793221Y0296062
X1751031Y0039063
X0769790Y0296231
X0793897Y0309026
X0794058Y0301569
X0758510Y0298620
X0812000Y1064706
X0795858Y1051320
X0812000Y1084785
X0795858Y1238722
R04Y-0036811
X0812000Y1232029
R03Y-0036811
X0812000Y1088131
X0795858Y1235375
R04Y-0036811
X0812000Y1235375
R03Y-0036811
X0812000Y1151714
X0812000Y1145021
X0795858Y1141675
X0795858Y1134982
X0812000Y1138328
X0812000Y1131635
X0795858Y1118249
X0795858Y1252108
X0795858Y1245415
X0795858Y1111556
X0812000Y1248761
X0812000Y1242068
X0795858Y1228682
X0795858Y1221989
X0812000Y1225336
X0812000Y1218643
X0795858Y1215297
X0795858Y1208604
X0812000Y1211950
X0812000Y1205257
X0812000Y1114903
X0795858Y1191871
X0795858Y1185178
X0812000Y1188525
X0812000Y1181832
X0795858Y1178486
X0795858Y1171793
X0812000Y1175139
X0812000Y1168446
X0795858Y1155060
X0795858Y1148367
X0812000Y1108210
X0795858Y1058013
X0812000Y1054667
X0795858Y1081438
X0795858Y1074745
X0812000Y1078092
X0812000Y1071399
X0795858Y1104863
X0795858Y1098171
X0812000Y1101517
X0812000Y1094824
X0812000Y1047974
X0795858Y1044627
X0812000Y1041281
X0795858Y1037934
X0812000Y1034588
X0795858Y1031241
X0812000Y1027895
X0812000Y1061360
X0812000Y1001123
X0795858Y0944234
X0795858Y0907423
X0795858Y0870611
R02Y-0036811
X0812000Y0937541
R04Y-0036811
X0795858Y0940887
R04Y-0036811
X0812000Y0940887
R04Y-0036811
X0812000Y0820415
X0812000Y0813722
X0795858Y0810375
X0795858Y0803682
X0812000Y0807029
X0812000Y0800336
X0795858Y0786950
X0795858Y0920808
X0795858Y0914115
X0795858Y0780257
X0812000Y0917462
X0812000Y0910769
X0795858Y0897383
X0795858Y0890690
X0812000Y0894037
X0812000Y0887344
X0795858Y0883997
X0795858Y0877304
X0812000Y0880651
X0812000Y0873958
X0812000Y0783604
X0795858Y0860572
X0795858Y0853879
X0812000Y0857226
X0812000Y0850533
X0795858Y0847186
X0795858Y0840493
X0812000Y0843840
X0812000Y0837147
X0795858Y0823761
X0795858Y0817068
X0812000Y0776911
X0795858Y0971005
X0812000Y0967659
X0795858Y0957619
X0795858Y0950926
X0812000Y0954273
X0812000Y0947580
X0795858Y0934194
X0795858Y0927501
X0812000Y0930848
X0812000Y0924155
X0812000Y0994430
X0795858Y0991084
X0812000Y0987737
X0795858Y0984391
X0812000Y0981045
X0795858Y0977698
X0812000Y0974352
X0795858Y0964312
X0795858Y0997777
X0795858Y1001123
X0806500Y0960966
X0812000Y0960966
X1788142Y1064705
X1772000Y1051319
X1788142Y1084784
X1772000Y1238721
R04Y-0036811
X1788142Y1232028
R03Y-0036811
X1788142Y1088130
X1772000Y1235374
R04Y-0036811
X1788142Y1235374
R03Y-0036811
X1788142Y1151713
X1788142Y1145020
X1772000Y1141674
X1772000Y1134981
X1788142Y1138327
X1788142Y1131634
X1772000Y1118248
X1772000Y1252107
X1772000Y1245414
X1772000Y1111555
X1788142Y1248760
X1788142Y1242067
X1772000Y1228681
X1772000Y1221988
X1788142Y1225335
X1788142Y1218642
X1772000Y1215296
X1772000Y1208603
X1788142Y1211949
X1788142Y1205256
X1788142Y1114902
X1772000Y1191870
X1772000Y1185177
X1788142Y1188524
X1788142Y1181831
X1772000Y1178485
X1772000Y1171792
X1788142Y1175138
X1788142Y1168445
X1772000Y1155059
X1772000Y1148366
X1788142Y1108209
X1772000Y1058012
X1788142Y1054666
X1772000Y1081437
X1772000Y1074744
X1788142Y1078091
X1788142Y1071398
X1772000Y1104862
X1772000Y1098170
X1788142Y1101516
X1788142Y1094823
X1788142Y1047973
X1772000Y1044626
X1788142Y1041280
X1772000Y1037933
X1788142Y1034587
X1772000Y1031240
X1788142Y1027894
X1788142Y1061359
X1788142Y1001122
X1772000Y0944233
X1772000Y0907422
X1772000Y0870610
R02Y-0036811
X1788142Y0937540
R04Y-0036811
X1772000Y0940886
R04Y-0036811
X1788142Y0940886
R04Y-0036811
X1788142Y0820414
X1788142Y0813721
X1772000Y0810374
X1772000Y0803681
X1788142Y0807028
X1788142Y0800335
X1772000Y0786949
X1772000Y0920807
X1772000Y0914114
X1772000Y0780256
X1788142Y0917461
X1788142Y0910768
X1772000Y0897382
X1772000Y0890689
X1788142Y0894036
X1788142Y0887343
X1772000Y0883996
X1772000Y0877303
X1788142Y0880650
X1788142Y0873957
X1788142Y0783603
X1772000Y0860571
X1772000Y0853878
X1788142Y0857225
X1788142Y0850532
X1772000Y0847185
X1772000Y0840492
X1788142Y0843839
X1788142Y0837146
X1772000Y0823760
X1772000Y0817067
X1788142Y0776910
X1772000Y0971004
X1788142Y0967658
X1772000Y0957618
X1772000Y0950925
X1788142Y0954272
X1788142Y0947579
X1772000Y0934193
X1772000Y0927500
X1788142Y0930847
X1788142Y0924154
X1788142Y0994429
X1772000Y0991083
X1788142Y0987736
X1772000Y0984390
X1788142Y0981044
X1772000Y0977697
X1788142Y0974351
X1772000Y0964311
X1772000Y0997776
X1772000Y1001122
X1782642Y0960965
X1788142Y0960965
X0782300Y1064706
X0766158Y1051320
X0782300Y1084785
X0766158Y1238722
R04Y-0036811
X0782300Y1232029
R03Y-0036811
X0782300Y1088131
X0766158Y1235375
R04Y-0036811
X0782300Y1235375
R03Y-0036811
X0782300Y1151714
X0782300Y1145021
X0766158Y1141675
X0766158Y1134982
X0782300Y1138328
X0782300Y1131635
X0766158Y1118249
X0766158Y1252108
X0766158Y1245415
X0766158Y1111556
X0782300Y1248761
X0782300Y1242068
X0766158Y1228682
X0766158Y1221989
X0782300Y1225336
X0782300Y1218643
X0766158Y1215297
X0766158Y1208604
X0782300Y1211950
X0782300Y1205257
X0782300Y1114903
X0766158Y1191871
X0766158Y1185178
X0782300Y1188525
X0782300Y1181832
X0766158Y1178486
X0766158Y1171793
X0782300Y1175139
X0782300Y1168446
X0766158Y1155060
X0766158Y1148367
X0782300Y1108210
X0766158Y1058013
X0782300Y1054667
X0766158Y1081438
X0766158Y1074745
X0782300Y1078092
X0782300Y1071399
X0766158Y1104863
X0766158Y1098171
X0782300Y1101517
X0782300Y1094824
X0782300Y1047974
X0766158Y1044627
X0782300Y1041281
X0766158Y1037934
X0782300Y1034588
X0766158Y1031241
X0782300Y1027895
X0782300Y1061360
X0782300Y1001123
X0766158Y0944234
X0766158Y0907423
X0766158Y0870611
R02Y-0036811
X0782300Y0937541
R04Y-0036811
X0766158Y0940887
R04Y-0036811
X0782300Y0940887
R04Y-0036811
X0782300Y0820415
X0782300Y0813722
X0766158Y0810375
X0766158Y0803682
X0782300Y0807029
X0782300Y0800336
X0766158Y0786950
X0766158Y0920808
X0766158Y0914115
X0766158Y0780257
X0782300Y0917462
X0782300Y0910769
X0766158Y0897383
X0766158Y0890690
X0782300Y0894037
X0782300Y0887344
X0766158Y0883997
X0766158Y0877304
X0782300Y0880651
X0782300Y0873958
X0782300Y0783604
X0766158Y0860572
X0766158Y0853879
X0782300Y0857226
X0782300Y0850533
X0766158Y0847186
X0766158Y0840493
X0782300Y0843840
X0782300Y0837147
X0766158Y0823761
X0766158Y0817068
X0782300Y0776911
X0766158Y0971005
X0782300Y0967659
X0766158Y0957619
X0766158Y0950926
X0782300Y0954273
X0782300Y0947580
X0766158Y0934194
X0766158Y0927501
X0782300Y0930848
X0782300Y0924155
X0782300Y0994430
X0766158Y0991084
X0782300Y0987737
X0766158Y0984391
X0782300Y0981045
X0766158Y0977698
X0782300Y0974352
X0766158Y0964312
X0766158Y0997777
X0766158Y1001123
X0776800Y0960966
X0782300Y0960966
X1758442Y1064705
X1742300Y1051319
X1758442Y1084784
X1742300Y1238721
R04Y-0036811
X1758442Y1232028
R03Y-0036811
X1758442Y1088130
X1742300Y1235374
R04Y-0036811
X1758442Y1235374
R03Y-0036811
X1758442Y1151713
X1758442Y1145020
X1742300Y1141674
X1742300Y1134981
X1758442Y1138327
X1758442Y1131634
X1742300Y1118248
X1742300Y1252107
X1742300Y1245414
X1742300Y1111555
X1758442Y1248760
X1758442Y1242067
X1742300Y1228681
X1742300Y1221988
X1758442Y1225335
X1758442Y1218642
X1742300Y1215296
X1742300Y1208603
X1758442Y1211949
X1758442Y1205256
X1758442Y1114902
X1742300Y1191870
X1742300Y1185177
X1758442Y1188524
X1758442Y1181831
X1742300Y1178485
X1742300Y1171792
X1758442Y1175138
X1758442Y1168445
X1742300Y1155059
X1742300Y1148366
X1758442Y1108209
X1742300Y1058012
X1758442Y1054666
X1742300Y1081437
X1742300Y1074744
X1758442Y1078091
X1758442Y1071398
X1742300Y1104862
X1742300Y1098170
X1758442Y1101516
X1758442Y1094823
X1758442Y1047973
X1742300Y1044626
X1758442Y1041280
X1742300Y1037933
X1758442Y1034587
X1742300Y1031240
X1758442Y1027894
X1758442Y1061359
X1758442Y1001122
X1742300Y0944233
X1742300Y0907422
X1742300Y0870610
R02Y-0036811
X1758442Y0937540
R04Y-0036811
X1742300Y0940886
R04Y-0036811
X1758442Y0940886
R04Y-0036811
X1758442Y0820414
X1758442Y0813721
X1742300Y0810374
X1742300Y0803681
X1758442Y0807028
X1758442Y0800335
X1742300Y0786949
X1742300Y0920807
X1742300Y0914114
X1742300Y0780256
X1758442Y0917461
X1758442Y0910768
X1742300Y0897382
X1742300Y0890689
X1758442Y0894036
X1758442Y0887343
X1742300Y0883996
X1742300Y0877303
X1758442Y0880650
X1758442Y0873957
X1758442Y0783603
X1742300Y0860571
X1742300Y0853878
X1758442Y0857225
X1758442Y0850532
X1742300Y0847185
X1742300Y0840492
X1758442Y0843839
X1758442Y0837146
X1742300Y0823760
X1742300Y0817067
X1758442Y0776910
X1742300Y0971004
X1758442Y0967658
X1742300Y0957618
X1742300Y0950925
X1758442Y0954272
X1758442Y0947579
X1742300Y0934193
X1742300Y0927500
X1758442Y0930847
X1758442Y0924154
X1758442Y0994429
X1742300Y0991083
X1758442Y0987736
X1742300Y0984390
X1758442Y0981044
X1742300Y0977697
X1758442Y0974351
X1742300Y0964311
X1742300Y0997776
X1742300Y1001122
X1752942Y0960965
X1758442Y0960965
X0752599Y1064706
X0736457Y1051320
X0752599Y1084785
X0736457Y1238722
R04Y-0036811
X0752599Y1232029
R03Y-0036811
X0752599Y1088131
X0736457Y1235375
R04Y-0036811
X0752599Y1235375
R03Y-0036811
X0752599Y1151714
X0752599Y1145021
X0736457Y1141675
X0736457Y1134982
X0752599Y1138328
X0752599Y1131635
X0736457Y1118249
X0736457Y1252108
X0736457Y1245415
X0736457Y1111556
X0752599Y1248761
X0752599Y1242068
X0736457Y1228682
X0736457Y1221989
X0752599Y1225336
X0752599Y1218643
X0736457Y1215297
X0736457Y1208604
X0752599Y1211950
X0752599Y1205257
X0752599Y1114903
X0736457Y1191871
X0736457Y1185178
X0752599Y1188525
X0752599Y1181832
X0736457Y1178486
X0736457Y1171793
X0752599Y1175139
X0752599Y1168446
X0736457Y1155060
X0736457Y1148367
X0752599Y1108210
X0736457Y1058013
X0752599Y1054667
X0736457Y1081438
X0736457Y1074745
X0752599Y1078092
X0752599Y1071399
X0736457Y1104863
X0736457Y1098171
X0752599Y1101517
X0752599Y1094824
X0752599Y1047974
X0736457Y1044627
X0752599Y1041281
X0736457Y1037934
X0752599Y1034588
X0736457Y1031241
X0752599Y1027895
X0752599Y1061360
X0752599Y1001123
X0736457Y0944234
X0736457Y0907423
X0736457Y0870611
R02Y-0036811
X0752599Y0937541
R04Y-0036811
X0736457Y0940887
R04Y-0036811
X0752599Y0940887
R04Y-0036811
X0752599Y0820415
X0752599Y0813722
X0736457Y0810375
X0736457Y0803682
X0752599Y0807029
X0752599Y0800336
X0736457Y0786950
X0736457Y0920808
X0736457Y0914115
X0736457Y0780257
X0752599Y0917462
X0752599Y0910769
X0736457Y0897383
X0736457Y0890690
X0752599Y0894037
X0752599Y0887344
X0736457Y0883997
X0736457Y0877304
X0752599Y0880651
X0752599Y0873958
X0752599Y0783604
X0736457Y0860572
X0736457Y0853879
X0752599Y0857226
X0752599Y0850533
X0736457Y0847186
X0736457Y0840493
X0752599Y0843840
X0752599Y0837147
X0736457Y0823761
X0736457Y0817068
X0752599Y0776911
X0736457Y0971005
X0752599Y0967659
X0736457Y0957619
X0736457Y0950926
X0752599Y0954273
X0752599Y0947580
X0736457Y0934194
X0736457Y0927501
X0752599Y0930848
X0752599Y0924155
X0752599Y0994430
X0736457Y0991084
X0752599Y0987737
X0736457Y0984391
X0752599Y0981045
X0736457Y0977698
X0752599Y0974352
X0736457Y0964312
X0736457Y0997777
X0736457Y1001123
X0747099Y0960966
X0752599Y0960966
X1728741Y1064705
X1712599Y1051319
X1728741Y1084784
X1712599Y1238721
R04Y-0036811
X1728741Y1232028
R03Y-0036811
X1728741Y1088130
X1712599Y1235374
R04Y-0036811
X1728741Y1235374
R03Y-0036811
X1728741Y1151713
X1728741Y1145020
X1712599Y1141674
X1712599Y1134981
X1728741Y1138327
X1728741Y1131634
X1712599Y1118248
X1712599Y1252107
X1712599Y1245414
X1712599Y1111555
X1728741Y1248760
X1728741Y1242067
X1712599Y1228681
X1712599Y1221988
X1728741Y1225335
X1728741Y1218642
X1712599Y1215296
X1712599Y1208603
X1728741Y1211949
X1728741Y1205256
X1728741Y1114902
X1712599Y1191870
X1712599Y1185177
X1728741Y1188524
X1728741Y1181831
X1712599Y1178485
X1712599Y1171792
X1728741Y1175138
X1728741Y1168445
X1712599Y1155059
X1712599Y1148366
X1728741Y1108209
X1712599Y1058012
X1728741Y1054666
X1712599Y1081437
X1712599Y1074744
X1728741Y1078091
X1728741Y1071398
X1712599Y1104862
X1712599Y1098170
X1728741Y1101516
X1728741Y1094823
X1728741Y1047973
X1712599Y1044626
X1728741Y1041280
X1712599Y1037933
X1728741Y1034587
X1712599Y1031240
X1728741Y1027894
X1728741Y1061359
X1728741Y1001122
X1712599Y0944233
X1712599Y0907422
X1712599Y0870610
R02Y-0036811
X1728741Y0937540
R04Y-0036811
X1712599Y0940886
R04Y-0036811
X1728741Y0940886
R04Y-0036811
X1728741Y0820414
X1728741Y0813721
X1712599Y0810374
X1712599Y0803681
X1728741Y0807028
X1728741Y0800335
X1712599Y0786949
X1712599Y0920807
X1712599Y0914114
X1712599Y0780256
X1728741Y0917461
X1728741Y0910768
X1712599Y0897382
X1712599Y0890689
X1728741Y0894036
X1728741Y0887343
X1712599Y0883996
X1712599Y0877303
X1728741Y0880650
X1728741Y0873957
X1728741Y0783603
X1712599Y0860571
X1712599Y0853878
X1728741Y0857225
X1728741Y0850532
X1712599Y0847185
X1712599Y0840492
X1728741Y0843839
X1728741Y0837146
X1712599Y0823760
X1712599Y0817067
X1728741Y0776910
X1712599Y0971004
X1728741Y0967658
X1712599Y0957618
X1712599Y0950925
X1728741Y0954272
X1728741Y0947579
X1712599Y0934193
X1712599Y0927500
X1728741Y0930847
X1728741Y0924154
X1728741Y0994429
X1712599Y0991083
X1728741Y0987736
X1712599Y0984390
X1728741Y0981044
X1712599Y0977697
X1728741Y0974351
X1712599Y0964311
X1712599Y0997776
X1712599Y1001122
X1723241Y0960965
X1728741Y0960965
X0722898Y1064706
X0706756Y1051320
X0722898Y1084785
X0706756Y1238722
R04Y-0036811
X0722898Y1232029
R03Y-0036811
X0722898Y1088131
X0706756Y1235375
R04Y-0036811
X0722898Y1235375
R03Y-0036811
X0722898Y1151714
X0722898Y1145021
X0706756Y1141675
X0706756Y1134982
X0722898Y1138328
X0722898Y1131635
X0706756Y1118249
X0706756Y1252108
X0706756Y1245415
X0706756Y1111556
X0722898Y1248761
X0722898Y1242068
X0706756Y1228682
X0706756Y1221989
X0722898Y1225336
X0722898Y1218643
X0706756Y1215297
X0706756Y1208604
X0722898Y1211950
X0722898Y1205257
X0722898Y1114903
X0706756Y1191871
X0706756Y1185178
X0722898Y1188525
X0722898Y1181832
X0706756Y1178486
X0706756Y1171793
X0722898Y1175139
X0722898Y1168446
X0706756Y1155060
X0706756Y1148367
X0722898Y1108210
X0706756Y1058013
X0722898Y1054667
X0706756Y1081438
X0706756Y1074745
X0722898Y1078092
X0722898Y1071399
X0706756Y1104863
X0706756Y1098171
X0722898Y1101517
X0722898Y1094824
X0722898Y1047974
X0706756Y1044627
X0722898Y1041281
X0706756Y1037934
X0722898Y1034588
X0706756Y1031241
X0722898Y1027895
X0722898Y1061360
X0722898Y1001123
X0706756Y0944234
X0706756Y0907423
X0706756Y0870611
R02Y-0036811
X0722898Y0937541
R04Y-0036811
X0706756Y0940887
R04Y-0036811
X0722898Y0940887
R04Y-0036811
X0722898Y0820415
X0722898Y0813722
X0706756Y0810375
X0706756Y0803682
X0722898Y0807029
X0722898Y0800336
X0706756Y0786950
X0706756Y0920808
X0706756Y0914115
X0706756Y0780257
X0722898Y0917462
X0722898Y0910769
X0706756Y0897383
X0706756Y0890690
X0722898Y0894037
X0722898Y0887344
X0706756Y0883997
X0706756Y0877304
X0722898Y0880651
X0722898Y0873958
X0722898Y0783604
X0706756Y0860572
X0706756Y0853879
X0722898Y0857226
X0722898Y0850533
X0706756Y0847186
X0706756Y0840493
X0722898Y0843840
X0722898Y0837147
X0706756Y0823761
X0706756Y0817068
X0722898Y0776911
X0706756Y0971005
X0722898Y0967659
X0706756Y0957619
X0706756Y0950926
X0722898Y0954273
X0722898Y0947580
X0706756Y0934194
X0706756Y0927501
X0722898Y0930848
X0722898Y0924155
X0722898Y0994430
X0706756Y0991084
X0722898Y0987737
X0706756Y0984391
X0722898Y0981045
X0706756Y0977698
X0722898Y0974352
X0706756Y0964312
X0706756Y0997777
X0706756Y1001123
X0717398Y0960966
X0722898Y0960966
X1699040Y1064705
X1682898Y1051319
X1699040Y1084784
X1682898Y1238721
R04Y-0036811
X1699040Y1232028
R03Y-0036811
X1699040Y1088130
X1682898Y1235374
R04Y-0036811
X1699040Y1235374
R03Y-0036811
X1699040Y1151713
X1699040Y1145020
X1682898Y1141674
X1682898Y1134981
X1699040Y1138327
X1699040Y1131634
X1682898Y1118248
X1682898Y1252107
X1682898Y1245414
X1682898Y1111555
X1699040Y1248760
X1699040Y1242067
X1682898Y1228681
X1682898Y1221988
X1699040Y1225335
X1699040Y1218642
X1682898Y1215296
X1682898Y1208603
X1699040Y1211949
X1699040Y1205256
X1699040Y1114902
X1682898Y1191870
X1682898Y1185177
X1699040Y1188524
X1699040Y1181831
X1682898Y1178485
X1682898Y1171792
X1699040Y1175138
X1699040Y1168445
X1682898Y1155059
X1682898Y1148366
X1699040Y1108209
X1682898Y1058012
X1699040Y1054666
X1682898Y1081437
X1682898Y1074744
X1699040Y1078091
X1699040Y1071398
X1682898Y1104862
X1682898Y1098170
X1699040Y1101516
X1699040Y1094823
X1699040Y1047973
X1682898Y1044626
X1699040Y1041280
X1682898Y1037933
X1699040Y1034587
X1682898Y1031240
X1699040Y1027894
X1699040Y1061359
X1699040Y1001122
X1682898Y0944233
X1682898Y0907422
X1682898Y0870610
R02Y-0036811
X1699040Y0937540
R04Y-0036811
X1682898Y0940886
R04Y-0036811
X1699040Y0940886
R04Y-0036811
X1699040Y0820414
X1699040Y0813721
X1682898Y0810374
X1682898Y0803681
X1699040Y0807028
X1699040Y0800335
X1682898Y0786949
X1682898Y0920807
X1682898Y0914114
X1682898Y0780256
X1699040Y0917461
X1699040Y0910768
X1682898Y0897382
X1682898Y0890689
X1699040Y0894036
X1699040Y0887343
X1682898Y0883996
X1682898Y0877303
X1699040Y0880650
X1699040Y0873957
X1699040Y0783603
X1682898Y0860571
X1682898Y0853878
X1699040Y0857225
X1699040Y0850532
X1682898Y0847185
X1682898Y0840492
X1699040Y0843839
X1699040Y0837146
X1682898Y0823760
X1682898Y0817067
X1699040Y0776910
X1682898Y0971004
X1699040Y0967658
X1682898Y0957618
X1682898Y0950925
X1699040Y0954272
X1699040Y0947579
X1682898Y0934193
X1682898Y0927500
X1699040Y0930847
X1699040Y0924154
X1699040Y0994429
X1682898Y0991083
X1699040Y0987736
X1682898Y0984390
X1699040Y0981044
X1682898Y0977697
X1699040Y0974351
X1682898Y0964311
X1682898Y0997776
X1682898Y1001122
X1693540Y0960965
X1699040Y0960965
X0693197Y1064706
X0677055Y1051320
X0693197Y1084785
X0677055Y1238722
R04Y-0036811
X0693197Y1232029
R03Y-0036811
X0693197Y1088131
X0677055Y1235375
R04Y-0036811
X0693197Y1235375
R03Y-0036811
X0693197Y1151714
X0693197Y1145021
X0677055Y1141675
X0677055Y1134982
X0693197Y1138328
X0693197Y1131635
X0677055Y1118249
X0677055Y1252108
X0677055Y1245415
X0677055Y1111556
X0693197Y1248761
X0693197Y1242068
X0677055Y1228682
X0677055Y1221989
X0693197Y1225336
X0693197Y1218643
X0677055Y1215297
X0677055Y1208604
X0693197Y1211950
X0693197Y1205257
X0693197Y1114903
X0677055Y1191871
X0677055Y1185178
X0693197Y1188525
X0693197Y1181832
X0677055Y1178486
X0677055Y1171793
X0693197Y1175139
X0693197Y1168446
X0677055Y1155060
X0677055Y1148367
X0693197Y1108210
X0677055Y1058013
X0693197Y1054667
X0677055Y1081438
X0677055Y1074745
X0693197Y1078092
X0693197Y1071399
X0677055Y1104863
X0677055Y1098171
X0693197Y1101517
X0693197Y1094824
X0693197Y1047974
X0677055Y1044627
X0693197Y1041281
X0677055Y1037934
X0693197Y1034588
X0677055Y1031241
X0693197Y1027895
X0693197Y1061360
X0693197Y1001123
X0677055Y0944234
X0677055Y0907423
X0677055Y0870611
R02Y-0036811
X0693197Y0937541
R04Y-0036811
X0677055Y0940887
R04Y-0036811
X0693197Y0940887
R04Y-0036811
X0693197Y0820415
X0693197Y0813722
X0677055Y0810375
X0677055Y0803682
X0693197Y0807029
X0693197Y0800336
X0677055Y0786950
X0677055Y0920808
X0677055Y0914115
X0677055Y0780257
X0693197Y0917462
X0693197Y0910769
X0677055Y0897383
X0677055Y0890690
X0693197Y0894037
X0693197Y0887344
X0677055Y0883997
X0677055Y0877304
X0693197Y0880651
X0693197Y0873958
X0693197Y0783604
X0677055Y0860572
X0677055Y0853879
X0693197Y0857226
X0693197Y0850533
X0677055Y0847186
X0677055Y0840493
X0693197Y0843840
X0693197Y0837147
X0677055Y0823761
X0677055Y0817068
X0693197Y0776911
X0677055Y0971005
X0693197Y0967659
X0677055Y0957619
X0677055Y0950926
X0693197Y0954273
X0693197Y0947580
X0677055Y0934194
X0677055Y0927501
X0693197Y0930848
X0693197Y0924155
X0693197Y0994430
X0677055Y0991084
X0693197Y0987737
X0677055Y0984391
X0693197Y0981045
X0677055Y0977698
X0693197Y0974352
X0677055Y0964312
X0677055Y0997777
X0677055Y1001123
X0687697Y0960966
X0693197Y0960966
X1669339Y1064705
X1653197Y1051319
X1669339Y1084784
X1653197Y1238721
R04Y-0036811
X1669339Y1232028
R03Y-0036811
X1669339Y1088130
X1653197Y1235374
R04Y-0036811
X1669339Y1235374
R03Y-0036811
X1669339Y1151713
X1669339Y1145020
X1653197Y1141674
X1653197Y1134981
X1669339Y1138327
X1669339Y1131634
X1653197Y1118248
X1653197Y1252107
X1653197Y1245414
X1653197Y1111555
X1669339Y1248760
X1669339Y1242067
X1653197Y1228681
X1653197Y1221988
X1669339Y1225335
X1669339Y1218642
X1653197Y1215296
X1653197Y1208603
X1669339Y1211949
X1669339Y1205256
X1669339Y1114902
X1653197Y1191870
X1653197Y1185177
X1669339Y1188524
X1669339Y1181831
X1653197Y1178485
X1653197Y1171792
X1669339Y1175138
X1669339Y1168445
X1653197Y1155059
X1653197Y1148366
X1669339Y1108209
X1653197Y1058012
X1669339Y1054666
X1653197Y1081437
X1653197Y1074744
X1669339Y1078091
X1669339Y1071398
X1653197Y1104862
X1653197Y1098170
X1669339Y1101516
X1669339Y1094823
X1669339Y1047973
X1653197Y1044626
X1669339Y1041280
X1653197Y1037933
X1669339Y1034587
X1653197Y1031240
X1669339Y1027894
X1669339Y1061359
X1669339Y1001122
X1653197Y0944233
X1653197Y0907422
X1653197Y0870610
R02Y-0036811
X1669339Y0937540
R04Y-0036811
X1653197Y0940886
R04Y-0036811
X1669339Y0940886
R04Y-0036811
X1669339Y0820414
X1669339Y0813721
X1653197Y0810374
X1653197Y0803681
X1669339Y0807028
X1669339Y0800335
X1653197Y0786949
X1653197Y0920807
X1653197Y0914114
X1653197Y0780256
X1669339Y0917461
X1669339Y0910768
X1653197Y0897382
X1653197Y0890689
X1669339Y0894036
X1669339Y0887343
X1653197Y0883996
X1653197Y0877303
X1669339Y0880650
X1669339Y0873957
X1669339Y0783603
X1653197Y0860571
X1653197Y0853878
X1669339Y0857225
X1669339Y0850532
X1653197Y0847185
X1653197Y0840492
X1669339Y0843839
X1669339Y0837146
X1653197Y0823760
X1653197Y0817067
X1669339Y0776910
X1653197Y0971004
X1669339Y0967658
X1653197Y0957618
X1653197Y0950925
X1669339Y0954272
X1669339Y0947579
X1653197Y0934193
X1653197Y0927500
X1669339Y0930847
X1669339Y0924154
X1669339Y0994429
X1653197Y0991083
X1669339Y0987736
X1653197Y0984390
X1669339Y0981044
X1653197Y0977697
X1669339Y0974351
X1653197Y0964311
X1653197Y0997776
X1653197Y1001122
X1663839Y0960965
X1669339Y0960965
X0657996Y0960966
X0663496Y0960966
X1634138Y0960965
X1639638Y0960965
X0085465Y1064706
X0069323Y1051320
X0085465Y1084785
X0069323Y1238722
R04Y-0036811
X0085465Y1232029
R03Y-0036811
X0085465Y1088131
X0069323Y1235375
R04Y-0036811
X0085465Y1235375
R03Y-0036811
X0085465Y1151714
X0085465Y1145021
X0069323Y1141675
X0069323Y1134982
X0085465Y1138328
X0085465Y1131635
X0069323Y1118249
X0069323Y1252108
X0069323Y1245415
X0069323Y1111556
X0085465Y1248761
X0085465Y1242068
X0069323Y1228682
X0069323Y1221989
X0085465Y1225336
X0085465Y1218643
X0069323Y1215297
X0069323Y1208604
X0085465Y1211950
X0085465Y1205257
X0085465Y1114903
X0069323Y1191871
X0069323Y1185178
X0085465Y1188525
X0085465Y1181832
X0069323Y1178486
X0069323Y1171793
X0085465Y1175139
X0085465Y1168446
X0069323Y1155060
X0069323Y1148367
X0085465Y1108210
X0069323Y1058013
X0085465Y1054667
X0069323Y1081438
X0069323Y1074745
X0085465Y1078092
X0085465Y1071399
X0069323Y1104863
X0069323Y1098171
X0085465Y1101517
X0085465Y1094824
X0085465Y1047974
X0069323Y1044627
X0085465Y1041281
X0069323Y1037934
X0085465Y1034588
X0069323Y1031241
X0085465Y1027895
X0085465Y1061360
X0085465Y1001123
X0069323Y0944234
X0069323Y0907423
X0069323Y0870611
R02Y-0036811
X0085465Y0937541
R04Y-0036811
X0069323Y0940887
R04Y-0036811
X0085465Y0940887
R04Y-0036811
X0085465Y0820415
X0085465Y0813722
X0069323Y0810375
X0069323Y0803682
X0085465Y0807029
X0085465Y0800336
X0069323Y0786950
X0069323Y0920808
X0069323Y0914115
X0069323Y0780257
X0085465Y0917462
X0085465Y0910769
X0069323Y0897383
X0069323Y0890690
X0085465Y0894037
X0085465Y0887344
X0069323Y0883997
X0069323Y0877304
X0085465Y0880651
X0085465Y0873958
X0085465Y0783604
X0069323Y0860572
X0069323Y0853879
X0085465Y0857226
X0085465Y0850533
X0069323Y0847186
X0069323Y0840493
X0085465Y0843840
X0085465Y0837147
X0069323Y0823761
X0069323Y0817068
X0085465Y0776911
X0069323Y0971005
X0085465Y0967659
X0069323Y0957619
X0069323Y0950926
X0085465Y0954273
X0085465Y0947580
X0069323Y0934194
X0069323Y0927501
X0085465Y0930848
X0085465Y0924155
X0085465Y0994430
X0069323Y0991084
X0085465Y0987737
X0069323Y0984391
X0085465Y0981045
X0069323Y0977698
X0085465Y0974352
X0069323Y0964312
X0069323Y0997777
X0069323Y1001123
X0090965Y0960966
X0085465Y0960966
X1061607Y1064705
X1045465Y1051319
X1061607Y1084784
X1045465Y1238721
R04Y-0036811
X1061607Y1232028
R03Y-0036811
X1061607Y1088130
X1045465Y1235374
R04Y-0036811
X1061607Y1235374
R03Y-0036811
X1061607Y1151713
X1061607Y1145020
X1045465Y1141674
X1045465Y1134981
X1061607Y1138327
X1061607Y1131634
X1045465Y1118248
X1045465Y1252107
X1045465Y1245414
X1045465Y1111555
X1061607Y1248760
X1061607Y1242067
X1045465Y1228681
X1045465Y1221988
X1061607Y1225335
X1061607Y1218642
X1045465Y1215296
X1045465Y1208603
X1061607Y1211949
X1061607Y1205256
X1061607Y1114902
X1045465Y1191870
X1045465Y1185177
X1061607Y1188524
X1061607Y1181831
X1045465Y1178485
X1045465Y1171792
X1061607Y1175138
X1061607Y1168445
X1045465Y1155059
X1045465Y1148366
X1061607Y1108209
X1045465Y1058012
X1061607Y1054666
X1045465Y1081437
X1045465Y1074744
X1061607Y1078091
X1061607Y1071398
X1045465Y1104862
X1045465Y1098170
X1061607Y1101516
X1061607Y1094823
X1061607Y1047973
X1045465Y1044626
X1061607Y1041280
X1045465Y1037933
X1061607Y1034587
X1045465Y1031240
X1061607Y1027894
X1061607Y1061359
X1061607Y1001122
X1045465Y0944233
X1045465Y0907422
X1045465Y0870610
R02Y-0036811
X1061607Y0937540
R04Y-0036811
X1045465Y0940886
R04Y-0036811
X1061607Y0940886
R04Y-0036811
X1061607Y0820414
X1061607Y0813721
X1045465Y0810374
X1045465Y0803681
X1061607Y0807028
X1061607Y0800335
X1045465Y0786949
X1045465Y0920807
X1045465Y0914114
X1045465Y0780256
X1061607Y0917461
X1061607Y0910768
X1045465Y0897382
X1045465Y0890689
X1061607Y0894036
X1061607Y0887343
X1045465Y0883996
X1045465Y0877303
X1061607Y0880650
X1061607Y0873957
X1061607Y0783603
X1045465Y0860571
X1045465Y0853878
X1061607Y0857225
X1061607Y0850532
X1045465Y0847185
X1045465Y0840492
X1061607Y0843839
X1061607Y0837146
X1045465Y0823760
X1045465Y0817067
X1061607Y0776910
X1045465Y0971004
X1061607Y0967658
X1045465Y0957618
X1045465Y0950925
X1061607Y0954272
X1061607Y0947579
X1045465Y0934193
X1045465Y0927500
X1061607Y0930847
X1061607Y0924154
X1061607Y0994429
X1045465Y0991083
X1061607Y0987736
X1045465Y0984390
X1061607Y0981044
X1045465Y0977697
X1061607Y0974351
X1045465Y0964311
X1045465Y0997776
X1045465Y1001122
X1067107Y0960965
X1061607Y0960965
X0115166Y1064706
X0099024Y1051320
X0115166Y1084785
X0099024Y1238722
R04Y-0036811
X0115166Y1232029
R03Y-0036811
X0115166Y1088131
X0099024Y1235375
R04Y-0036811
X0115166Y1235375
R03Y-0036811
X0115166Y1151714
X0115166Y1145021
X0099024Y1141675
X0099024Y1134982
X0115166Y1138328
X0115166Y1131635
X0099024Y1118249
X0099024Y1252108
X0099024Y1245415
X0099024Y1111556
X0115166Y1248761
X0115166Y1242068
X0099024Y1228682
X0099024Y1221989
X0115166Y1225336
X0115166Y1218643
X0099024Y1215297
X0099024Y1208604
X0115166Y1211950
X0115166Y1205257
X0115166Y1114903
X0099024Y1191871
X0099024Y1185178
X0115166Y1188525
X0115166Y1181832
X0099024Y1178486
X0099024Y1171793
X0115166Y1175139
X0115166Y1168446
X0099024Y1155060
X0099024Y1148367
X0115166Y1108210
X0099024Y1058013
X0115166Y1054667
X0099024Y1081438
X0099024Y1074745
X0115166Y1078092
X0115166Y1071399
X0099024Y1104863
X0099024Y1098171
X0115166Y1101517
X0115166Y1094824
X0115166Y1047974
X0099024Y1044627
X0115166Y1041281
X0099024Y1037934
X0115166Y1034588
X0099024Y1031241
X0115166Y1027895
X0115166Y1061360
X0115166Y1001123
X0099024Y0944234
X0099024Y0907423
X0099024Y0870611
R02Y-0036811
X0115166Y0937541
R04Y-0036811
X0099024Y0940887
R04Y-0036811
X0115166Y0940887
R04Y-0036811
X0115166Y0820415
X0115166Y0813722
X0099024Y0810375
X0099024Y0803682
X0115166Y0807029
X0115166Y0800336
X0099024Y0786950
X0099024Y0920808
X0099024Y0914115
X0099024Y0780257
X0115166Y0917462
X0115166Y0910769
X0099024Y0897383
X0099024Y0890690
X0115166Y0894037
X0115166Y0887344
X0099024Y0883997
X0099024Y0877304
X0115166Y0880651
X0115166Y0873958
X0115166Y0783604
X0099024Y0860572
X0099024Y0853879
X0115166Y0857226
X0115166Y0850533
X0099024Y0847186
X0099024Y0840493
X0115166Y0843840
X0115166Y0837147
X0099024Y0823761
X0099024Y0817068
X0115166Y0776911
X0099024Y0971005
X0115166Y0967659
X0099024Y0957619
X0099024Y0950926
X0115166Y0954273
X0115166Y0947580
X0099024Y0934194
X0099024Y0927501
X0115166Y0930848
X0115166Y0924155
X0115166Y0994430
X0099024Y0991084
X0115166Y0987737
X0099024Y0984391
X0115166Y0981045
X0099024Y0977698
X0115166Y0974352
X0099024Y0964312
X0099024Y0997777
X0099024Y1001123
X0120666Y0960966
X0115166Y0960966
X1091308Y1064705
X1075166Y1051319
X1091308Y1084784
X1075166Y1238721
R04Y-0036811
X1091308Y1232028
R03Y-0036811
X1091308Y1088130
X1075166Y1235374
R04Y-0036811
X1091308Y1235374
R03Y-0036811
X1091308Y1151713
X1091308Y1145020
X1075166Y1141674
X1075166Y1134981
X1091308Y1138327
X1091308Y1131634
X1075166Y1118248
X1075166Y1252107
X1075166Y1245414
X1075166Y1111555
X1091308Y1248760
X1091308Y1242067
X1075166Y1228681
X1075166Y1221988
X1091308Y1225335
X1091308Y1218642
X1075166Y1215296
X1075166Y1208603
X1091308Y1211949
X1091308Y1205256
X1091308Y1114902
X1075166Y1191870
X1075166Y1185177
X1091308Y1188524
X1091308Y1181831
X1075166Y1178485
X1075166Y1171792
X1091308Y1175138
X1091308Y1168445
X1075166Y1155059
X1075166Y1148366
X1091308Y1108209
X1075166Y1058012
X1091308Y1054666
X1075166Y1081437
X1075166Y1074744
X1091308Y1078091
X1091308Y1071398
X1075166Y1104862
X1075166Y1098170
X1091308Y1101516
X1091308Y1094823
X1091308Y1047973
X1075166Y1044626
X1091308Y1041280
X1075166Y1037933
X1091308Y1034587
X1075166Y1031240
X1091308Y1027894
X1091308Y1061359
X1091308Y1001122
X1075166Y0944233
X1075166Y0907422
X1075166Y0870610
R02Y-0036811
X1091308Y0937540
R04Y-0036811
X1075166Y0940886
R04Y-0036811
X1091308Y0940886
R04Y-0036811
X1091308Y0820414
X1091308Y0813721
X1075166Y0810374
X1075166Y0803681
X1091308Y0807028
X1091308Y0800335
X1075166Y0786949
X1075166Y0920807
X1075166Y0914114
X1075166Y0780256
X1091308Y0917461
X1091308Y0910768
X1075166Y0897382
X1075166Y0890689
X1091308Y0894036
X1091308Y0887343
X1075166Y0883996
X1075166Y0877303
X1091308Y0880650
X1091308Y0873957
X1091308Y0783603
X1075166Y0860571
X1075166Y0853878
X1091308Y0857225
X1091308Y0850532
X1075166Y0847185
X1075166Y0840492
X1091308Y0843839
X1091308Y0837146
X1075166Y0823760
X1075166Y0817067
X1091308Y0776910
X1075166Y0971004
X1091308Y0967658
X1075166Y0957618
X1075166Y0950925
X1091308Y0954272
X1091308Y0947579
X1075166Y0934193
X1075166Y0927500
X1091308Y0930847
X1091308Y0924154
X1091308Y0994429
X1075166Y0991083
X1091308Y0987736
X1075166Y0984390
X1091308Y0981044
X1075166Y0977697
X1091308Y0974351
X1075166Y0964311
X1075166Y0997776
X1075166Y1001122
X1096808Y0960965
X1091308Y0960965
X0144866Y1064706
X0128724Y1051320
X0144866Y1084785
X0128724Y1238722
R04Y-0036811
X0144866Y1232029
R03Y-0036811
X0144866Y1088131
X0128724Y1235375
R04Y-0036811
X0144866Y1235375
R03Y-0036811
X0144866Y1151714
X0144866Y1145021
X0128724Y1141675
X0128724Y1134982
X0144866Y1138328
X0144866Y1131635
X0128724Y1118249
X0128724Y1252108
X0128724Y1245415
X0128724Y1111556
X0144866Y1248761
X0144866Y1242068
X0128724Y1228682
X0128724Y1221989
X0144866Y1225336
X0144866Y1218643
X0128724Y1215297
X0128724Y1208604
X0144866Y1211950
X0144866Y1205257
X0144866Y1114903
X0128724Y1191871
X0128724Y1185178
X0144866Y1188525
X0144866Y1181832
X0128724Y1178486
X0128724Y1171793
X0144866Y1175139
X0144866Y1168446
X0128724Y1155060
X0128724Y1148367
X0144866Y1108210
X0128724Y1058013
X0144866Y1054667
X0128724Y1081438
X0128724Y1074745
X0144866Y1078092
X0144866Y1071399
X0128724Y1104863
X0128724Y1098171
X0144866Y1101517
X0144866Y1094824
X0144866Y1047974
X0128724Y1044627
X0144866Y1041281
X0128724Y1037934
X0144866Y1034588
X0128724Y1031241
X0144866Y1027895
X0144866Y1061360
X0144866Y1001123
X0128724Y0944234
X0128724Y0907423
X0128724Y0870611
R02Y-0036811
X0144866Y0937541
R04Y-0036811
X0128724Y0940887
R04Y-0036811
X0144866Y0940887
R04Y-0036811
X0144866Y0820415
X0144866Y0813722
X0128724Y0810375
X0128724Y0803682
X0144866Y0807029
X0144866Y0800336
X0128724Y0786950
X0128724Y0920808
X0128724Y0914115
X0128724Y0780257
X0144866Y0917462
X0144866Y0910769
X0128724Y0897383
X0128724Y0890690
X0144866Y0894037
X0144866Y0887344
X0128724Y0883997
X0128724Y0877304
X0144866Y0880651
X0144866Y0873958
X0144866Y0783604
X0128724Y0860572
X0128724Y0853879
X0144866Y0857226
X0144866Y0850533
X0128724Y0847186
X0128724Y0840493
X0144866Y0843840
X0144866Y0837147
X0128724Y0823761
X0128724Y0817068
X0144866Y0776911
X0128724Y0971005
X0144866Y0967659
X0128724Y0957619
X0128724Y0950926
X0144866Y0954273
X0144866Y0947580
X0128724Y0934194
X0128724Y0927501
X0144866Y0930848
X0144866Y0924155
X0144866Y0994430
X0128724Y0991084
X0144866Y0987737
X0128724Y0984391
X0144866Y0981045
X0128724Y0977698
X0144866Y0974352
X0128724Y0964312
X0128724Y0997777
X0128724Y1001123
X0150366Y0960966
X0144866Y0960966
X1121008Y1064705
X1104866Y1051319
X1121008Y1084784
X1104866Y1238721
R04Y-0036811
X1121008Y1232028
R03Y-0036811
X1121008Y1088130
X1104866Y1235374
R04Y-0036811
X1121008Y1235374
R03Y-0036811
X1121008Y1151713
X1121008Y1145020
X1104866Y1141674
X1104866Y1134981
X1121008Y1138327
X1121008Y1131634
X1104866Y1118248
X1104866Y1252107
X1104866Y1245414
X1104866Y1111555
X1121008Y1248760
X1121008Y1242067
X1104866Y1228681
X1104866Y1221988
X1121008Y1225335
X1121008Y1218642
X1104866Y1215296
X1104866Y1208603
X1121008Y1211949
X1121008Y1205256
X1121008Y1114902
X1104866Y1191870
X1104866Y1185177
X1121008Y1188524
X1121008Y1181831
X1104866Y1178485
X1104866Y1171792
X1121008Y1175138
X1121008Y1168445
X1104866Y1155059
X1104866Y1148366
X1121008Y1108209
X1104866Y1058012
X1121008Y1054666
X1104866Y1081437
X1104866Y1074744
X1121008Y1078091
X1121008Y1071398
X1104866Y1104862
X1104866Y1098170
X1121008Y1101516
X1121008Y1094823
X1121008Y1047973
X1104866Y1044626
X1121008Y1041280
X1104866Y1037933
X1121008Y1034587
X1104866Y1031240
X1121008Y1027894
X1121008Y1061359
X1121008Y1001122
X1104866Y0944233
X1104866Y0907422
X1104866Y0870610
R02Y-0036811
X1121008Y0937540
R04Y-0036811
X1104866Y0940886
R04Y-0036811
X1121008Y0940886
R04Y-0036811
X1121008Y0820414
X1121008Y0813721
X1104866Y0810374
X1104866Y0803681
X1121008Y0807028
X1121008Y0800335
X1104866Y0786949
X1104866Y0920807
X1104866Y0914114
X1104866Y0780256
X1121008Y0917461
X1121008Y0910768
X1104866Y0897382
X1104866Y0890689
X1121008Y0894036
X1121008Y0887343
X1104866Y0883996
X1104866Y0877303
X1121008Y0880650
X1121008Y0873957
X1121008Y0783603
X1104866Y0860571
X1104866Y0853878
X1121008Y0857225
X1121008Y0850532
X1104866Y0847185
X1104866Y0840492
X1121008Y0843839
X1121008Y0837146
X1104866Y0823760
X1104866Y0817067
X1121008Y0776910
X1104866Y0971004
X1121008Y0967658
X1104866Y0957618
X1104866Y0950925
X1121008Y0954272
X1121008Y0947579
X1104866Y0934193
X1104866Y0927500
X1121008Y0930847
X1121008Y0924154
X1121008Y0994429
X1104866Y0991083
X1121008Y0987736
X1104866Y0984390
X1121008Y0981044
X1104866Y0977697
X1121008Y0974351
X1104866Y0964311
X1104866Y0997776
X1104866Y1001122
X1126508Y0960965
X1121008Y0960965
X0174567Y1064706
X0158425Y1051320
X0174567Y1084785
X0158425Y1238722
R04Y-0036811
X0174567Y1232029
R03Y-0036811
X0174567Y1088131
X0158425Y1235375
R04Y-0036811
X0174567Y1235375
R03Y-0036811
X0174567Y1151714
X0174567Y1145021
X0158425Y1141675
X0158425Y1134982
X0174567Y1138328
X0174567Y1131635
X0158425Y1118249
X0158425Y1252108
X0158425Y1245415
X0158425Y1111556
X0174567Y1248761
X0174567Y1242068
X0158425Y1228682
X0158425Y1221989
X0174567Y1225336
X0174567Y1218643
X0158425Y1215297
X0158425Y1208604
X0174567Y1211950
X0174567Y1205257
X0174567Y1114903
X0158425Y1191871
X0158425Y1185178
X0174567Y1188525
X0174567Y1181832
X0158425Y1178486
X0158425Y1171793
X0174567Y1175139
X0174567Y1168446
X0158425Y1155060
X0158425Y1148367
X0174567Y1108210
X0158425Y1058013
X0174567Y1054667
X0158425Y1081438
X0158425Y1074745
X0174567Y1078092
X0174567Y1071399
X0158425Y1104863
X0158425Y1098171
X0174567Y1101517
X0174567Y1094824
X0174567Y1047974
X0158425Y1044627
X0174567Y1041281
X0158425Y1037934
X0174567Y1034588
X0158425Y1031241
X0174567Y1027895
X0174567Y1061360
X0174567Y1001123
X0158425Y0944234
X0158425Y0907423
X0158425Y0870611
R02Y-0036811
X0174567Y0937541
R04Y-0036811
X0158425Y0940887
R04Y-0036811
X0174567Y0940887
R04Y-0036811
X0174567Y0820415
X0174567Y0813722
X0158425Y0810375
X0158425Y0803682
X0174567Y0807029
X0174567Y0800336
X0158425Y0786950
X0158425Y0920808
X0158425Y0914115
X0158425Y0780257
X0174567Y0917462
X0174567Y0910769
X0158425Y0897383
X0158425Y0890690
X0174567Y0894037
X0174567Y0887344
X0158425Y0883997
X0158425Y0877304
X0174567Y0880651
X0174567Y0873958
X0174567Y0783604
X0158425Y0860572
X0158425Y0853879
X0174567Y0857226
X0174567Y0850533
X0158425Y0847186
X0158425Y0840493
X0174567Y0843840
X0174567Y0837147
X0158425Y0823761
X0158425Y0817068
X0174567Y0776911
X0158425Y0971005
X0174567Y0967659
X0158425Y0957619
X0158425Y0950926
X0174567Y0954273
X0174567Y0947580
X0158425Y0934194
X0158425Y0927501
X0174567Y0930848
X0174567Y0924155
X0174567Y0994430
X0158425Y0991084
X0174567Y0987737
X0158425Y0984391
X0174567Y0981045
X0158425Y0977698
X0174567Y0974352
X0158425Y0964312
X0158425Y0997777
X0158425Y1001123
X0180067Y0960966
X0174567Y0960966
X1150709Y1064705
X1134567Y1051319
X1150709Y1084784
X1134567Y1238721
R04Y-0036811
X1150709Y1232028
R03Y-0036811
X1150709Y1088130
X1134567Y1235374
R04Y-0036811
X1150709Y1235374
R03Y-0036811
X1150709Y1151713
X1150709Y1145020
X1134567Y1141674
X1134567Y1134981
X1150709Y1138327
X1150709Y1131634
X1134567Y1118248
X1134567Y1252107
X1134567Y1245414
X1134567Y1111555
X1150709Y1248760
X1150709Y1242067
X1134567Y1228681
X1134567Y1221988
X1150709Y1225335
X1150709Y1218642
X1134567Y1215296
X1134567Y1208603
X1150709Y1211949
X1150709Y1205256
X1150709Y1114902
X1134567Y1191870
X1134567Y1185177
X1150709Y1188524
X1150709Y1181831
X1134567Y1178485
X1134567Y1171792
X1150709Y1175138
X1150709Y1168445
X1134567Y1155059
X1134567Y1148366
X1150709Y1108209
X1134567Y1058012
X1150709Y1054666
X1134567Y1081437
X1134567Y1074744
X1150709Y1078091
X1150709Y1071398
X1134567Y1104862
X1134567Y1098170
X1150709Y1101516
X1150709Y1094823
X1150709Y1047973
X1134567Y1044626
X1150709Y1041280
X1134567Y1037933
X1150709Y1034587
X1134567Y1031240
X1150709Y1027894
X1150709Y1061359
X1150709Y1001122
X1134567Y0944233
X1134567Y0907422
X1134567Y0870610
R02Y-0036811
X1150709Y0937540
R04Y-0036811
X1134567Y0940886
R04Y-0036811
X1150709Y0940886
R04Y-0036811
X1150709Y0820414
X1150709Y0813721
X1134567Y0810374
X1134567Y0803681
X1150709Y0807028
X1150709Y0800335
X1134567Y0786949
X1134567Y0920807
X1134567Y0914114
X1134567Y0780256
X1150709Y0917461
X1150709Y0910768
X1134567Y0897382
X1134567Y0890689
X1150709Y0894036
X1150709Y0887343
X1134567Y0883996
X1134567Y0877303
X1150709Y0880650
X1150709Y0873957
X1150709Y0783603
X1134567Y0860571
X1134567Y0853878
X1150709Y0857225
X1150709Y0850532
X1134567Y0847185
X1134567Y0840492
X1150709Y0843839
X1150709Y0837146
X1134567Y0823760
X1134567Y0817067
X1150709Y0776910
X1134567Y0971004
X1150709Y0967658
X1134567Y0957618
X1134567Y0950925
X1150709Y0954272
X1150709Y0947579
X1134567Y0934193
X1134567Y0927500
X1150709Y0930847
X1150709Y0924154
X1150709Y0994429
X1134567Y0991083
X1150709Y0987736
X1134567Y0984390
X1150709Y0981044
X1134567Y0977697
X1150709Y0974351
X1134567Y0964311
X1134567Y0997776
X1134567Y1001122
X1156209Y0960965
X1150709Y0960965
X0204268Y1064706
X0188126Y1051320
X0204268Y1084785
X0188126Y1238722
R04Y-0036811
X0204268Y1232029
R03Y-0036811
X0204268Y1088131
X0188126Y1235375
R04Y-0036811
X0204268Y1235375
R03Y-0036811
X0204268Y1151714
X0204268Y1145021
X0188126Y1141675
X0188126Y1134982
X0204268Y1138328
X0204268Y1131635
X0188126Y1118249
X0188126Y1252108
X0188126Y1245415
X0188126Y1111556
X0204268Y1248761
X0204268Y1242068
X0188126Y1228682
X0188126Y1221989
X0204268Y1225336
X0204268Y1218643
X0188126Y1215297
X0188126Y1208604
X0204268Y1211950
X0204268Y1205257
X0204268Y1114903
X0188126Y1191871
X0188126Y1185178
X0204268Y1188525
X0204268Y1181832
X0188126Y1178486
X0188126Y1171793
X0204268Y1175139
X0204268Y1168446
X0188126Y1155060
X0188126Y1148367
X0204268Y1108210
X0188126Y1058013
X0204268Y1054667
X0188126Y1081438
X0188126Y1074745
X0204268Y1078092
X0204268Y1071399
X0188126Y1104863
X0188126Y1098171
X0204268Y1101517
X0204268Y1094824
X0204268Y1047974
X0188126Y1044627
X0204268Y1041281
X0188126Y1037934
X0204268Y1034588
X0188126Y1031241
X0204268Y1027895
X0204268Y1061360
X0204268Y1001123
X0188126Y0944234
X0188126Y0907423
X0188126Y0870611
R02Y-0036811
X0204268Y0937541
R04Y-0036811
X0188126Y0940887
R04Y-0036811
X0204268Y0940887
R04Y-0036811
X0204268Y0820415
X0204268Y0813722
X0188126Y0810375
X0188126Y0803682
X0204268Y0807029
X0204268Y0800336
X0188126Y0786950
X0188126Y0920808
X0188126Y0914115
X0188126Y0780257
X0204268Y0917462
X0204268Y0910769
X0188126Y0897383
X0188126Y0890690
X0204268Y0894037
X0204268Y0887344
X0188126Y0883997
X0188126Y0877304
X0204268Y0880651
X0204268Y0873958
X0204268Y0783604
X0188126Y0860572
X0188126Y0853879
X0204268Y0857226
X0204268Y0850533
X0188126Y0847186
X0188126Y0840493
X0204268Y0843840
X0204268Y0837147
X0188126Y0823761
X0188126Y0817068
X0204268Y0776911
X0188126Y0971005
X0204268Y0967659
X0188126Y0957619
X0188126Y0950926
X0204268Y0954273
X0204268Y0947580
X0188126Y0934194
X0188126Y0927501
X0204268Y0930848
X0204268Y0924155
X0204268Y0994430
X0188126Y0991084
X0204268Y0987737
X0188126Y0984391
X0204268Y0981045
X0188126Y0977698
X0204268Y0974352
X0188126Y0964312
X0188126Y0997777
X0188126Y1001123
X0209768Y0960966
X0204268Y0960966
X1180410Y1064705
X1164268Y1051319
X1180410Y1084784
X1164268Y1238721
R04Y-0036811
X1180410Y1232028
R03Y-0036811
X1180410Y1088130
X1164268Y1235374
R04Y-0036811
X1180410Y1235374
R03Y-0036811
X1180410Y1151713
X1180410Y1145020
X1164268Y1141674
X1164268Y1134981
X1180410Y1138327
X1180410Y1131634
X1164268Y1118248
X1164268Y1252107
X1164268Y1245414
X1164268Y1111555
X1180410Y1248760
X1180410Y1242067
X1164268Y1228681
X1164268Y1221988
X1180410Y1225335
X1180410Y1218642
X1164268Y1215296
X1164268Y1208603
X1180410Y1211949
X1180410Y1205256
X1180410Y1114902
X1164268Y1191870
X1164268Y1185177
X1180410Y1188524
X1180410Y1181831
X1164268Y1178485
X1164268Y1171792
X1180410Y1175138
X1180410Y1168445
X1164268Y1155059
X1164268Y1148366
X1180410Y1108209
X1164268Y1058012
X1180410Y1054666
X1164268Y1081437
X1164268Y1074744
X1180410Y1078091
X1180410Y1071398
X1164268Y1104862
X1164268Y1098170
X1180410Y1101516
X1180410Y1094823
X1180410Y1047973
X1164268Y1044626
X1180410Y1041280
X1164268Y1037933
X1180410Y1034587
X1164268Y1031240
X1180410Y1027894
X1180410Y1061359
X1180410Y1001122
X1164268Y0944233
X1164268Y0907422
X1164268Y0870610
R02Y-0036811
X1180410Y0937540
R04Y-0036811
X1164268Y0940886
R04Y-0036811
X1180410Y0940886
R04Y-0036811
X1180410Y0820414
X1180410Y0813721
X1164268Y0810374
X1164268Y0803681
X1180410Y0807028
X1180410Y0800335
X1164268Y0786949
X1164268Y0920807
X1164268Y0914114
X1164268Y0780256
X1180410Y0917461
X1180410Y0910768
X1164268Y0897382
X1164268Y0890689
X1180410Y0894036
X1180410Y0887343
X1164268Y0883996
X1164268Y0877303
X1180410Y0880650
X1180410Y0873957
X1180410Y0783603
X1164268Y0860571
X1164268Y0853878
X1180410Y0857225
X1180410Y0850532
X1164268Y0847185
X1164268Y0840492
X1180410Y0843839
X1180410Y0837146
X1164268Y0823760
X1164268Y0817067
X1180410Y0776910
X1164268Y0971004
X1180410Y0967658
X1164268Y0957618
X1164268Y0950925
X1180410Y0954272
X1180410Y0947579
X1164268Y0934193
X1164268Y0927500
X1180410Y0930847
X1180410Y0924154
X1180410Y0994429
X1164268Y0991083
X1180410Y0987736
X1164268Y0984390
X1180410Y0981044
X1164268Y0977697
X1180410Y0974351
X1164268Y0964311
X1164268Y0997776
X1164268Y1001122
X1185910Y0960965
X1180410Y0960965
X0227540Y0960966
X0233969Y0960966
X1203682Y0960965
X1210111Y0960965
X1553154Y0479063
X1222094Y0297066
X0877640Y0315789
X1234000Y0385500
X0888372Y0547518
X1029431Y0587342
X0844741Y0543864
X0900808Y1437798
X0758163Y1502600
X0709382Y1601210
X0562208Y0404717
X0735500Y0390862
X0603326Y0429530
X0603526Y0229995
X0640923Y0169388
X0678226Y0215771
X0587710Y0399287
X0731500Y0360862
X0617985Y0401728
X0504796Y0086320
X0524680Y0417602
X0508238Y0199506
X0494144Y0221370
X0568804Y0221926
X0496831Y0205030
X0491635Y0225970
X0504351Y0202776
X1072738Y0421922
X0662000Y0449862
X0420115Y0235442
X0618732Y0039913
X0612608Y0035961
X0505315Y0196944
X0500209Y0238119
X0534277Y0235560
X0519601Y0196117
X0456231Y0232883
X0613025Y0042725
X0565093Y0242640
X0702095Y0446705
X0411940Y0240501
X0708395Y0443555
X0588968Y0240112
X0491577Y0243240
X0661546Y0444497
X0708395Y0440405
X0549248Y0230441
X0559774Y0243176
X0705245Y0446705
X0471371Y0227764
X0420115Y0240501
X0500119Y0243173
X0534277Y0230441
X0456231Y0227764
X0467545Y0356864
X1072738Y0416763
X0582766Y0221421
X0491859Y0233000
X0582766Y0225496
X0549248Y0237652
X1072738Y0411322
X0487827Y0354017
X0420115Y0230323
X0500209Y0233000
X0538613Y0238119
X0460567Y0235442
X1078823Y0269400
X0564794Y0058911
X1090061Y0428019
X0651384Y0445252
X0598968Y0238878
X0992460Y0370659
X0996889Y0374156
X1000460Y0369535
X0951102Y0628662
X0511684Y0221219
X0499380Y0222510
X0937310Y0580755
X0910731Y0590251
X0602833Y0791746
X1074249Y0387795
X0657428Y0674761
X1078400Y0383226
X0650228Y0674761
X0595619Y0806084
X0691417Y0680382
X0924987Y0622523
X0697571Y0730453
X0660175Y0679517
X0952497Y0614080
X0618645Y0783582
X0603743Y0794963
X1074654Y0380188
X0662628Y0674761
X0590710Y0804192
X1078400Y0391226
X0646446Y0674643
X0920989Y0617692
X1486761Y0826279
X0993460Y0358405
X1495670Y0826073
X0998460Y0358405
X0935746Y0611573
X0910535Y0619251
X0900323Y0604377
X0939511Y0597073
X1484177Y0812988
X1498177Y0829359
X0948156Y0593912
X1490973Y0825557
X1003460Y0358405
X1480677Y0813488
X1489177Y0812988
X0988460Y0358405
X0902376Y0590172
X0613565Y0350819
X1029601Y0394387
X1034409Y0429618
X0611118Y0359462
X0581099Y0263680
X1071698Y0270702
X1593349Y0248160
X1682433Y0220857
X0863745Y1444560
X0565537Y1235456
X0832347Y1251703
X0822794Y0797511
X0631505Y0284355
X0643053Y0502891
X0734442Y0675695
X1545627Y1254068
X0639313Y0452361
X0627364Y0478823
X0900885Y1435041
X1019261Y0571324
X0698946Y0484420
X0720106Y1609542
X0758163Y1522286
X0723590Y1595323
X0302606Y0026365
X0410678Y0159140
X1797692Y0146285
X1775920Y0027068
X0666000Y0433862
X0822625Y0763529
X0651406Y0501178
X0746665Y0678879
X0758163Y1494726
X0757610Y1584023
X0652027Y0415930
X0539721Y0042862
X0807451Y0767299
X1792692Y0766870
X0786850Y0766871
X1762992Y0766870
X0757149Y0766871
X1733727Y0766870
X0727448Y0766871
X1703590Y0766870
X0697747Y0766871
X1673889Y0766870
X0668046Y0766871
X1644188Y0766870
X0658947Y0771100
X0718349Y0771100
X0688648Y0771100
X0748049Y0771100
X0777750Y0771100
X0816550Y0770218
X0777750Y0767300
X0748049Y0767300
X0718349Y0767300
R02X-0029701
X0816550Y0766871
X0822555Y0807409
X0730770Y0644218
X0711295Y0665117
X0636551Y0767900
X0631741Y0770318
X1635088Y0771005
X1664789Y0771065
X1694490Y0771065
X1724191Y0771099
X1753891Y0771105
X1783592Y0771365
X1718686Y0676154
X1783592Y0767565
X1753891Y0767305
X1724191Y0767299
X1694490Y0767265
X1664789Y0767265
X1635088Y0767205
X1736848Y0650974
X1699500Y0673738
X1512523Y0809679
X1699500Y0654738
X1500422Y0814180
X0090015Y0766871
X1066157Y0766870
X0119616Y0767166
X1095858Y0766870
X0149416Y0766871
X1125558Y0766870
X0179117Y0766871
X1155282Y0766806
X0208818Y0766871
X1184960Y0766870
X0240200Y0766300
X1214661Y0766870
X0134902Y0686074
X0169987Y0771266
X0140317Y0771200
X0110485Y0771366
X0080784Y0771366
X0197651Y0769241
X0229275Y0769292
X0199718Y0767400
X0169987Y0767666
X0110616Y0767400
X0080915Y0767400
X0134902Y0668506
X0140317Y0767400
X0229263Y0765863
X0172725Y0679230
X0131752Y0686074
X0172725Y0667898
X0131752Y0668506
X1038867Y0774960
X1057057Y0771099
R03X0029701
X1175860Y0771099
X1205448Y0769914
X1205630Y0766600
X1146160Y0767299
X1116459Y0767299
X1036427Y0770532
X1057057Y0767299
X1086758Y0767299
X1175860Y0767299
X1205679Y0594148
X1178000Y0592673
X1206191Y0588400
X1178000Y0572602
X0724000Y0633906
X0721163Y0058588
X0724645Y0058362
X0713343Y0633842
X0728285Y0058135
X0441320Y0295170
X0161735Y0684456
X0730785Y0058068
X0441320Y0301170
X0162482Y0679319
X0865912Y0089252
X0738590Y0059868
X1216300Y0475682
X1737002Y0671494
X0863343Y0090021
X0740817Y0058503
X1212700Y0475712
X1742306Y0661032
X0746588Y0059754
X1195336Y0586606
X1150577Y0478840
X0910093Y0246015
X1155890Y0478812
X0749478Y0059902
X1195236Y0581407
X0910267Y0242658
X0682291Y0046822
X0843308Y0335550
X0951895Y0808163
X1134207Y1669230
X0684611Y0041857
X1422266Y1628947
X1141356Y1676542
X1422154Y1626270
X1136575Y1676239
X0640271Y0763488
X0705158Y0645357
X0631557Y0773359
X1508177Y0803488
X1733043Y0657091
X1496532Y0803513
X1720050Y0649142
X1510261Y0814611
X1500500Y0809063
X0159513Y0674855
X0163372Y0670863
X1199370Y0578154
X1199392Y0590500
X1208733Y0585986
X1191087Y0573809
X0705245Y0468672
X0726789Y0060562
X0774420Y1587284
X0900150Y1587284
X0858150Y1587284
X0816150Y1587284
X0710360Y1589296
X0726550Y1599358
X0721440Y1570963
X0709836Y1594721
X0894050Y1584033
R02X-0042000
X0766950Y1581233
X0723963Y1578932
X0719963Y1578932
X0721963Y1576932
X0710080Y1581683
X0710550Y1576523
X0699500Y1559000
X0886700Y1587183
R02X-0042000
X0754635Y1592571
X0699500Y1588500
X0699500Y1599500
X0771550Y1587133
X0813049Y1590633
R02X0042000
X0710420Y1585173
X0844150Y1606633
X0802150Y1606633
X0760521Y1595500
X0886150Y1606633
X0724110Y1561825
X0747110Y1579863
X0925650Y1581379
X0883150Y1581379
X0841150Y1581379
X0799150Y1581379
X0757650Y1580023
X0766212Y1568043
X0714900Y1571273
X0813150Y1570633
R02X0042000
X0749167Y1591967
X0708994Y1568507
X0771450Y1577333
X0813150Y1579410
X0897150Y1579410
X0855150Y1579410
X0894150Y1598633
X0936150Y1586233
X0852150Y1598633
X0810150Y1598633
X0747160Y1587773
X0922650Y1583347
R03X-0042000
X0747150Y1583247
X0726475Y1571293
X0758163Y1498663
X1111701Y1558640
X1072134Y1647920
X0727325Y1563400
X0936150Y1578233
X0894150Y1574633
R02X-0042000
X0747110Y1575863
X0757610Y1576023
X0697503Y1661331
X0796955Y1487468
X0822579Y0760169
X0639002Y0449862
X0647576Y0497964
X0742579Y0676093
X0699424Y1616627
X0708600Y1572523
X0708500Y1560500
X0223687Y0522453
X0357925Y0304082
X0391310Y0227871
X0234000Y0148000
X0323036Y0073125
X0253874Y0111774
X0341082Y0056308
X0619240Y0123232
X0248350Y0165700
X0855722Y0416606
X1233468Y0419742
X1822724Y0424948
X0871190Y0382230
X1657545Y0434506
X1627986Y0282728
X1781368Y0162824
X1728965Y0112941
X1788204Y0074958
X0829800Y0331013
X0823778Y0376378
X1627909Y0286742
X1654110Y0434177
X0670000Y0442362
X1787390Y0165834
X0783377Y0451344
X0958158Y0449020
X0990579Y0155248
X1000611Y0215039
X0586390Y0069291
X0654037Y0093241
X0705245Y0459223
X1227803Y0094210
X0576478Y0058563
X0431664Y1624342
X0394521Y1575891
X0404640Y1637425
X0135543Y1637055
X0814489Y0558082
X0812895Y0449802
X1086714Y0353515
X1598303Y0234250
X1054613Y0261586
X1055934Y0381988
X1049451Y0266747
X0479870Y0270400
X0487620Y0270400
X1046384Y0269814
X1068143Y0380188
X1056941Y0259176
X0744916Y0530268
X1060719Y0516059
X0748143Y0530269
X1060719Y0512359
X1055934Y0388988
X1062704Y0270875
X0780877Y0483344
X0838561Y0484071
X1721172Y1712115
X1744620Y1716018
X0155071Y1543604
X0200424Y1686870
X1719181Y1706712
X0913512Y0486743
X0651072Y0465939
X0661718Y0579932
X0661718Y0498056
X0923747Y0584945
X0757161Y1696424
X0730647Y1623629
X0668133Y1625828
X0200448Y1690771
X0381711Y1593842
X0759723Y1626161
X0185084Y1691988
X0403004Y1582457
X0650966Y1618934
X0403163Y1579357
X0725638Y1682890
X0661156Y1626532
X0365493Y1655107
X0403844Y1665769
X0730347Y1682902
X0412000Y1647177
X0666610Y1571580
X0775388Y0390862
X0870826Y0423423
X0837391Y0659820
X0865466Y0788081
X0671068Y1650818
X0417000Y1675000
X0473500Y1662500
X0865466Y0798081
X0817900Y0649012
X0828751Y0463578
X0468075Y1662500
X0700528Y1661468
X0200478Y1701758
X0780759Y0479344
X0785919Y0559660
X0197780Y1696973
X0185124Y1701851
X0828979Y0449802
X0824366Y0552444
X0178385Y1715441
X0393005Y1592304
X0193274Y1709769
X0189760Y1713061
X0149338Y1705603
X0146982Y0521997
X0206788Y1660960
X0137386Y1626412
X0813000Y0484862
X0284018Y0522300
X0198698Y1662215
X1219738Y1708861
X1219738Y1713861
X1153724Y1462695
X1595716Y1431861
X0797326Y0483344
X0678350Y1567400
X0865466Y0785581
X0805150Y0623843
X0796333Y0435344
X0405000Y1675000
X0670803Y1654606
X0423500Y1652500
X0672810Y1571560
X0813208Y0435344
X0820617Y0641273
X0865466Y0790581
X0468575Y1731000
X0685747Y1669303
X0446182Y1625555
X0139802Y1556133
X0155618Y1549331
X0828751Y0467568
X0820620Y0550846
X0479500Y1666500
X0684080Y1576500
X0865466Y0795581
X0787591Y0631785
X0764500Y0529862
X0474000Y1704000
X0685635Y1675310
X1400029Y1615796
X1453553Y1686892
X0483500Y1658500
X0681780Y1574280
X0804863Y0626789
X0787279Y0499238
X0865466Y0793081
X0468575Y1704000
X0685719Y1672391
X0732852Y1695701
X0746766Y1696036
X0822883Y0780334
X0768565Y0677573
X0812983Y0463578
X0659557Y1714672
X0662120Y1720404
X1602782Y1435920
X0797322Y0463344
X1219738Y1727861
X1159283Y1471132
X1219738Y1722861
X0960054Y0516982
X0958255Y0465811
X0797252Y0451344
X1719148Y1721530
X1212954Y1703343
X1719218Y1727265
X1680877Y1723593
X0780877Y0455344
X0860280Y0488636
X1192612Y1703334
X1597992Y1433183
X0812983Y0480159
X1150718Y1462792
X1197612Y1703334
X0635472Y1711808
X1645029Y1710609
X0860508Y0497772
X0780877Y0463344
X0822794Y0777511
X0812983Y0476159
X0771553Y0677963
X0639391Y1700695
X0635491Y1696845
X1645029Y1715609
X0799742Y0628983
X0825390Y0770020
X0756936Y0676319
X0780877Y0475344
X0686949Y1625144
X0653542Y1649059
X0548610Y0057990
X1033748Y1659315
X1033798Y1656675
X0849750Y0401280
X0872020Y0413300
X0246250Y0204360
X0254095Y0209235
X0168910Y0415930
X0168950Y0412950
X0173960Y0400560
X0149830Y0441920
X0149210Y0438640
X0146930Y0441870
X0145960Y0438800
X0143720Y0441960
X0140800Y0441920
X0138090Y0441900
X0142660Y0438930
X0139440Y0439000
X0144610Y0429560
X0166220Y0438460
X0169440Y0438390
X0172740Y0438260
X0164870Y0441360
X0167580Y0441380
X0170500Y0441420
X0173710Y0441330
X0175990Y0438100
X0176610Y0441380
X0195730Y0412410
X0195690Y0415390
X0189410Y0388180
X0172120Y0416600
X1572230Y1533000
X1444200Y1533240
X1308290Y1533380
X1180047Y1533247
X0562860Y1499360
X0436140Y1499320
X0299950Y1499500
X0177322Y1498320
X1195050Y1620040
X0721916Y1431589
X0721916Y1428989
X1720210Y1435330
X1722810Y1435330
X0864700Y0836100
X0753500Y0675800
X0556197Y1536687
X0541259Y1536882
X0528940Y1548260
X0278021Y1493392
X0280621Y1491482
X0283221Y1493392
X0278021Y1498172
X0283221Y1498172
X0544814Y1459995
X0666050Y1501670
X0401583Y1504872
X1409456Y1537872
X1774940Y1669037
X1061974Y1731920
X1572036Y1306083
X0056542Y0589521
X0707608Y0069718
X0561248Y0100399
X0561248Y0106985
X0550505Y0114382
X0557091Y0114382
X0972109Y1135149
X0969709Y1137023
X0967315Y1135550
X0964915Y1137424
X0963012Y1139511
X0979091Y1257742
X0979091Y1245920
X0979091Y1248920
X0979091Y1254742
X0979091Y1251742
X0969691Y1257742
X0964058Y1252177
X0963991Y1245920
X0963991Y1248920
X0969691Y1251742
X0969691Y1254742
X0955091Y1257742
X0955891Y1248920
X0955891Y1245920
X0955091Y1251742
X0955091Y1254742
X0945691Y1257742
X0936464Y1248844
X0940921Y1251857
X0940791Y1245920
X0940791Y1248920
X0945691Y1251742
X0945691Y1254742
X1737126Y1401238
X1737126Y1403838
X0110996Y1592018
X0113496Y1592018
X0110144Y1597831
X0128617Y1561022
X0128268Y1568744
X0125768Y1568744
X0127392Y1575524
X0127374Y1572749
X0129874Y1572749
X0129892Y1575524
X0905074Y1252177
X0722141Y1408412
X0139869Y0686582
X0131861Y0664958
X0173299Y0664958
X0172802Y0682036
X0649936Y0574185
X0642816Y0574185
X1515192Y0814294
X1368922Y1359024
X0848660Y0651127
X0858567Y1521416
X0858581Y1518568
X0855853Y1518684
X0853213Y1518634
X0850146Y1518637
X0850146Y1521261
X0853213Y1521258
X0855853Y1521308
X0841270Y1521588
X0838630Y1521538
X0841310Y1518608
X0838670Y1518558
X0847007Y1518834
X0844367Y1518784
X0844367Y1521408
X0847007Y1521458
X0950902Y1456876
X0948262Y1456826
X0945195Y1456829
X0942056Y1457026
X0939416Y1456976
X0953616Y1459608
X0948262Y1459450
X0950902Y1459500
X0939416Y1459600
X0942056Y1459650
X0877480Y1248844
X0923125Y1137046
X0925525Y1135172
X0921477Y1134647
X0919077Y1136521
X0055789Y1509224
X0049330Y1509137
X0052330Y1509137
X0049405Y1511986
X0052405Y1511986
X0088905Y1508698
R02X-0003500
X0058564Y1570209
X0061225Y1570283
X0063915Y1556254
X0063915Y1558805
X1740400Y1543682
X1772613Y1541172
X1769113Y1541172
X1776113Y1541172
X1816254Y1613775
R02X-0003500
X1812078Y1600225
X1812003Y1603875
X1812003Y1607375
X1812078Y1596725
X0834430Y0434634
X0802752Y0455344
X0876044Y1444317
X1300560Y1554261
X0706172Y1552082
X0488908Y0242754
X0664170Y0445711
X0562475Y0242721
X0501718Y0240558
X1081857Y0269856
X0841203Y1361376
X0839188Y1348937
X0834071Y1342457
X0834017Y1333584
X0653013Y0443200
X0595563Y0239128
X0933041Y1315920
X0927869Y1317417
X0933586Y1325501
X0923680Y1339520
X0919758Y1348990
X0920738Y1321363
X0992233Y0373679
X0997488Y0370287
X0941000Y1128957
X0941000Y1131557
X0941000Y1121957
X0941000Y1124557
X0941000Y1114957
X0941000Y1117557
X0941000Y1107957
X0941000Y1110557
X0968919Y1111777
X0968919Y1109177
X0968919Y1118777
X0968919Y1116177
X0968919Y1125777
X0968919Y1123177
X0968800Y1132646
X0968800Y1130046
X0898000Y1119144
X0898000Y1116544
X0898000Y1125952
X0898000Y1123352
X0898000Y1132760
X0898000Y1130160
X0925200Y1128843
X0925200Y1131443
X0925200Y1121843
X0925200Y1124443
X0925200Y1114843
X0925200Y1117443
X0925200Y1107843
X0925200Y1110443
X0697642Y0733401
X1010650Y1310500
X1083819Y0353094
X1013000Y1306500
X1013500Y1312500
X1013500Y1325500
X1011500Y1335000
X1013500Y1344500
X1051495Y0265133
X1044012Y0268659
X1054355Y0258698
X1061837Y0519703
X1056517Y0512787
X1065552Y0271441
X1161311Y1548204
X1442993Y0176204
X0737009Y0083169
X0731555Y0083685
X1679420Y1683597
X1823112Y1538659
X0647500Y1682850
X1436940Y1554277
X1564839Y1554561
X1547767Y1564073
R02X-0002500
X1411655Y1564073
R02X-0002500
X0275720Y1531073
R02X-0002500
X0034704Y1515235
X1734575Y1562068
X0047760Y1529506
X1801789Y1536742
X1737541Y1543707
X1283593Y1564073
R02X-0002500
X1796257Y1558755
X1796257Y1561255
X1765709Y1556050
X0372313Y1641759
X1165589Y0569118
X1252561Y0072675
X1246490Y0483302
X0736524Y0058069
X0403782Y1531073
R02X-0002500
X1587028Y1307137
X1441390Y0163944
X1350809Y1202323
X1063614Y0733409
X1364239Y1207949
X1459177Y0163796
X1081632Y0648854
X1040890Y0735717
X0822699Y0056712
X1214856Y0421018
X1702985Y1700328
X1460457Y1685160
X0973616Y0317648
X1427973Y0060409
X1451353Y0116158
X1202711Y0087651
X1235546Y0075293
X1445985Y0116953
X0810360Y0442079
X1403207Y0118938
X0820405Y0311830
X1254905Y1417026
X1252315Y1417085
X1303943Y1430729
X1302365Y1418702
X1292522Y1421596
X1318580Y1425240
R11X0004000
X1430465Y1361060
X1428559Y1365296
X1426441Y1369427
X1424163Y1373240
X1420774Y1377106
X1417491Y1381183
X1414950Y1384942
X1411508Y1388384
X1408543Y1391826
X1405207Y1395480
X1401764Y1399928
X1398375Y1403688
X1395463Y1406918
X1392021Y1410360
X1387308Y1413643
X1383284Y1415973
X1379101Y1418621
X1375341Y1421268
X1372164Y1423810
X1368299Y1425240
X1310580Y1425240
X1314580Y1425240
X0375056Y1393741
X0379610Y1391781
X0384270Y1389875
X0388718Y1387386
X0393321Y1385630
X0397187Y1383354
X0401953Y1380494
X0405978Y1377794
X0410002Y1375093
X0414132Y1372234
X0217097Y1413863
X0220803Y1412115
X0224881Y1410685
X0228693Y1408885
X0233194Y1407349
X1431106Y1325219
X1430312Y1322412
X1429517Y1319447
X1428458Y1316481
X1427314Y1313482
X1426202Y1310752
X1425437Y1308184
X1424561Y1305566
X0345760Y1401449
R03X0004000
X0337760Y1401449
X0341760Y1401449
X0310399Y1400549
X0314199Y1400549
X0318199Y1400549
X0321999Y1400549
X0454909Y1326721
X0454603Y1324033
X0453823Y1321436
X0452936Y1318775
X0452089Y1316074
X0451083Y1313347
X0450220Y1310834
X0449440Y1308386
X0448688Y1305947
X1512831Y1659588
X0535193Y1531073
R02X0002500
X0580489Y1550797
X0594662Y1550697
X0589938Y1550897
X0585213Y1550797
X0608836Y1550697
X0604111Y1550897
X0599387Y1550897
X0627734Y1550897
X0623009Y1550897
X0618285Y1550897
X0613560Y1550797
X0641906Y1550897
X0637182Y1550697
X0632458Y1550897
X0651355Y1550797
X0646631Y1550897
X1324189Y1583797
X1338362Y1583697
X1333638Y1583897
X1328913Y1583797
X1352536Y1583697
X1347811Y1583897
X1343087Y1583897
X1371434Y1583897
X1366709Y1583897
X1361985Y1583897
X1357260Y1583797
X1385606Y1583897
X1380882Y1583697
X1376158Y1583897
X1395055Y1583797
X1390331Y1583897
X1460301Y1583797
X1474474Y1583697
X1469750Y1583897
X1465025Y1583797
X1488648Y1583697
X1483923Y1583897
X1479199Y1583897
X1507546Y1583897
X1502821Y1583897
X1498097Y1583897
X1493372Y1583797
X1521718Y1583897
X1516994Y1583697
X1512270Y1583897
X1531167Y1583797
X1526443Y1583897
X1588363Y1583797
X1602536Y1583697
X1597812Y1583897
X1593087Y1583797
X1616710Y1583697
X1611985Y1583897
X1607261Y1583897
X1635608Y1583897
X1630883Y1583897
X1626159Y1583897
X1621434Y1583797
X1649780Y1583897
X1645056Y1583697
X1640332Y1583897
X1659229Y1583797
X1654505Y1583897
X0504396Y1550897
X0509120Y1550697
X0513844Y1550897
X0518569Y1550897
X0523293Y1550797
X0466600Y1550697
X0471325Y1550897
X0476049Y1550897
X0480774Y1550697
X0457151Y1550797
X0452427Y1550797
X0461876Y1550897
X1621187Y0588591
X1624067Y0588474
X1628756Y0588591
X1631558Y0588513
X1609355Y0592794
X0313961Y0604588
X0313961Y0607088
X0234727Y0571211
X0780000Y1357500
X1266993Y1583797
X1262269Y1583897
X1257544Y1583897
X1252820Y1583697
X1248096Y1583897
X1243372Y1583897
X1238647Y1583897
X1233923Y1583897
X1229198Y1583797
X1224474Y1583697
X1219749Y1583897
X1215025Y1583897
X1210300Y1583697
X1205576Y1583897
X1200851Y1583797
X1196127Y1583797
X0499672Y1550897
X0494947Y1550897
X0490223Y1550897
X0485498Y1550797
X1673132Y1690741
X1691357Y1688418
X1686857Y1683918
X1673245Y1673475
X0195153Y1679774
X0185254Y1686870
X0162840Y1674272
X0162848Y1679357
X0159910Y1676811
X1688243Y1663802
X1670534Y1670149
X1676971Y1668582
X1661101Y1671631
X1459435Y1659788
X0190271Y1671753
X0196366Y1664821
X0163003Y1666462
X0160011Y1663933
X0162995Y1661377
X1459435Y1654796
X0195504Y1645359
X0190242Y1656635
X0196081Y1639349
X0161239Y1631191
X0161239Y1636147
X0187388Y1626788
X0620401Y1589884
X0632461Y1589884
X0608341Y1589884
R02X-0012060
X0560101Y1589884
X0572161Y1589884
X0548041Y1589884
R03X-0012060
X0487741Y1589884
X0499801Y1589884
X0475681Y1589884
X0373244Y1589884
X0361184Y1589884
R14X-0012060
X0249671Y1550897
X0254396Y1550897
X0259120Y1550797
X0244947Y1550697
X0240223Y1550897
X0235499Y1550897
X0230774Y1550897
X0207152Y1550897
X0211876Y1550897
X0202427Y1550697
X0188254Y1550797
X0192978Y1550797
X0197703Y1550897
X1173586Y1534300
X1228214Y1507895
X0746082Y1506931
X0165713Y1501300
X0050880Y1421963
X0058349Y1412731
X0050880Y1412563
X1424971Y1564264
X1424971Y1566764
X1125732Y1666072
X1129230Y1666174
X1091026Y1653031
X1090143Y1643625
X1684172Y1538135
X1719893Y1609640
R03Y-0003300
X1719893Y1594940
X1719893Y1612940
X0713357Y1535212
X1423735Y1536715
X1673674Y1563575
X1549618Y1569763
X1552118Y1569763
X1285445Y1569763
X1287945Y1569763
X0716989Y1537249
X0713459Y1540917
X0715224Y1539083
X0715122Y1533378
X0716770Y1531459
X0543759Y1536882
X0280072Y1536763
X0277572Y1536763
X0417098Y1531264
X0417098Y1533764
X0415862Y1503715
X0363110Y1398312
R04X-0004000
X1727336Y0054524
X1729836Y0054524
X0981445Y0185389
X0251793Y0100846
X1726814Y0102968
X1726596Y0064284
X1729836Y0057024
X1726596Y0061784
X1727336Y0057024
X1572283Y0301816
X1569592Y0294816
X1564517Y0299432
X1558480Y0302678
X1553913Y0298119
X1536542Y0304819
X1536542Y0300819
X1296228Y0408125
X1293277Y0401125
X1288202Y0405741
X1282165Y0408987
X1277598Y0404428
X1260227Y0411128
X1260227Y0407128
X0975689Y0153950
X0975689Y0156950
X0960421Y0157699
X0957421Y0157699
X0963985Y0177154
X0964743Y0179917
X0962243Y0179917
X0296272Y0069128
X0099754Y0155807
X0107931Y0158767
X0104829Y0151191
X0093717Y0159053
X0089150Y0154494
X0071779Y0161194
X0071779Y0157194
X0247716Y0071865
X0247716Y0075865
X0244296Y0059765
X0199040Y1666925
X1313109Y1200898
X1313109Y1195398
X1340483Y1209006
X1339488Y1202295
X1348611Y1218463
X1348611Y1212963
X1368137Y1222298
X1368137Y1227798
X0859446Y1284288
X0721916Y1416939
X0721916Y1414339
X0782758Y1405249
X0780111Y1405366
X0146978Y1440000
X0141028Y1454705
X0137120Y1454751
X0133120Y1454751
X0971000Y1300000
X0884462Y1446974
X0688540Y1455140
X0697300Y1454140
X0640520Y1635483
X0447387Y1641441
X0292516Y1398132
X0292516Y1400632
X0307799Y1398269
X0307799Y1400769
X0295116Y1400632
X0295116Y1398132
X0305199Y1400769
X0305199Y1398269
X0324309Y1394099
X0324309Y1401799
X0324309Y1399199
X0324309Y1396599
X0333830Y1393799
X0333830Y1401499
X0333830Y1398899
X0333830Y1396299
X0172721Y1432671
X0163421Y1432671
X0163421Y1430171
R02Y-0002500
X0172721Y1427671
X0172721Y1430171
X0172721Y1425171
X1412572Y1556953
X1017069Y1290346
X1019314Y1289159
X1021908Y1289124
X0835554Y1281324
X0999894Y1267126
X1010944Y1279751
X1010865Y1275768
X1010894Y1271743
X0968500Y1300000
X0966000Y1300000
X0836587Y1295333
X0836670Y1291355
X0835682Y1285472
X0846725Y1269785
X0928827Y1283048
X0928979Y1278713
X0928852Y1274591
X0928901Y1270408
X0928751Y1266347
X0928983Y1295957
X0928906Y1291676
X0928928Y1287193
X0903690Y1298027
X0903651Y1293853
X0903923Y1289630
X0903945Y1285420
X0903899Y1281203
X0903947Y1276968
X0904024Y1272692
X0903980Y1268420
X0421059Y1569168
X0430239Y1581726
X0127264Y1588576
X0127246Y1585801
X0612969Y0447260
X0108861Y1526410
X0108861Y1528840
X0605796Y0425585
X0811569Y0387674
X0792488Y0377452
X0835425Y0477890
X0852240Y0470946
X0841862Y0390441
X0862075Y0398537
X0394915Y1590018
X0968594Y1288193
X0999303Y1285693
X0999304Y1289215
X0999304Y1282574
X0955000Y1279000
R03Y-0004000
X0662740Y0375240
X0140775Y1638035
X0655914Y1668744
X0663997Y1703111
X0649526Y1709274
X0649500Y0382500
X1151384Y1556029
X0422007Y1592330
X1135043Y1553371
X1152186Y1570567
X0367902Y0303760
X1172603Y1554561
X0393322Y1573347
X1178932Y1686698
X1691226Y1559526
X1691548Y1555287
X1688584Y1553284
X1682561Y1552726
X1680558Y1555690
X1695529Y1545193
X1691226Y1563526
X1689880Y1572067
X1680491Y1571235
X1680491Y1578089
X1682494Y1575125
X1682494Y1568271
X1181361Y1551040
R02Y-0003620
X1172523Y1573250
X1172523Y1562350
X1200824Y1593498
X1175454Y1668046
X1159741Y1669759
X0396237Y0315507
X0182548Y0147260
X0222000Y0160000
X0206760Y0148760
X0267500Y0220441
X0279500Y0234075
X0285260Y0234000
X0293000Y0216500
X0342075Y0287925
X0627958Y1654114
X0331000Y0270260
X1664256Y1690794
X1647700Y1674228
X1433979Y1655655
X1420042Y1649716
X1416357Y1644027
X0035852Y0705728
X1471616Y1670098
X1469034Y1667794
X1466260Y1675155
X0919886Y0179500
R05Y-0002500
X0917386Y0167000
X0917386Y0174500
X0917386Y0172000
X0917386Y0169500
X0917386Y0177000
X1466599Y1679401
X1479375Y1685984
X1466500Y1666000
X1453950Y1681450
X0963134Y0882936
X0944057Y0882886
X0659398Y0516260
X0679500Y0526834
X0317240Y0252970
X0056620Y0303500
X1642240Y0399603
X0686825Y1647430
X0454099Y1649575
X0687577Y1425054
X0767381Y1676594
X0671631Y1690786
X0080400Y1602225
X0674486Y1647842
X0673480Y1662668
X0693150Y1640773
X0743039Y1643326
X0712354Y1682279
X0665802Y1652337
X0642151Y1649961
X0192951Y1560498
X0875447Y0301500
X0698003Y1684692
X0738550Y1693215
X0732434Y1690660
X0728454Y1690491
X0164650Y1529350
X0164650Y1540250
X0703473Y1663001
X0624760Y0424569
X0709771Y1654927
X0705815Y1654918
X0717749Y1654921
X0635200Y0415425
X0726302Y1658022
X0730302Y1658050
X0706089Y1643411
X0674620Y1535271
X0672617Y1538235
X0674687Y1519726
X0672684Y1522690
X0683674Y1522287
X0680710Y1520284
X0672617Y1545089
X0674620Y1542125
X0688120Y1519601
X0683352Y1526526
X0683352Y1530526
X0665800Y1530575
X0151611Y1663933
X0151510Y1676811
X0101939Y1662728
X0101939Y1657742
X0106573Y1660235
X0114973Y1660235
X0102243Y1682263
X0102243Y1689263
X0105069Y1685763
X0113469Y1685763
X0085395Y1675311
X0085395Y1670331
X0083340Y1659333
X0083340Y1654353
X0044583Y1677613
X0044583Y1672433
X0038426Y1659059
X0038426Y1654079
X0080000Y1702450
X0079500Y1720450
X0093029Y1705225
X0097683Y1722477
X0130000Y1719450
X0125107Y1702666
X0152449Y1623572
X0152449Y1628528
X0682016Y1539067
X0129746Y1585801
X0036822Y1462075
R02Y-0003000
X0036822Y1465075
X0058349Y1403331
X0071511Y1444379
X0652189Y1421276
X0655873Y1428844
X0559090Y1452185
X0076378Y1406622
X0745712Y0212760
X0756083Y0220240
X0822559Y0530876
X0522831Y0443712
X0577801Y0466000
X0649266Y1650126
X0639284Y1683049
X1144118Y1449628
X1160031Y1591163
X1131832Y1607245
X1131790Y1597984
X1117263Y1601526
X1113785Y1601462
X1145060Y1588837
X1143063Y1580334
X1118004Y1584908
X1118326Y1594118
X0545931Y1451344
X1136173Y1573638
X1137523Y1579453
X1149278Y1589453
X0583505Y0457925
X1115394Y1620306
X0400905Y1596091
X1162144Y1658042
X1143127Y1649068
X1141645Y1640017
X1146316Y1649422
X1146477Y1658441
X0440846Y1576526
X0410672Y1561170
X0173488Y1518040
R02Y-0003620
X0084500Y1440000
X1192903Y1666276
X1179187Y1666429
X1185676Y1697249
X1169187Y1687117
X1128934Y1688600
X1137492Y1685240
X1132209Y1672033
X1144107Y1671118
X1140117Y1671421
X0093000Y1440000
X1292673Y1559750
X1420735Y1559750
X1556847Y1559750
X0151082Y1436653
X0143478Y1440000
X0145028Y1454705
X1138752Y1624627
X1132168Y1620860
X0444128Y1600200
X0444128Y1604200
X1409660Y1619853
X1398058Y1619683
X0428746Y1521727
X0556965Y1521561
X0550540Y1526910
X0569464Y0462140
X0412862Y1526750
X0164730Y1521561
X0421347Y1636668
X1318363Y1411404
X1187925Y1417000
X1194000Y1418000
X1185000Y1405500
X1184100Y1410000
X1185000Y1401000
X1185000Y1396500
X1220855Y1412564
X1228355Y1412564
X1213355Y1412564
X1202484Y1402467
X1242500Y1437075
X1237100Y1442500
X1242500Y1430075
X1220855Y1427564
X1228355Y1420064
X1228355Y1427564
X1213355Y1420064
X1213355Y1427564
X1187925Y1440400
X1194000Y1433000
X1194000Y1428500
X1178400Y1433000
X0112355Y1433564
X0112355Y1426064
X0097530Y1410247
X0084000Y1426000
R04Y-0004500
X0093000Y1430500
X0150900Y1429500
X0127355Y1426064
X0127355Y1433564
X0119855Y1426064
X0150900Y1433500
X0127355Y1441064
R02X-0007500
X0093000Y1435500
X0938507Y1137843
X0975000Y1307500
X0967500Y1340241
X0877000Y1340241
X1433327Y1643287
X1422914Y1601663
X1435584Y1596545
X1695166Y1717606
X1702777Y1723593
X0439404Y1615146
X0439283Y1608704
X0403848Y1615354
X0403417Y1606224
X1689383Y1729187
X0938000Y1304500
X0938000Y1301500
X0938000Y1309500
X1653464Y1668416
X0885000Y1307500
X0924000Y1310000
X1651101Y1700478
X1660541Y1704237
X1430319Y1623504
X1421392Y1621706
X1421232Y1606126
X1430075Y1613904
X1425390Y1635496
X1397367Y1639951
X1402425Y1649532
X0416163Y1594450
X0411515Y1599649
X0426688Y1598003
X1724323Y1676965
X1685298Y1451231
X1704822Y1694243
X0842500Y1302000
R02Y0004000
X1683587Y1433425
X0387805Y1610802
X0387805Y1604802
X0387805Y1607802
X0696105Y0364149
X0052052Y1684027
X0129764Y1588576
X0085133Y1625396
X0085167Y1629905
X0085133Y1620896
X0085133Y1616396
X0076806Y1593265
X0054449Y1641722
X0051333Y1640996
X0058633Y1641388
X0053767Y1609405
X0053767Y1621405
X0053767Y1615405
X0059767Y1609405
X0065767Y1609405
X0059767Y1621405
X0065943Y1621405
X0065767Y1615405
X0050133Y1592481
X0047602Y1622414
X0035167Y1610521
X0035133Y1603396
X0035233Y1623196
X0045633Y1592481
X0159427Y1687843
X0155328Y1670087
X0139353Y1696062
X0146928Y1685087
X0143353Y1696062
X0140353Y1646612
R02X0004000
X0135353Y1696062
X0131353Y1696062
X0123278Y1658587
X0136048Y1666851
X0133548Y1677351
X0124353Y1646612
X0128353Y1646612
X0115353Y1695941
X0119353Y1695941
X0120353Y1646612
X0116353Y1646612
X0100915Y1679564
X0100439Y1667361
X0086127Y1687362
X0089466Y1667127
X0089466Y1663138
X0078127Y1687362
X0074127Y1687362
X0073427Y1644410
X0068427Y1644410
X0070127Y1687362
X0069589Y1669878
X0069486Y1661828
X0061374Y1669931
X0061415Y1661695
X0053648Y1653088
X0051358Y1650217
X0051358Y1647717
X0059427Y1644410
X0041427Y1668587
X1773963Y1680965
X1773738Y1672965
X1773863Y1661465
X1758963Y1691565
X1763463Y1691465
X1761494Y1661947
X1754763Y1641665
X1743329Y1674956
X1755329Y1674956
X1749329Y1674956
X1743153Y1662956
X1743329Y1668956
X1755329Y1662956
X1755329Y1668956
X1749329Y1662956
X1757763Y1643365
X1747963Y1641965
X1724263Y1681465
X1723963Y1667965
X1723929Y1654456
X1723963Y1663465
X1723963Y1658965
X1818344Y1539373
X1815344Y1539373
X1810408Y1539223
X1807408Y1539223
X1558493Y1563595
X1555993Y1563595
X1562613Y1564816
X1564581Y1562316
X1562621Y1569761
X1564128Y1572225
X1548684Y1556953
X1576653Y1579333
X1583523Y1585567
X1662129Y1582178
X1670248Y1581563
X1427931Y1563595
X1430431Y1563595
X1435578Y1562402
X1435578Y1564902
X1435604Y1569606
X1435604Y1572106
X1445535Y1543800
R02Y0003620
X1446027Y1561731
X1448505Y1579725
X1455461Y1585567
X1548132Y1542654
X1534067Y1582178
X1542186Y1581563
X1573597Y1551040
R02Y-0003620
X1574089Y1561731
X1294319Y1563595
X1291819Y1563595
X1299466Y1564902
X1299466Y1562402
X1299492Y1569606
X1299492Y1572106
X1284510Y1556953
X1312700Y1579596
X1319349Y1585567
X1397955Y1582178
X1412020Y1542654
X1406074Y1581563
X1181853Y1561731
X1283958Y1542654
X1278012Y1581563
X1309423Y1551040
R02Y-0003620
X1309915Y1561731
X0550619Y1530595
X0548119Y1530595
X0554715Y1531564
X0556642Y1529389
X0556197Y1539187
X0540810Y1523953
X0568779Y1546333
X0575649Y1552567
X0654005Y1548999
X0662374Y1548563
X0420057Y1530595
X0422557Y1530595
X0427704Y1529402
X0427704Y1531902
X0427730Y1536606
X0427730Y1539106
X0437661Y1510800
R02Y0003620
X0438153Y1528731
X0438732Y1546977
X0447587Y1552567
X0565723Y1518040
R02Y-0003620
X0566215Y1528731
X0404699Y1523953
X0404147Y1509654
X0398201Y1548563
X0390082Y1549178
X0173980Y1528731
X0989556Y1100408
X0989556Y1097008
X0989556Y1084108
X0989556Y1087508
X0966905Y1152769
X0969905Y1149769
X0966905Y1149769
X0969905Y1143369
X0969905Y1139969
X0966905Y1143369
X0966905Y1139969
X0969905Y1146569
X0966905Y1146569
X0986356Y1100408
X0983156Y1100408
X0983156Y1097008
X0986356Y1097008
X0986356Y1084108
X0983156Y1084108
X0983156Y1087508
X0986356Y1087508
X0953498Y1158574
X0947748Y1146553
X0944820Y1156119
X0977150Y1052684
X0919880Y1152769
X0922880Y1149769
X0922880Y1143369
X0922880Y1139969
X0922880Y1146569
X0919880Y1149769
X0916880Y1138969
X0919880Y1143369
X0919880Y1139969
X0919880Y1146569
X0889057Y1053133
X0906473Y1158574
X0900723Y1146553
X0897754Y1156119
X0891648Y1137843
X0898000Y1109736
X0898000Y1112336
X0881217Y1097557
X0881217Y1100957
X0881217Y1088057
X0881217Y1084657
X0874617Y1097557
X0877817Y1097557
X0877817Y1100957
X0874617Y1100957
X0874617Y1088057
X0877817Y1088057
X0877817Y1084657
X0874617Y1084657
X0920107Y1245920
X0920107Y1248920
X0920107Y1257742
R02Y-0003000
X0905007Y1245920
X0905007Y1248920
X0910707Y1251742
X0910707Y1257742
X0910707Y1254742
X0896907Y1248920
X0896907Y1245920
X0896107Y1251742
R02Y0003000
X0881937Y1251857
X0881807Y1245920
X0881807Y1248920
X0886707Y1251742
R02Y0003000
X0810986Y1361684
X0810246Y1351988
X0808469Y1359245
X0808469Y1356745
X0801171Y1343278
X0804099Y1333835
X0807601Y1307191
X0804530Y1310259
X0802030Y1310259
X0785014Y1350862
X0795421Y1331257
X0788530Y1310259
X0796530Y1310259
X0794030Y1310259
X0786030Y1310259
X0780000Y1360500
X0780000Y1363500
X0782014Y1349862
X0782014Y1346462
X0779014Y1349862
X0779014Y1346462
X0780000Y1353500
X0782014Y1343262
X0782014Y1337062
X0782014Y1340062
X0779014Y1340062
X0779014Y1343262
X0780530Y1310259
X0778030Y1310259
X0270139Y1548563
X0276637Y1523953
X0292792Y1521561
X0221325Y1550797
X0226050Y1550897
X0216601Y1550697
X0284800Y1526750
X0302042Y1528731
X0304606Y1546333
X0311476Y1552567
X0301550Y1510800
R02Y0003620
X0291593Y1531902
X0291593Y1529402
X0291619Y1539106
X0291619Y1536606
X0286446Y1530595
X0283946Y1530595
X1695102Y1698947
X1684733Y1698952
X1551887Y0606938
X1584160Y0558973
X1589436Y0555463
X1591962Y0555463
X1595036Y0555463
X1597562Y0555463
X1565676Y0568423
X1561376Y0572258
X1570676Y0568423
X1568176Y0568423
X1593214Y0531226
X1579748Y0536344
X1677516Y0609450
X1671516Y0609450
X1677516Y0599956
X1674516Y0609450
X1671516Y0599956
X1674516Y0599956
X1668516Y0609450
X1668516Y0599956
X1635798Y0558364
X1638798Y0555364
X1635798Y0555364
X1635798Y0548964
X1635798Y0552164
X1638798Y0552164
X1638798Y0548964
X1638798Y0545564
X1635798Y0545564
X1632798Y0544564
X1636783Y0542604
X1636929Y0538690
R02Y-0003500
X1639868Y0542444
X1636929Y0528190
X1636929Y0524690
X1631889Y0521480
X1622391Y0564169
X1618884Y0533388
X1606535Y0553297
X1607369Y0561330
X0401666Y1677925
X0409000Y1667025
X0635210Y1721545
X0654527Y1718229
X0654508Y1728000
X0276085Y1509654
X0307255Y1641150
X0297323Y1651172
X0297323Y1659772
X0307255Y1649750
X0203800Y1646832
X0207968Y1653130
X0163113Y1507982
X1308700Y0587800
X1321300Y0640000
R03Y0003000
X1318300Y0646000
R02Y-0003000
X0199547Y1704605
X0233474Y0609640
X0236674Y0609640
X0236656Y0601598
X0233456Y0601598
X0754556Y0283976
X0234727Y0584030
X0420765Y1630495
X0417365Y1630495
X1117828Y1473091
X1117946Y1467955
X0406075Y1641000
X0400623Y1629772
X0415437Y1636382
X0416962Y1634123
X0448776Y1619766
X0448776Y1617166
X0448776Y1622266
X0432559Y1627500
X0428000Y1640500
X0417441Y1643946
X0411500Y1653500
X0420000Y1668075
X0417000Y1683500
X0405000Y1683500
X0187388Y1621796
X0204404Y1621796
X0199448Y1621796
X0192344Y1621796
X0204404Y1626788
X0199448Y1626788
X0192344Y1626788
X0216464Y1621796
X0211508Y1621796
X0216464Y1626788
X0211508Y1626788
X0228524Y1621796
X0223568Y1621796
X0228524Y1626788
X0223568Y1626788
X0247688Y1621796
X0240584Y1621796
X0235628Y1621796
X0247688Y1626788
X0240584Y1626788
X0235628Y1626788
X0264704Y1621796
X0259748Y1621796
X0252644Y1621796
X0264704Y1626788
X0259748Y1626788
X0252644Y1626788
X0276764Y1621796
X0271808Y1621796
X0276764Y1626788
X0271808Y1626788
X0288824Y1621796
X0283868Y1621796
X0288824Y1626788
X0283868Y1626788
X0300884Y1621796
X0295928Y1621796
X0307988Y1621796
X0300884Y1626788
X0295928Y1626788
X0307988Y1626788
X0312944Y1621796
X0320048Y1621796
X0312944Y1626788
X0320048Y1626788
X0325004Y1621796
X0337064Y1621796
X0332108Y1621796
X0325004Y1626788
X0337064Y1626788
X0332108Y1626788
X0349124Y1621796
X0344168Y1621796
X0349124Y1626788
X0344168Y1626788
X0361184Y1621796
X0356228Y1621796
X0368288Y1621796
X0361184Y1626788
X0356228Y1626788
X0368288Y1626788
X0373244Y1621796
X0373244Y1626788
X0461000Y1650000
X0452500Y1637559
X0457240Y1629500
X0456517Y1626788
X0451561Y1626788
X0451561Y1621796
X0456517Y1621796
X0468350Y1645351
X0478500Y1655500
X0462500Y1655500
X0470500Y1674075
X0476000Y1680000
X0478500Y1701000
X0462500Y1701000
X0464734Y1730518
X0478500Y1714500
X0330223Y1455495
X0335003Y1455495
X0330223Y1450295
X0335003Y1450295
X0328313Y1452895
X0336913Y1452895
X0206941Y1455495
X0202161Y1455495
X0208851Y1452895
X0200251Y1452895
X0206941Y1450295
X0202161Y1450295
X0471114Y1455495
X0466334Y1455495
X0473024Y1452895
X0464424Y1452895
X0471114Y1450295
X0466334Y1450295
X0599176Y1455495
X0594396Y1455495
X0601086Y1452895
X0592486Y1452895
X0599176Y1450295
X0594396Y1450295
X1214814Y1488495
X1210034Y1488495
X1216724Y1485895
X1208124Y1485895
X1214814Y1483295
X1210034Y1483295
X1342876Y1488495
X1338096Y1488495
X1344786Y1485895
X1336186Y1485895
X1342876Y1483295
X1338096Y1483295
X1478988Y1488495
X1474208Y1488495
X1480898Y1485895
X1472298Y1485895
X1478988Y1483295
X1474208Y1483295
X1607050Y1488495
X1602270Y1488495
X1608960Y1485895
X1600360Y1485895
X1607050Y1483295
X1602270Y1483295
X0291175Y1507990
X0293775Y1479500
X0293775Y1484280
X0293775Y1501300
X0293775Y1506080
X0288575Y1479500
X0288575Y1484280
X0288575Y1501300
X0288575Y1506080
X0291175Y1477590
X0291175Y1486190
X0291175Y1499490
X0321603Y1474895
X0316823Y1474895
X0343623Y1474895
X0348403Y1474895
X0370423Y1474895
X0375203Y1474895
X0321603Y1469695
X0316823Y1469695
X0343623Y1469695
X0348403Y1469695
X0370423Y1469695
X0375203Y1469695
X0296723Y1465195
X0301503Y1465195
X0328303Y1465195
X0323523Y1465195
X0355103Y1465195
X0350323Y1465195
X0381903Y1465195
X0377123Y1465195
X0296723Y1459995
X0301503Y1459995
X0328303Y1459995
X0323523Y1459995
X0355103Y1459995
X0350323Y1459995
X0381903Y1459995
X0377123Y1459995
X0308203Y1455495
X0303423Y1455495
X0357023Y1455495
X0361803Y1455495
X0388603Y1455495
X0383823Y1455495
X0402003Y1455495
X0397223Y1455495
X0308203Y1450295
X0303423Y1450295
X0357023Y1450295
X0361803Y1450295
X0388603Y1450295
X0383823Y1450295
X0402003Y1450295
X0397223Y1450295
X0294813Y1462595
X0301513Y1452895
X0310113Y1452895
X0303413Y1462595
X0321613Y1462595
X0330213Y1462595
X0314913Y1472295
X0328313Y1472295
X0323513Y1472295
X0341713Y1472295
X0350313Y1472295
X0368513Y1472295
X0348413Y1462595
X0357013Y1462595
X0375213Y1462595
X0355113Y1452895
X0363713Y1452895
X0381913Y1452895
X0395313Y1452895
X0390513Y1452895
X0383813Y1462595
X0403913Y1452895
X0377113Y1472295
X0406083Y1493392
X0406083Y1484772
X0406083Y1479992
X0406083Y1498172
X0411283Y1493392
X0411283Y1484772
X0411283Y1479992
X0411283Y1498172
X0408683Y1491482
X0408683Y1486682
X0408683Y1500082
X0408683Y1478082
X0427286Y1507990
X0429886Y1479500
X0429886Y1484280
X0429886Y1501300
X0429886Y1506080
X0424686Y1479500
X0424686Y1484280
X0424686Y1501300
X0424686Y1506080
X0427286Y1477590
X0427286Y1486190
X0427286Y1499490
X0457714Y1474895
X0452934Y1474895
X0479734Y1474895
X0484514Y1474895
X0506534Y1474895
X0511314Y1474895
X0457714Y1469695
X0452934Y1469695
X0479734Y1469695
X0484514Y1469695
X0506534Y1469695
X0511314Y1469695
X0432834Y1465195
X0437614Y1465195
X0464414Y1465195
X0459634Y1465195
X0491214Y1465195
X0486434Y1465195
X0518014Y1465195
X0513234Y1465195
X0432834Y1459995
X0437614Y1459995
X0464414Y1459995
X0459634Y1459995
X0491214Y1459995
X0486434Y1459995
X0518014Y1459995
X0513234Y1459995
X0444314Y1455495
X0439534Y1455495
X0493134Y1455495
X0497914Y1455495
X0524714Y1455495
X0519934Y1455495
X0538114Y1455495
X0533334Y1455495
X0444314Y1450295
X0439534Y1450295
X0493134Y1450295
X0497914Y1450295
X0524714Y1450295
X0519934Y1450295
X0538114Y1450295
X0533334Y1450295
X0430924Y1462595
X0437624Y1452895
X0446224Y1452895
X0439524Y1462595
X0457724Y1462595
X0466324Y1462595
X0451024Y1472295
X0459624Y1472295
X0477824Y1472295
X0486424Y1472295
X0504624Y1472295
X0484524Y1462595
X0493124Y1462595
X0511324Y1462595
X0491224Y1452895
X0499824Y1452895
X0518024Y1452895
X0531424Y1452895
X0526624Y1452895
X0519924Y1462595
X0540024Y1452895
X0513224Y1472295
X0542194Y1493392
X0542194Y1484772
X0542194Y1479992
X0542194Y1498172
X0547394Y1493392
X0547394Y1484772
X0547394Y1479992
X0547394Y1498172
X0537694Y1504872
X0544794Y1486682
X0544794Y1500082
X0544794Y1478082
X0555348Y1507990
X0557948Y1479500
X0557948Y1484280
X0557948Y1501300
X0557948Y1506080
X0552748Y1479500
X0552748Y1484280
X0552748Y1501300
X0552748Y1506080
X0555348Y1477590
X0555348Y1486190
X0555348Y1499490
X0585776Y1474895
X0580996Y1474895
X0607796Y1474895
X0612576Y1474895
X0634596Y1474895
X0639376Y1474895
X0585776Y1469695
X0580996Y1469695
X0607796Y1469695
X0612576Y1469695
X0634596Y1469695
X0639376Y1469695
X0560896Y1465195
X0565676Y1465195
X0592476Y1465195
X0587696Y1465195
X0619276Y1465195
X0614496Y1465195
X0646076Y1465195
X0641296Y1465195
X0560896Y1459995
X0565676Y1459995
X0592476Y1459995
X0587696Y1459995
X0619276Y1459995
X0614496Y1459995
X0646076Y1459995
X0641296Y1459995
X0572376Y1455495
X0567596Y1455495
X0621196Y1455495
X0625976Y1455495
X0652776Y1455495
X0647996Y1455495
X0666176Y1455495
X0661396Y1455495
X0572376Y1450295
X0567596Y1450295
X0621196Y1450295
X0625976Y1450295
X0652776Y1450295
X0647996Y1450295
X0666176Y1450295
X0661396Y1450295
X0558986Y1462595
X0565686Y1452895
X0574286Y1452895
X0567586Y1462595
X0585786Y1462595
X0594386Y1462595
X0579086Y1472295
X0587686Y1472295
X0605886Y1472295
X0614486Y1472295
X0632686Y1472295
X0612586Y1462595
X0621186Y1462595
X0639386Y1462595
X0619286Y1452895
X0627886Y1452895
X0646086Y1452895
X0659486Y1452895
X0654686Y1452895
X0647986Y1462595
X0668086Y1452895
X0641286Y1472295
X0670256Y1493392
X0670256Y1484772
X0670256Y1479992
X0670256Y1498172
X0675456Y1493392
X0675456Y1484772
X0675112Y1479602
X0675456Y1498172
X0665756Y1504872
X0672856Y1491482
X0672856Y1486682
X0672856Y1500082
X0672856Y1478082
X1170986Y1540990
X1173586Y1512500
X1173586Y1517280
X1173586Y1539080
X1168386Y1512500
X1168386Y1517280
X1168386Y1534300
X1168386Y1539080
X1170986Y1510590
X1170986Y1519190
X1170986Y1532490
X1201414Y1507895
X1196634Y1507895
X1223434Y1507895
X1250234Y1507895
X1255014Y1507895
X1201414Y1502695
X1196634Y1502695
X1223434Y1502695
X1228214Y1502695
X1250234Y1502695
X1255014Y1502695
X1176534Y1498195
X1181314Y1498195
X1208114Y1498195
X1203334Y1498195
X1234914Y1498195
X1230134Y1498195
X1261714Y1498195
X1256934Y1498195
X1176534Y1492995
X1181314Y1492995
X1208114Y1492995
X1203334Y1492995
X1234914Y1492995
X1230134Y1492995
X1261714Y1492995
X1256934Y1492995
X1188014Y1488495
X1183234Y1488495
X1236834Y1488495
X1241614Y1488495
X1268414Y1488495
X1263634Y1488495
X1281814Y1488495
X1277034Y1488495
X1188014Y1483295
X1183234Y1483295
X1236834Y1483295
X1241614Y1483295
X1268414Y1483295
X1263634Y1483295
X1281814Y1483295
X1277034Y1483295
X1174624Y1495595
X1181324Y1485895
X1189924Y1485895
X1183224Y1495595
X1201424Y1495595
X1210024Y1495595
X1194724Y1505295
X1203324Y1505295
X1221524Y1505295
X1230124Y1505295
X1248324Y1505295
X1228224Y1495595
X1236824Y1495595
X1255024Y1495595
X1234924Y1485895
X1243524Y1485895
X1261724Y1485895
X1275124Y1485895
X1270324Y1485895
X1263624Y1495595
X1283724Y1485895
X1256924Y1505295
X1285894Y1526392
X1285894Y1517772
X1285894Y1512992
X1285894Y1531172
X1291094Y1526392
X1291094Y1517772
X1291094Y1512992
X1291094Y1531172
X1288494Y1524482
X1288494Y1519682
X1288494Y1533082
X1288494Y1511082
X1299048Y1540990
X1301648Y1512500
X1301648Y1517280
X1301648Y1534300
X1301648Y1539080
X1296448Y1512500
X1296448Y1517280
X1296448Y1534300
X1296448Y1539080
X1299048Y1510590
X1299048Y1519190
X1299048Y1532490
X1329476Y1507895
X1324696Y1507895
X1351496Y1507895
X1356276Y1507895
X1378296Y1507895
X1383076Y1507895
X1329476Y1502695
X1324696Y1502695
X1351496Y1502695
X1356276Y1502695
X1378296Y1502695
X1383076Y1502695
X1304596Y1498195
X1309376Y1498195
X1336176Y1498195
X1331396Y1498195
X1362976Y1498195
X1358196Y1498195
X1389776Y1498195
X1384996Y1498195
X1304596Y1492995
X1309376Y1492995
X1336176Y1492995
X1331396Y1492995
X1362976Y1492995
X1358196Y1492995
X1389776Y1492995
X1384996Y1492995
X1316076Y1488495
X1311296Y1488495
X1364896Y1488495
X1369676Y1488495
X1396476Y1488495
X1391696Y1488495
X1409876Y1488495
X1405096Y1488495
X1316076Y1483295
X1311296Y1483295
X1364896Y1483295
X1369676Y1483295
X1396476Y1483295
X1391696Y1483295
X1409876Y1483295
X1405096Y1483295
X1302686Y1495595
X1309386Y1485895
X1317986Y1485895
X1311286Y1495595
X1329486Y1495595
X1338086Y1495595
X1322786Y1505295
X1331386Y1505295
X1349586Y1505295
X1358186Y1505295
X1376386Y1505295
X1356286Y1495595
X1364886Y1495595
X1383086Y1495595
X1362986Y1485895
X1371586Y1485895
X1389786Y1485895
X1403186Y1485895
X1398386Y1485895
X1391686Y1495595
X1411786Y1485895
X1384986Y1505295
X1413956Y1526392
X1413956Y1517772
X1413956Y1512992
X1413956Y1531172
X1419156Y1526392
X1419156Y1517772
X1419156Y1512992
X1419156Y1531172
X1416556Y1524482
X1416556Y1519682
X1416556Y1533082
X1416556Y1511082
X1435160Y1540990
X1437760Y1512500
X1437760Y1517280
X1437760Y1534300
X1437760Y1539080
X1432560Y1512500
X1432560Y1517280
X1432560Y1534300
X1432560Y1539080
X1435160Y1510590
X1435160Y1519190
X1435160Y1532490
X1465588Y1507895
X1460808Y1507895
X1487608Y1507895
X1492388Y1507895
X1514408Y1507895
X1519188Y1507895
X1465588Y1502695
X1460808Y1502695
X1487608Y1502695
X1492388Y1502695
X1514408Y1502695
X1527808Y1502695
X1519188Y1502695
X1440708Y1498195
X1445488Y1498195
X1472288Y1498195
X1467508Y1498195
X1499088Y1498195
X1494308Y1498195
X1525888Y1498195
X1521108Y1498195
X1440708Y1492995
X1445488Y1492995
X1472288Y1492995
X1467508Y1492995
X1499088Y1492995
X1494308Y1492995
X1525888Y1492995
X1521108Y1492995
X1452188Y1488495
X1447408Y1488495
X1501008Y1488495
X1505788Y1488495
X1532588Y1488495
X1527808Y1488495
X1545988Y1488495
X1541208Y1488495
X1452188Y1483295
X1447408Y1483295
X1501008Y1483295
X1505788Y1483295
X1532588Y1483295
X1527808Y1483295
X1545988Y1483295
X1541208Y1483295
X1438798Y1495595
X1445498Y1485895
X1454098Y1485895
X1447398Y1495595
X1465598Y1495595
X1474198Y1495595
X1458898Y1505295
X1467498Y1505295
X1485698Y1505295
X1494298Y1505295
X1512498Y1505295
X1492398Y1495595
X1500998Y1495595
X1519198Y1495595
X1499098Y1485895
X1507698Y1485895
X1525898Y1485895
X1539298Y1485895
X1534498Y1485895
X1527798Y1495595
X1547898Y1485895
X1525898Y1505295
X1521098Y1505295
X1550068Y1526392
X1550068Y1517772
X1550068Y1512992
X1550068Y1531172
X1555268Y1526392
X1555268Y1517772
X1555268Y1512992
X1555268Y1531172
X1552668Y1524482
X1552668Y1519682
X1552668Y1533082
X1552668Y1511082
X1563222Y1540990
X1565822Y1512500
X1565822Y1517280
X1565822Y1534300
X1565822Y1539080
X1560622Y1512500
X1560622Y1517280
X1560622Y1534300
X1560622Y1539080
X1563222Y1510590
X1563222Y1519190
X1563222Y1532490
X1593650Y1507895
X1588870Y1507895
X1615670Y1507895
X1620450Y1507895
X1642470Y1507895
X1647250Y1507895
X1593650Y1502695
X1588870Y1502695
X1615670Y1502695
X1620450Y1502695
X1642470Y1502695
X1647250Y1502695
X1568770Y1498195
X1573550Y1498195
X1600350Y1498195
X1595570Y1498195
X1627150Y1498195
X1622370Y1498195
X1653950Y1498195
X1649170Y1498195
X1568770Y1492995
X1573550Y1492995
X1600350Y1492995
X1595570Y1492995
X1627150Y1492995
X1622370Y1492995
X1653950Y1492995
X1649170Y1492995
X1580250Y1488495
X1575470Y1488495
X1629070Y1488495
X1633850Y1488495
X1660650Y1488495
X1655870Y1488495
X1674050Y1488495
X1669270Y1488495
X1580250Y1483295
X1575470Y1483295
X1629070Y1483295
X1633850Y1483295
X1660650Y1483295
X1655870Y1483295
X1674050Y1483295
X1669270Y1483295
X1566860Y1495595
X1573560Y1485895
X1582160Y1485895
X1575460Y1495595
X1593660Y1495595
X1602260Y1495595
X1586960Y1505295
X1595560Y1505295
X1613760Y1505295
X1622360Y1505295
X1640560Y1505295
X1620460Y1495595
X1629060Y1495595
X1647260Y1495595
X1627160Y1485895
X1635760Y1485895
X1653960Y1485895
X1667360Y1485895
X1662560Y1485895
X1655860Y1495595
X1675960Y1485895
X1649160Y1505295
X1678130Y1526392
X1678130Y1517772
X1678130Y1512992
X1678130Y1531172
X1683330Y1526392
X1683330Y1517772
X1682760Y1512169
X1683330Y1531172
X1673630Y1537872
X1673630Y1533092
X1680730Y1524482
X1680730Y1519682
X1680730Y1533082
X1680430Y1511198
X0468500Y1708500
X0379895Y1670046
X0923916Y0843990
X0651840Y1567752
X0150318Y0233536
X0652274Y1630366
X0657392Y1628137
X0660542Y1638169
X0650895Y1648115
X0706681Y1627361
X0423439Y1612407
X0413200Y1612700
X0423379Y1607675
X0418293Y1607495
X0413100Y1607600
X0423349Y1617857
X0418500Y1618000
X0413100Y1617900
X0175361Y1455495
X0180141Y1455495
X0175361Y1450295
X0180141Y1450295
X0195461Y1465195
X0200241Y1465195
X0195461Y1459995
X0200241Y1459995
X0188761Y1474895
X0193541Y1474895
X0188761Y1469695
X0193541Y1469695
X0222261Y1465195
X0227041Y1465195
X0222261Y1459995
X0227041Y1459995
X0215561Y1474895
X0220341Y1474895
X0215561Y1469695
X0220341Y1469695
X0228961Y1455495
X0233741Y1455495
X0228961Y1450295
X0233741Y1450295
X0242361Y1474895
X0247141Y1474895
X0242361Y1469695
X0247141Y1469695
X0249061Y1465195
X0253841Y1465195
X0249061Y1459995
X0253841Y1459995
X0255761Y1455495
X0260541Y1455495
X0255761Y1450295
X0260541Y1450295
X0269161Y1455495
X0273941Y1455495
X0269161Y1450295
X0273941Y1450295
X0278021Y1479992
X0278021Y1484772
X0283221Y1479992
X0283221Y1484772
X0165713Y1506080
X0160513Y1506080
X0160513Y1501300
X0165713Y1484280
X0165713Y1479500
X0160513Y1484280
X0160513Y1479500
X0173451Y1452895
X0182051Y1452895
X0193551Y1462595
X0202151Y1462595
X0186851Y1472295
X0195451Y1472295
X0220351Y1462595
X0228951Y1462595
X0213651Y1472295
X0222251Y1472295
X0227051Y1452895
X0235651Y1452895
X0240451Y1472295
X0249051Y1472295
X0247151Y1462595
X0255751Y1462595
X0253851Y1452895
X0262451Y1452895
X0267251Y1452895
X0275851Y1452895
X0280621Y1478082
X0280621Y1486682
X0280621Y1500082
X0163113Y1499490
X0163113Y1486190
X0163113Y1477590
X0705833Y1633568
X0688308Y1631636
X0673982Y1639289
X0674894Y1629042
X0685485Y1682259
X0705366Y1684064
X0695400Y1685887
X1120303Y1682055
X1105000Y1682132
X1116000Y1671029
X0544794Y1491482
X0173441Y1465195
X0175351Y1462595
X0173441Y1459995
X0168661Y1465195
X0166751Y1462595
X0168661Y1459995
X0738370Y1677909
X0734925Y1657826
X0743740Y1657327
X0736001Y1695509
X0659436Y1694697
X0661845Y1717340
X1096469Y1643468
X1120200Y1646597
X1125487Y1641754
X1120595Y1652037
X1125771Y1652189
X1130245Y1652189
X1130684Y1646949
X1130772Y1641753
X1120376Y1641684
X0682925Y1657116
X0200848Y1655656
X0201120Y1668603
X0203807Y1681173
X0195300Y1694898
X0203807Y1696366
X0192745Y1707106
X0190391Y1701988
X1068221Y1662778
X1064221Y1662726
X1063751Y1653834
X1068094Y1654099
X1050866Y1659548
X0184340Y1718000
X0157860Y1718500
X0120052Y1712450
X0181760Y1731351
X0167500Y1712864
X0201531Y1715000
X0195150Y1723000
X0179444Y1708810
X0171925Y1708428
X0171925Y1727581
X0194000Y1712362
X0155740Y1729726
X0211103Y1708988
X0152815Y1705500
X0147277Y1712791
X0213648Y1416262
X1448500Y1601000
X1445500Y1611500
X1452579Y1673303
R02X-0005000
X1456852Y1673320
X0926004Y0952716
X0943135Y0977129
X0942924Y0982547
X0908799Y0985291
X0909203Y0970709
X0910066Y0960332
X0909890Y0950217
X0926062Y0938727
X0939670Y0945169
X0940391Y0859947
X0958051Y0859384
X0931948Y0891397
X0948060Y0891468
X0920276Y0900554
X0904719Y0921792
X0897824Y0909093
X0919916Y0908916
X0920409Y0918274
X0928535Y0913454
X0951367Y0913648
X0940514Y0918134
X0931877Y0918168
X0831756Y0901318
X1601959Y1351773
X1601772Y1337293
X1577913Y1341623
X1578336Y1356103
X1575504Y1356103
X0746705Y0315647
X0933021Y0933979
X0951500Y0930925
X1137846Y1453487
X0952425Y0876575
X0092192Y1713741
X0106448Y1696436
X0132643Y1711846
X0124461Y1726116
X1648029Y1718759
X1648013Y1713684
X1648029Y1733909
X1648013Y1728834
X1665520Y1716877
X1656997Y1708609
X1665520Y1732027
X1656997Y1723759
X1668000Y1711759
X1668000Y1726909
X1742120Y1708265
X1739640Y1713383
X1752864Y1716383
X1455579Y1636114
X1133765Y1572102
X1119067Y1551457
X0791823Y1527404
X0784277Y1528191
X0758179Y1534963
X0784261Y1534963
X0758163Y1526223
X0758179Y1482049
X0784261Y1482049
X1405058Y1639607
X1399940Y1637127
X1418740Y1622902
X1413199Y1643920
X1197980Y1688270
X1192612Y1680410
X1189462Y1691366
X1199612Y1700334
X0387182Y1550797
X0382458Y1550897
X0377733Y1550897
X0373009Y1550697
X0368285Y1550897
X0363561Y1550897
X0358836Y1550897
X0354112Y1550897
X0344663Y1550697
X0349387Y1550797
X0339938Y1550897
X0335214Y1550897
X0330489Y1550697
X0325765Y1550897
X0316316Y1550797
X0321040Y1550797
X1651321Y1644796
X1651321Y1649788
X1651321Y1632884
X1651321Y1637876
X1645291Y1659788
X1640335Y1659788
X1633231Y1659788
X1646365Y1644796
X1639261Y1644796
X1634305Y1644796
X1646365Y1649788
X1645291Y1654796
X1639261Y1649788
X1640335Y1654796
X1634305Y1649788
X1633231Y1654796
X1645291Y1627876
X1640335Y1627876
X1633231Y1627876
X1646365Y1632884
X1646365Y1637876
X1639261Y1632790
X1639261Y1637876
X1634305Y1632790
X1634305Y1637876
X1640335Y1622884
X1645291Y1622884
X1633231Y1622884
X1628275Y1659788
X1621171Y1659788
X1627201Y1644796
X1622245Y1644796
X1627201Y1649788
X1628275Y1654796
X1622245Y1649788
X1621171Y1654796
X1628275Y1627876
X1621171Y1627876
X1627201Y1632884
X1627201Y1637876
X1622245Y1632884
X1622245Y1637876
X1628275Y1622884
X1621171Y1622884
X1609111Y1659788
X1616215Y1659788
X1604155Y1659788
X1610185Y1644796
X1615141Y1644796
X1610185Y1649788
X1615141Y1649788
X1609111Y1654796
X1616215Y1654796
X1604155Y1654796
X1616215Y1627876
X1609111Y1627876
X1604155Y1627876
X1615141Y1632884
X1610185Y1632884
X1615141Y1637876
X1610185Y1637876
X1616215Y1622884
X1604155Y1622884
X1609111Y1622884
X1597051Y1659788
X1592095Y1659788
X1598125Y1644796
X1603081Y1644796
X1591021Y1644796
X1598125Y1649788
X1603081Y1649788
X1597051Y1654796
X1591021Y1649788
X1592095Y1654796
X1597051Y1627876
X1592095Y1627876
X1603081Y1632884
X1598125Y1632884
X1603081Y1637876
X1598125Y1637876
X1591021Y1632884
X1591021Y1637876
X1592095Y1622884
X1597051Y1622884
X1584991Y1659788
X1580035Y1659788
X1586065Y1644796
X1578961Y1644796
X1574005Y1644796
X1586065Y1649788
X1584991Y1654796
X1578961Y1649788
X1580035Y1654796
X1574005Y1649788
X1584991Y1627876
X1580035Y1627876
X1586065Y1632884
X1586065Y1637876
X1578961Y1632884
X1578961Y1637876
X1574005Y1632884
X1574005Y1637876
X1580035Y1622884
X1584991Y1622884
X1572931Y1659788
X1567975Y1659788
X1560871Y1659788
X1566901Y1644796
X1561945Y1644796
X1566901Y1649788
X1572931Y1654796
X1567975Y1654796
X1561945Y1649788
X1560871Y1654796
X1567975Y1627876
X1572931Y1627876
X1560871Y1627876
X1566901Y1632884
X1566901Y1637876
X1561945Y1632884
X1561945Y1637876
X1567975Y1622884
X1572931Y1622884
X1560871Y1622884
X1548811Y1659788
X1555915Y1659788
X1543855Y1659788
X1549885Y1644796
X1554841Y1644796
X1549885Y1649788
X1554841Y1649788
X1548811Y1654796
X1555915Y1654796
X1543855Y1654796
X1555915Y1627876
X1548811Y1627876
X1543855Y1627876
X1554841Y1632884
X1549885Y1632884
X1554841Y1637876
X1549885Y1637876
X1555915Y1622884
X1543855Y1622884
X1548811Y1622884
X1536751Y1659788
X1531795Y1659788
X1537825Y1644796
X1542781Y1644796
X1530721Y1644796
X1537825Y1649788
X1542781Y1649788
X1536751Y1654796
X1530721Y1649788
X1531795Y1654796
X1536751Y1627876
X1531795Y1627876
X1542781Y1632790
X1537825Y1632790
X1542781Y1637876
X1537825Y1637876
X1530721Y1632884
X1530721Y1637876
X1531795Y1622884
X1536751Y1622884
X1519735Y1659788
X1524991Y1659788
X1525765Y1644796
X1518661Y1644796
X1525765Y1649788
X1519735Y1654796
X1524691Y1654796
X1518661Y1649788
X1524691Y1627876
X1519735Y1627876
X1525765Y1632884
X1525765Y1637876
X1518661Y1632884
X1518661Y1637876
X1519735Y1622884
X1524691Y1622884
X1507675Y1659788
X1500571Y1659788
X1506601Y1644796
X1513705Y1644796
X1501645Y1644796
X1506601Y1649788
X1513705Y1649788
X1512631Y1654796
X1507675Y1654796
X1501645Y1649788
X1500571Y1654796
X1507675Y1627876
X1512631Y1627876
X1500571Y1627876
X1513705Y1632884
X1513705Y1637876
X1506601Y1632884
X1506601Y1637876
X1501645Y1632884
X1501645Y1637876
X1507675Y1622884
X1512631Y1622884
X1500571Y1622884
X1495615Y1659788
X1488511Y1659788
X1494541Y1644796
X1489585Y1644796
X1494541Y1649788
X1489585Y1649788
X1495615Y1654796
X1488511Y1654796
X1495615Y1627876
X1488511Y1627876
X1489585Y1632884
X1494541Y1632884
X1489585Y1637876
X1494541Y1637876
X1495615Y1622884
X1488511Y1622884
X1483555Y1659788
X1476451Y1659788
X1471495Y1659788
X1482481Y1644796
X1477525Y1644796
X1470421Y1644796
X1477525Y1649788
X1482481Y1649788
X1483555Y1654796
X1476451Y1654796
X1470421Y1649788
X1471495Y1654796
X1476451Y1627876
X1483555Y1627876
X1471495Y1627876
X1477525Y1632884
X1482481Y1632884
X1477525Y1637876
X1482481Y1637876
X1470421Y1637876
X1470421Y1632884
X1483555Y1622884
X1471495Y1622884
X1476451Y1622884
X1464391Y1659788
X1465465Y1644796
X1465465Y1649788
X1464391Y1654796
X1464391Y1627876
X1459435Y1627876
X1465465Y1632884
X1465465Y1637876
X1459435Y1622884
X1464391Y1622884
X1381117Y1659788
X1387147Y1644796
X1382191Y1644796
X1387147Y1649788
X1382191Y1649788
X1381117Y1654796
X1381117Y1627876
X1387147Y1632884
X1382191Y1632884
X1387147Y1637876
X1382191Y1637876
X1381117Y1622884
X1376161Y1659788
X1369057Y1659788
X1375087Y1644796
X1370131Y1644796
X1375087Y1649788
X1376161Y1654796
X1370131Y1649788
X1369057Y1654796
X1376161Y1627876
X1369057Y1627876
X1375087Y1632790
X1375087Y1637876
X1370131Y1632790
X1370131Y1637876
X1376161Y1622884
X1369057Y1622884
X1364101Y1659788
X1356997Y1659788
X1352041Y1659788
X1363027Y1644796
X1350967Y1644796
X1358071Y1644796
X1363027Y1649788
X1364101Y1654796
X1350967Y1649788
X1358071Y1649788
X1356997Y1654796
X1352041Y1654796
X1364101Y1627876
X1352041Y1627876
X1356997Y1627876
X1363027Y1632884
X1363027Y1637876
X1358071Y1632884
X1358071Y1637876
X1350967Y1632884
X1350967Y1637876
X1364101Y1622884
X1356997Y1622884
X1352041Y1622884
X1344937Y1659788
X1339981Y1659788
X1346011Y1644796
X1338907Y1644796
X1346011Y1649788
X1344937Y1654796
X1338907Y1649788
X1339981Y1654796
X1344937Y1627876
X1339981Y1627876
X1346011Y1632884
X1346011Y1637876
X1338907Y1632884
X1338907Y1637876
X1344937Y1622884
X1339981Y1622884
X1332877Y1659788
X1327921Y1659788
X1320817Y1659788
X1333951Y1644796
X1321891Y1644796
X1326847Y1644796
X1333951Y1649788
X1332877Y1654796
X1321891Y1649788
X1326847Y1649788
X1327921Y1654796
X1320817Y1654796
X1332877Y1627876
X1320817Y1627876
X1327921Y1627876
X1333951Y1632884
X1333951Y1637876
X1326847Y1632884
X1321891Y1632884
X1326847Y1637876
X1321891Y1637876
X1332877Y1622884
X1320817Y1622884
X1327921Y1622884
X1315861Y1659788
X1308757Y1659788
X1314787Y1644796
X1309831Y1644796
X1314787Y1649788
X1315861Y1654796
X1309831Y1649788
X1308757Y1654796
X1315861Y1627876
X1308757Y1627876
X1314787Y1632884
X1314787Y1637876
X1309831Y1632884
X1309831Y1637876
X1315861Y1622884
X1308757Y1622884
X1303801Y1659788
X1296697Y1659788
X1291741Y1659788
X1302727Y1644796
X1290667Y1644796
X1297771Y1644796
X1302727Y1649788
X1303801Y1654796
X1290667Y1649788
X1297771Y1649788
X1296697Y1654796
X1291741Y1654796
X1303801Y1627876
X1291741Y1627876
X1296697Y1627876
X1302727Y1632884
X1302727Y1637876
X1297771Y1632884
X1297771Y1637876
X1290667Y1632884
X1290667Y1637876
X1303801Y1622884
X1296697Y1622884
X1291741Y1622884
X1284637Y1659788
X1279681Y1659788
X1285711Y1644796
X1278607Y1644796
X1285711Y1649788
X1284637Y1654796
X1278607Y1649788
X1279681Y1654796
X1284637Y1627876
X1279681Y1627876
X1285711Y1632884
X1285711Y1637876
X1278607Y1632790
X1278607Y1637876
X1284637Y1622884
X1279681Y1622884
X1272577Y1659788
X1267621Y1659788
X1260517Y1659788
X1273651Y1644796
X1261591Y1644796
X1266547Y1644796
X1273651Y1649788
X1272577Y1654796
X1261591Y1649788
X1266547Y1649788
X1267621Y1654796
X1260517Y1654796
X1272577Y1627876
X1260517Y1627876
X1267621Y1627876
X1273651Y1632790
X1273651Y1637876
X1266547Y1632884
X1261591Y1632884
X1266547Y1637876
X1261591Y1637876
X1272577Y1622884
X1260517Y1622884
X1267621Y1622884
X1255561Y1659788
X1248657Y1659588
X1249531Y1644796
X1254487Y1644796
X1255561Y1654796
X1249531Y1649788
X1254487Y1649788
X1248457Y1654796
X1255561Y1627876
X1248457Y1627876
X1249531Y1632884
X1249531Y1637876
X1254487Y1632884
X1254487Y1637876
X1255561Y1622884
X1248457Y1622884
X1243501Y1659788
X1236397Y1659788
X1231441Y1659788
X1242427Y1644796
X1237471Y1644796
X1242427Y1649788
X1243501Y1654796
X1237471Y1649788
X1236397Y1654796
X1231441Y1654796
X1243501Y1627876
X1231441Y1627876
X1236397Y1627876
X1242427Y1632884
X1242427Y1637876
X1237471Y1632884
X1237471Y1637876
X1243501Y1622884
X1236397Y1622884
X1231441Y1622884
X1219381Y1659788
X1224337Y1659788
X1230367Y1644796
X1225411Y1644796
X1218307Y1644796
X1230367Y1649788
X1225411Y1649788
X1218307Y1649788
X1219381Y1654796
X1224337Y1654796
X1224337Y1627876
X1219381Y1627876
X1225411Y1632884
X1230367Y1632884
X1225411Y1637876
X1230367Y1637876
X1218307Y1632884
X1218307Y1637876
X1224337Y1622884
X1219381Y1622884
X1212277Y1659788
X1207321Y1659788
X1213351Y1644796
X1201291Y1644796
X1206247Y1644796
X1213351Y1649788
X1212277Y1654796
X1201291Y1649788
X1206247Y1649788
X1207321Y1654796
X1212277Y1627876
X1207321Y1627876
X1213351Y1632884
X1213351Y1637876
X1206247Y1637876
X1206247Y1632884
X1201291Y1632884
X1201291Y1637876
X1212277Y1622884
X1207321Y1622884
X1195261Y1659788
X1200217Y1659788
X1195261Y1654796
X1200217Y1654796
X1200217Y1627876
X1195261Y1627876
X1200217Y1622884
X1195261Y1622884
X0637417Y1621796
X0638491Y1616788
X0637417Y1626788
X0643447Y1616788
X0638491Y1611796
X0643447Y1611796
X0638491Y1604876
X0643447Y1604876
X0638491Y1599884
X0643447Y1599884
X0637417Y1594876
X0637417Y1589884
X0625357Y1626788
X0620401Y1626788
X0625357Y1621796
X0620401Y1621796
X0626431Y1616788
X0632461Y1621796
X0632461Y1626788
X0631387Y1616788
X0626431Y1604876
X0626431Y1599790
X0626431Y1611796
X0631387Y1604876
X0631387Y1599790
X0631387Y1611796
X0625357Y1594876
X0620401Y1594876
X0625357Y1589884
X0632461Y1594876
X0608341Y1626788
X0613297Y1626788
X0608341Y1621796
X0613297Y1621796
X0614371Y1616788
X0607267Y1616788
X0619327Y1616788
X0607267Y1604876
X0607267Y1599884
X0614371Y1604876
X0614371Y1599884
X0614371Y1611796
X0607267Y1611796
X0619327Y1604876
X0619327Y1599884
X0619327Y1611796
X0613297Y1594876
X0608341Y1594876
X0613297Y1589884
X0596281Y1626788
X0596281Y1621796
X0595207Y1616788
X0590251Y1616788
X0601237Y1626788
X0601237Y1621796
X0602311Y1616788
X0590251Y1604876
X0595207Y1604876
X0590251Y1599884
X0595207Y1599884
X0595207Y1611796
X0590251Y1611796
X0602311Y1604876
X0602311Y1599884
X0602311Y1611796
X0596281Y1594876
X0601237Y1594876
X0601237Y1589884
X0577117Y1626788
X0584221Y1626788
X0577117Y1621796
X0584221Y1621796
X0583147Y1616788
X0578191Y1616788
X0589177Y1626788
X0589177Y1621796
X0578191Y1604876
X0583147Y1604876
X0578191Y1599884
X0583147Y1599884
X0583147Y1611796
X0578191Y1611796
X0584221Y1594876
X0577117Y1594876
X0577117Y1589884
X0589177Y1594876
X0589177Y1589884
X0560101Y1626788
X0565057Y1626788
X0560101Y1621796
X0565057Y1621796
X0566131Y1616788
X0572161Y1626788
X0572161Y1621796
X0571087Y1616788
X0566131Y1604876
X0566131Y1599884
X0566131Y1611796
X0571087Y1604876
X0571087Y1599884
X0571087Y1611796
X0565057Y1594876
X0560101Y1594876
X0565057Y1589884
X0572161Y1594876
X0548041Y1621796
X0548041Y1626788
X0552997Y1626788
X0552997Y1621796
X0554071Y1616788
X0546967Y1616788
X0559027Y1616788
X0546967Y1604876
X0546967Y1599884
X0554071Y1604876
X0554071Y1599884
X0554071Y1611796
X0546967Y1611796
X0559027Y1604876
X0559027Y1599884
X0559027Y1611796
X0552997Y1594876
X0548041Y1594876
X0552997Y1589884
X0535981Y1626788
X0535981Y1621796
X0534907Y1616788
X0540937Y1626788
X0540937Y1621796
X0542011Y1616788
X0534907Y1604876
X0534907Y1599790
X0534907Y1611796
X0542011Y1604876
X0542011Y1599884
X0542011Y1611796
X0535981Y1594876
X0540937Y1594876
X0540937Y1589884
X0516817Y1626788
X0523921Y1626788
X0516817Y1621796
X0523921Y1621796
X0522847Y1616788
X0517891Y1616788
X0528877Y1626788
X0528877Y1621796
X0529951Y1616788
X0517891Y1604876
X0522847Y1604876
X0517891Y1599884
X0522847Y1599884
X0522847Y1611796
X0517891Y1611796
X0529951Y1604876
X0529951Y1599790
X0529951Y1611796
X0523921Y1594876
X0516817Y1594876
X0516817Y1589884
X0528877Y1594876
X0528877Y1589884
X0504757Y1626788
X0504757Y1621796
X0510787Y1616788
X0505831Y1616788
X0511861Y1626788
X0511861Y1621796
X0510787Y1604876
X0510787Y1599884
X0505831Y1604876
X0505831Y1599884
X0510787Y1611796
X0505831Y1611796
X0504757Y1594876
X0504757Y1589884
X0511861Y1594876
X0487741Y1626788
X0492697Y1626788
X0487741Y1621796
X0492697Y1621796
X0493771Y1616788
X0486667Y1616788
X0499801Y1626788
X0499801Y1621796
X0498727Y1616788
X0486667Y1604876
X0486667Y1599884
X0493771Y1604876
X0493771Y1599884
X0493771Y1611796
X0486667Y1611796
X0498727Y1604876
X0498727Y1599884
X0498727Y1611796
X0492697Y1594876
X0487741Y1594876
X0492697Y1589884
X0499801Y1594876
X0480637Y1626788
X0475681Y1626788
X0480637Y1621796
X0475681Y1621796
X0474607Y1616788
X0481711Y1616788
X0474607Y1604876
X0474607Y1599884
X0474607Y1611796
X0481711Y1604876
X0481711Y1599884
X0481711Y1611796
X0475681Y1594876
X0480637Y1594876
X0480637Y1589884
X0463621Y1626788
X0463621Y1621796
X0468577Y1626788
X0468577Y1621796
X0469651Y1616788
X0457591Y1616788
X0462547Y1616788
X0469651Y1604876
X0469651Y1599884
X0469651Y1611796
X0457591Y1611796
X0462547Y1611796
X0457591Y1604876
X0462547Y1604876
X0462547Y1599884
X0457591Y1599884
X0456517Y1594876
X0463621Y1594876
X0463621Y1589884
X0456517Y1589884
X0468577Y1594876
X0468577Y1589884
X0451561Y1594876
X0451561Y1589884
X0367214Y1616788
X0374318Y1616788
X0379274Y1616788
X0367214Y1611796
X0374318Y1611796
X0379274Y1611796
X0379274Y1599884
X0374318Y1599884
X0379274Y1604876
X0374318Y1604876
X0367214Y1599790
X0367214Y1604876
X0368288Y1589884
X0373244Y1594876
X0368288Y1594876
X0355154Y1616788
X0362258Y1616788
X0355154Y1611796
X0362258Y1611796
X0362258Y1599790
X0362258Y1604876
X0355154Y1599884
X0355154Y1604876
X0356228Y1589884
X0356228Y1594876
X0361184Y1594876
X0338138Y1616788
X0343094Y1616788
X0350198Y1616788
X0338138Y1611796
X0343094Y1611796
X0350198Y1611796
X0350198Y1599884
X0350198Y1604876
X0343094Y1599884
X0338138Y1599884
X0343094Y1604876
X0338138Y1604876
X0344168Y1589884
X0344168Y1594876
X0337064Y1594876
X0349124Y1594876
X0326078Y1616788
X0331034Y1616788
X0326078Y1611796
X0331034Y1611796
X0331034Y1599884
X0326078Y1599884
X0331034Y1604876
X0326078Y1604876
X0332108Y1589884
X0325004Y1594876
X0332108Y1594876
X0306914Y1616788
X0314018Y1616788
X0318974Y1616788
X0306914Y1611796
X0314018Y1611796
X0318974Y1611796
X0318974Y1599884
X0314018Y1599884
X0318974Y1604876
X0314018Y1604876
X0306914Y1599884
X0306914Y1604876
X0320048Y1589884
X0307988Y1589884
X0312944Y1594876
X0307988Y1594876
X0320048Y1594876
X0294854Y1616788
X0301958Y1616788
X0294854Y1611796
X0301958Y1611796
X0301958Y1599884
X0301958Y1604876
X0294854Y1599884
X0294854Y1604876
X0295928Y1589884
X0295928Y1594876
X0300884Y1594876
X0277838Y1616788
X0282794Y1616788
X0289898Y1616788
X0277838Y1611796
X0282794Y1611796
X0289898Y1611796
X0289898Y1599884
X0289898Y1604876
X0282794Y1599884
X0277838Y1599884
X0282794Y1604876
X0277838Y1604876
X0283868Y1589884
X0283868Y1594876
X0276764Y1594876
X0288824Y1594876
X0265778Y1616788
X0270734Y1616788
X0265778Y1611796
X0270734Y1611796
X0270734Y1599790
X0265778Y1599790
X0270734Y1604876
X0265778Y1604876
X0271808Y1589884
X0264704Y1594876
X0271808Y1594876
X0253718Y1616788
X0258674Y1616788
X0253718Y1611796
X0258674Y1611796
X0258674Y1599884
X0253718Y1599884
X0258674Y1604876
X0253718Y1604876
X0259748Y1589884
X0247688Y1589884
X0252644Y1594876
X0247688Y1594876
X0259748Y1594876
X0234554Y1616788
X0241658Y1616788
X0246614Y1616788
X0234554Y1611796
X0241658Y1611796
X0246614Y1611796
X0241658Y1599884
X0241658Y1604876
X0234554Y1599884
X0234554Y1604876
X0246614Y1599884
X0246614Y1604876
X0235628Y1589884
X0235628Y1594876
X0240584Y1594876
X0222494Y1616788
X0217538Y1616788
X0229598Y1616788
X0222494Y1611796
X0217538Y1611796
X0229598Y1611796
X0229598Y1599884
X0229598Y1604876
X0217538Y1599884
X0222494Y1599884
X0217538Y1604876
X0222494Y1604876
X0223568Y1589884
X0223568Y1594876
X0228524Y1594876
X0205478Y1616788
X0210434Y1616788
X0210434Y1611796
X0205478Y1611796
X0205478Y1599884
X0210434Y1599884
X0205478Y1604876
X0210434Y1604876
X0211508Y1589884
X0216464Y1594876
X0204404Y1594876
X0211508Y1594876
X0193418Y1616788
X0198374Y1616788
X0193418Y1611796
X0198374Y1611796
X0198374Y1604876
X0198374Y1599884
X0193418Y1599884
X0193418Y1604876
X0199448Y1589884
X0187388Y1589884
X0199448Y1594876
X0192344Y1594876
X0187388Y1594876
X0333500Y0578500
X0333500Y0582500
X1086936Y0370532
X0021309Y0395712
X0027309Y0383926
X0908500Y0927500
X0911500Y0931000
X0905000Y0909000
X0909000Y0909000
X0918000Y0928000
X0532000Y0426500
X0929603Y0889000
X0930925Y0860925
X0258470Y0775410
X1330820Y0518265
X1330758Y0521749
X0726720Y0574910
X0742278Y0566667
X1731117Y1705115
X1719149Y1703190
X1703000Y1711759
X1700520Y1716877
X1742120Y1723415
X1739640Y1728533
X1691997Y1708609
X1731117Y1720265
X1680519Y1726825
X1682724Y1717701
X1722149Y1730415
X1683013Y1713684
X1722133Y1725340
X1722149Y1715265
X0548856Y0440452
X0563575Y0448425
X0543500Y0463500
X0544844Y0439701
X0488260Y0418980
X0501500Y0433000
X0636614Y0512597
X0649771Y0505736
X0671500Y0529500
X0449760Y0497240
X0465925Y0489925
X0439500Y0484000
X0310425Y0243925
X0308925Y0260075
X0812500Y0504000
X0817441Y0517941
X0824500Y0514500
X0785000Y0563500
X0794059Y0553559
X0791500Y0560000
X0794425Y0541425
X1414619Y0244450
X0874500Y0328000
X0884740Y0316000
X1632500Y0381500
X1630927Y0398002
X0903941Y0874000
X0916763Y0972343
X0919272Y0989932
X0918500Y0856925
X0917622Y0887545
X1021425Y0404925
X0040000Y0323500
X0036500Y0323500
X0067575Y0287500
X0826665Y0423425
X0377190Y1387697
X0750090Y0072820
X0717342Y0057098
X0464051Y0224799
X0826112Y1269546
X1393179Y1733118
X0462500Y1733500
X1385061Y1721418
X1387620Y1721418
X1384604Y1728318
X1219738Y1731011
X1216738Y1720861
X1207770Y1731011
X1196814Y1726261
X1199294Y1721143
X1112001Y1718991
X1109521Y1724109
X1092030Y1720841
X1092030Y1725991
X0659673Y1722174
X0659673Y1732836
X0662153Y1727718
X0469975Y1724808
X0467416Y1724808
X1382045Y1708038
X1382045Y1712038
X1219738Y1717011
X1216875Y1705826
X1207770Y1717011
X1204447Y1707143
X1196767Y1712261
X1095489Y1708519
X1092030Y1715841
X1388918Y1687878
X1209879Y1700359
X1214954Y1700343
X1204804Y1691375
X1113948Y1714244
X1092980Y1696029
X1089030Y1691229
X1383800Y1685398
X1213072Y1682899
X1207954Y1680419
X0757557Y1684444
X0470309Y1689000
X0372350Y1683284
X1381918Y1667907
X1392068Y1667907
X0947798Y1660762
X0939798Y1660762
X0921289Y1663187
X0923798Y1660762
X0931798Y1660762
X0755408Y1672381
X0762030Y1668583
X0751030Y1668583
X0751521Y1659158
X0399824Y1667120
X0389824Y1667120
X0394824Y1667120
X0385502Y1667154
X0979708Y1659375
X0976948Y1659375
X0979658Y1662015
X0976898Y1662015
X0979618Y1656185
X0976858Y1656185
X0957758Y1656185
X0960518Y1656185
X0957798Y1662015
X0960558Y1662015
X0960608Y1659375
X0988078Y1656105
X0985318Y1656105
X0988168Y1659295
X0985408Y1659295
X0988118Y1661935
X0985358Y1661935
X1007178Y1656105
X1004418Y1656105
X1004458Y1661935
X1004508Y1659295
X1007218Y1661935
X1007268Y1659295
X0957848Y1659375
X0761510Y1638434
X0749261Y1628208
X0466041Y1664913
X0428500Y1650000
X0387325Y1627212
X0722876Y1611343
X0699610Y1580523
X0945195Y1459453
X0958383Y1462447
X0939507Y1462497
X0953630Y1456760
X0956693Y1459805
X0936693Y1462328
X0811767Y1388154
X0811272Y1382752
X1603507Y1306262
X1605447Y1288748
X1594539Y1295288
X1583007Y1288958
X1586835Y1271918
X1568660Y1283460
X1653197Y1255453
X1623496Y1255453
X1553811Y1264488
X1547062Y1258468
X1193969Y1255453
X1164268Y1255453
X0677055Y1255454
X0647354Y1255454
X0605771Y1267098
X0571271Y1259488
X0217827Y1255454
X0188126Y1255454
X1669339Y1252107
X1669339Y1245414
X1658647Y1242067
X1653197Y1248760
X1639638Y1252107
X1639638Y1245414
X1623496Y1248760
X1628946Y1242067
X1540850Y1240863
X1210111Y1252107
X1210111Y1245414
X1199419Y1242067
X1193969Y1248760
X1180410Y1252107
X1180410Y1245414
X1164268Y1248760
X1169718Y1242067
X0693197Y1252108
X0693197Y1245415
X0682505Y1242068
X0677055Y1248761
X0663496Y1252108
X0663496Y1245415
X0652804Y1242068
X0647354Y1248761
X0561580Y1242740
X0233969Y1252108
X0233969Y1245415
X0217827Y1248761
X0223277Y1242068
X0204268Y1252108
X0204268Y1245415
X0188126Y1248761
X0193576Y1242068
X1663889Y1238721
X1663889Y1228681
X1673739Y1233701
X1653197Y1225335
X1658647Y1232028
X1657597Y1237048
X1634188Y1238721
X1634188Y1228681
X1644038Y1233701
X1623496Y1225335
X1628946Y1232028
X1627896Y1237048
X1540227Y1227648
X1531227Y1227648
X1204661Y1238721
X1204661Y1228681
X1205711Y1233701
X1199419Y1232028
X1193969Y1225335
X1189569Y1237048
X1174960Y1228681
X1174960Y1238721
X1176010Y1233701
X1164268Y1225335
X1169718Y1232028
X1159868Y1237048
X0697597Y1233702
X0687747Y1228682
X0687747Y1238722
X0682505Y1232029
X0681455Y1237049
X0677055Y1225336
X0667896Y1233702
X0658046Y1228682
X0658046Y1238722
X0652804Y1232029
X0651754Y1237049
X0647354Y1225336
X0217827Y1225336
X0228519Y1238722
X0223277Y1232029
X0228519Y1228682
X0229569Y1233702
X0213427Y1237049
X0188126Y1225336
X0198818Y1238722
X0193576Y1232029
X0198818Y1228682
X0199868Y1233702
X0183726Y1237049
X1669339Y1221988
X1669339Y1215296
X1653197Y1218642
X1653197Y1211949
X1639638Y1221988
X1639638Y1215296
X1623496Y1218642
X1623496Y1211949
X1549877Y1221288
X1326433Y1214334
X1336861Y1222119
X1331202Y1211488
X1329477Y1222158
X1210111Y1221988
X1210111Y1215296
X1193969Y1218642
X1193969Y1211949
X1180410Y1221988
X1180410Y1215296
X1164268Y1218642
X1164268Y1211949
X0693197Y1221989
X0693197Y1215297
X0677055Y1218643
X0677055Y1211950
X0663496Y1221989
X0663496Y1215297
X0647354Y1218643
X0647354Y1211950
X0352943Y1214510
X0233969Y1221989
X0233969Y1215297
X0217827Y1218643
X0217827Y1211950
X0204268Y1221989
X0204268Y1215297
X0188126Y1218643
X0188126Y1211950
X1669339Y1208603
X1663889Y1201910
X1673739Y1196890
X1658647Y1195217
X1658647Y1205256
X1657597Y1200237
X1639638Y1208603
X1634188Y1201910
X1644038Y1196890
X1628946Y1205256
X1628946Y1195217
X1627896Y1200237
X1210111Y1208603
X1204661Y1201910
X1205711Y1196890
X1199419Y1205256
X1199419Y1195217
X1189569Y1200237
X1180410Y1208603
X1174960Y1201910
X1176010Y1196890
X1169718Y1195217
X1169718Y1205256
X1159868Y1200237
X0697597Y1196891
X0693197Y1208604
X0687747Y1201911
X0682505Y1195218
X0682505Y1205257
X0681455Y1200238
X0667896Y1196891
X0663496Y1208604
X0658046Y1201911
X0652804Y1195218
X0652804Y1205257
X0651754Y1200238
X0367836Y1209506
X0367782Y1199648
X0233969Y1208604
X0223277Y1195218
X0223277Y1205257
X0228519Y1201911
X0229569Y1196891
X0204268Y1208604
X0213427Y1200238
X0193576Y1195218
X0193576Y1205257
X0198818Y1201911
X0199868Y1196891
X0183726Y1200238
X1669339Y1185177
X1663889Y1191870
X1653197Y1181831
X1653197Y1188524
X1639638Y1185177
X1634188Y1191870
X1623496Y1188524
X1623496Y1181831
X1210111Y1185177
X1204661Y1191870
X1193969Y1188524
X1193969Y1181831
X1180410Y1185177
X1174960Y1191870
X1164268Y1188524
X1164268Y1181831
X0693197Y1185178
X0687747Y1191871
X0677055Y1188525
X0677055Y1181832
X0663496Y1185178
X0658046Y1191871
X0647354Y1188525
X0647354Y1181832
X0378083Y1184949
X0364457Y1188109
X0364788Y1193918
X0233969Y1185178
X0217827Y1188525
X0217827Y1181832
X0228519Y1191871
X0204268Y1185178
X0188126Y1188525
X0188126Y1181832
X0198818Y1191871
X1669339Y1178485
X1669339Y1171792
X1653197Y1175138
X1658647Y1168445
X1639638Y1178485
X1639638Y1171792
X1623496Y1175138
X1628946Y1168445
X1338142Y1181642
X1337975Y1177999
X1210111Y1178485
X1210111Y1171792
X1193969Y1175138
X1199419Y1168445
X1180410Y1178485
X1180410Y1171792
X1164268Y1175138
X1169718Y1168445
X0693197Y1178486
X0693197Y1171793
X0682505Y1168446
X0677055Y1175139
X0663496Y1178486
X0663496Y1171793
X0652804Y1168446
X0647354Y1175139
X0233969Y1178486
X0233969Y1171793
X0217827Y1175139
X0223277Y1168446
X0204268Y1178486
X0204268Y1171793
X0188126Y1175139
X0193576Y1168446
X1663889Y1165099
X1663889Y1155059
X1673739Y1160079
X1653197Y1151713
X1658647Y1158406
X1657597Y1163426
X1634188Y1165099
X1634188Y1155059
X1644038Y1160079
X1623496Y1151713
X1628946Y1158406
X1627896Y1163426
X1494386Y1178743
X1504470Y1178265
X1513470Y1178265
X1534317Y1216828
X1555303Y1242557
X1555367Y1248078
X1555570Y1235968
X1549877Y1217288
X1564267Y1253158
X1581327Y1252858
X1575370Y1252770
X1590097Y1246768
X1589557Y1252778
X1204661Y1165099
X1204661Y1155059
X1205711Y1160079
X1193969Y1151713
X1199419Y1158406
X1189569Y1163426
X1174960Y1165099
X1174960Y1155059
X1176010Y1160079
X1164268Y1151713
X1169718Y1158406
X1159868Y1163426
X0697597Y1160080
X0687747Y1165100
X0687747Y1155060
X0682505Y1158407
X0681455Y1163427
X0677055Y1151714
X0667896Y1160080
X0658046Y1165100
X0658046Y1155060
X0652804Y1158407
X0651754Y1163427
X0647354Y1151714
X0551171Y1167678
X0583630Y1255075
X0588630Y1255075
X0578071Y1244425
X0578830Y1238075
X0585501Y1229536
X0578830Y1218588
X0595947Y1258575
X0603947Y1258575
X0599659Y1241734
X0595598Y1251075
X0595671Y1245688
X0594330Y1238075
X0592761Y1220688
X0612447Y1258575
X0609159Y1240234
X0612947Y1252075
X0612871Y1248488
X0217827Y1151714
X0228519Y1165100
X0223277Y1158407
X0228519Y1155060
X0229569Y1160080
X0213427Y1163427
X0188126Y1151714
X0198818Y1165100
X0193576Y1158407
X0198818Y1155060
X0199868Y1160080
X0183726Y1163427
X1669339Y1148366
X1669339Y1141674
X1653197Y1145020
X1653197Y1138327
X1639638Y1148366
X1639638Y1141674
X1623496Y1145020
X1623496Y1138327
X1210111Y1148366
X1210111Y1141674
X1193969Y1145020
X1193969Y1138327
X1180410Y1148366
X1180410Y1141674
X1164268Y1145020
X1164268Y1138327
X0693197Y1148367
X0693197Y1141675
X0677055Y1145021
X0677055Y1138328
X0663496Y1148367
X0663496Y1141675
X0647354Y1145021
X0647354Y1138328
X0233969Y1148367
X0233969Y1141675
X0217827Y1145021
X0217827Y1138328
X0204268Y1148367
X0204268Y1141675
X0188126Y1145021
X0188126Y1138328
X1669339Y1134981
X1663889Y1128288
X1673739Y1123268
X1658647Y1131634
X1658647Y1121595
X1657597Y1126615
X1639638Y1134981
X1634188Y1128288
X1644038Y1123268
X1628946Y1131634
X1628946Y1121595
X1627896Y1126615
X1210111Y1134981
X1204661Y1128288
X1205711Y1123268
X1199419Y1131634
X1199419Y1121595
X1189569Y1126615
X1180410Y1134981
X1174960Y1128288
X1176010Y1123268
X1169718Y1131634
X1169718Y1121595
X1159868Y1126615
X0697597Y1123269
X0693197Y1134982
X0687747Y1128289
X0682505Y1131635
X0682505Y1121596
X0681455Y1126616
X0667896Y1123269
X0663496Y1134982
X0658046Y1128289
X0652804Y1131635
X0652804Y1121596
X0651754Y1126616
X0233969Y1134982
X0223277Y1131635
X0228519Y1128289
X0223277Y1121596
X0229569Y1123269
X0204268Y1134982
X0213427Y1126616
X0193576Y1131635
X0198818Y1128289
X0193576Y1121596
X0199868Y1123269
X0183726Y1126616
X1669339Y1111555
X1663889Y1118248
X1653197Y1114902
X1653197Y1108209
X1639638Y1111555
X1634188Y1118248
X1623496Y1114902
X1623496Y1108209
X1210111Y1111555
X1204661Y1118248
X1193969Y1114902
X1193969Y1108209
X1180410Y1111555
X1174960Y1118248
X1164268Y1114902
X1164268Y1108209
X0693197Y1111556
X0687747Y1118249
X0677055Y1114903
X0677055Y1108210
X0663496Y1111556
X0658046Y1118249
X0647354Y1114903
X0647354Y1108210
X0233969Y1111556
X0217827Y1114903
X0217827Y1108210
X0228519Y1118249
X0204268Y1111556
X0188126Y1114903
X0188126Y1108210
X0198818Y1118249
X1669339Y1104862
X1669339Y1098170
X1663889Y1091477
X1653197Y1101516
X1658647Y1094823
X1639638Y1104862
X1639638Y1098170
X1634188Y1091477
X1623496Y1101516
X1628946Y1094823
X1210111Y1104862
X1210111Y1098170
X1204661Y1091477
X1193969Y1101516
X1199419Y1094823
X1180410Y1104862
X1180410Y1098170
X1174960Y1091477
X1164268Y1101516
X1169718Y1094823
X0693197Y1104863
X0693197Y1098171
X0687747Y1091478
X0682505Y1094824
X0677055Y1101517
X0663496Y1104863
X0663496Y1098171
X0658046Y1091478
X0652804Y1094824
X0647354Y1101517
X0233969Y1104863
X0233969Y1098171
X0223277Y1094824
X0228519Y1091478
X0217827Y1101517
X0204268Y1104863
X0204268Y1098171
X0188126Y1101517
X0193576Y1094824
X0198818Y1091478
X1663889Y1081437
X1673739Y1086457
X1653197Y1078091
X1658647Y1084784
X1657597Y1089804
X1634188Y1081437
X1644038Y1086457
X1623496Y1078091
X1628946Y1084784
X1627896Y1089804
X1204661Y1081437
X1205711Y1086457
X1193969Y1078091
X1199419Y1084784
X1189569Y1089804
X1174960Y1081437
X1176010Y1086457
X1164268Y1078091
X1169718Y1084784
X1159868Y1089804
X0697597Y1086458
X0687747Y1081438
X0682505Y1084785
X0681455Y1089805
X0677055Y1078092
X0667896Y1086458
X0658046Y1081438
X0652804Y1084785
X0651754Y1089805
X0647354Y1078092
X0217827Y1078092
X0228519Y1081438
X0223277Y1084785
X0229569Y1086458
X0213427Y1089805
X0188126Y1078092
X0198818Y1081438
X0193576Y1084785
X0199868Y1086458
X0183726Y1089805
X1669339Y1074744
X1669339Y1068051
X1653197Y1071398
X1653197Y1061359
X1639638Y1074744
X1639638Y1068051
X1623496Y1071398
X1623496Y1061359
X1210111Y1074744
X1210111Y1068051
X1193969Y1071398
X1193969Y1061359
X1180410Y1074744
X1180410Y1068051
X1164268Y1071398
X1164268Y1061359
X0693197Y1074745
X0693197Y1068052
X0677055Y1071399
X0677055Y1061360
X0663496Y1074745
X0663496Y1068052
X0647354Y1071399
X0647354Y1061360
X0233969Y1074745
X0233969Y1068052
X0217827Y1071399
X0217827Y1061360
X0204268Y1074745
X0204268Y1068052
X0188126Y1071399
X0188126Y1061360
X1669339Y1058012
X1669339Y1051319
X1653197Y1054666
X1653197Y1047973
X1639638Y1058012
X1639638Y1051319
X1623496Y1054666
X1623496Y1047973
X1417301Y1055140
X1210111Y1058012
X1210111Y1051319
X1193969Y1054666
X1193969Y1047973
X1180410Y1058012
X1180410Y1051319
X1164268Y1054666
X1164268Y1047973
X0693197Y1058013
X0693197Y1051320
X0677055Y1054667
X0663496Y1058013
X0663496Y1051320
X0647354Y1054667
X0647354Y1047974
X0441159Y1055141
X0233969Y1058013
X0233969Y1051320
X0217827Y1054667
X0217827Y1047974
X0204268Y1058013
X0204268Y1051320
X0188126Y1054667
X0188126Y1047974
X1669339Y1044626
R02Y-0006693
X1653197Y1041280
X1653197Y1034587
X1639638Y1044626
R02Y-0006693
X1623496Y1041280
X1623496Y1034587
X1438507Y1032205
X1415426Y1038765
X1415426Y1042765
X1391460Y1032205
X1210111Y1044626
R02Y-0006693
X1193969Y1041280
X1193969Y1034587
X1180410Y1044626
R02Y-0006693
X1164268Y1041280
X1164268Y1034587
X0647354Y1041281
X0647354Y1034588
X0462365Y1032206
X0439284Y1042766
X0439284Y1038766
X0415318Y1032206
X0233969Y1044627
R02Y-0006693
X0217827Y1041281
X0217827Y1034588
X0204268Y1044627
R02Y-0006693
X0188126Y1041281
X0188126Y1034588
X1467926Y1022559
X1467926Y1019016
X1460926Y1022559
X1460926Y1019016
X1453345Y1022559
X1453345Y1019016
X1433614Y1028830
X1426134Y1028830
X1433552Y1023012
X1438507Y1028465
X1433552Y1018878
X1438507Y1017244
X1429874Y1028830
X1438507Y1020985
X1438507Y1024725
X1414458Y1018878
X1422394Y1028830
X1423316Y1018878
X1423316Y1023012
X1414913Y1028830
X1411173Y1028830
X1418653Y1028830
X1414458Y1023012
X1403693Y1028830
X1404615Y1018878
X1395060Y1017244
X1395060Y1028465
X1395060Y1024725
X1395060Y1020985
X1404615Y1023012
X1407433Y1028830
X1399953Y1028830
X1381083Y1019016
X1381083Y1022559
X1366123Y1019016
X1366123Y1022559
X1373603Y1022559
X1373603Y1019016
X0492284Y1022560
X0492284Y1019017
X0484784Y1022560
X0477203Y1022560
X0484784Y1019017
X0477203Y1019017
X0457472Y1028831
X0457410Y1023013
X0462365Y1017245
X0462365Y1024726
X0462365Y1028466
X0457410Y1018879
X0462365Y1020986
X0447174Y1018879
X0442511Y1028831
X0447174Y1023013
X0449992Y1028831
X0453732Y1028831
X0446252Y1028831
X0431291Y1028831
X0428473Y1023013
X0428473Y1018879
X0438316Y1018879
X0435031Y1028831
X0427551Y1028831
X0438316Y1023013
X0438771Y1028831
X0423811Y1028831
X0418918Y1017245
X0418918Y1028466
X0418918Y1020986
X0418918Y1024726
X0397461Y1019017
X0404941Y1022560
X0404941Y1019017
X0397461Y1022560
X0389981Y1019017
X0389981Y1022560
X1669339Y1004469
X1653197Y1004469
X1639638Y1004469
X1623496Y1004469
X1467926Y1015473
X1460926Y1015473
X1453345Y1015473
X1433552Y1014744
X1438507Y1013504
X1438507Y1009764
X1429874Y1009399
X1426134Y1009399
X1433614Y1009399
X1438507Y1006024
X1414458Y1014744
X1423316Y1014744
X1411173Y1009399
X1414913Y1009399
X1422394Y1009399
X1418101Y1001765
X1418653Y1009399
X1404615Y1014744
X1395060Y1013504
X1399953Y1009399
X1407433Y1009399
X1403693Y1009399
X1395060Y1006024
X1395060Y1009764
X1381083Y1015473
R02X-0007480
X1210111Y1004469
X1193969Y1004469
X1180410Y1004469
X1164268Y1004469
X0647354Y1004470
X0492284Y1015474
X0484784Y1015474
X0477203Y1015474
X0462365Y1013505
X0462365Y1009765
X0457410Y1014745
X0462365Y1006025
X0457472Y1009400
X0447174Y1014745
X0441959Y1001766
X0453732Y1009400
X0446252Y1009400
X0449992Y1009400
X0442511Y1009400
X0428473Y1014745
X0438771Y1009400
X0435031Y1009400
X0427551Y1009400
X0438316Y1014745
X0431291Y1009400
X0418918Y1009765
X0423811Y1009400
X0418918Y1013505
X0418918Y1006025
X0404941Y1015474
R02X-0007480
X0233969Y1004470
X0217827Y1004470
X0204268Y1004470
X0188126Y1004470
X1669339Y0997776
X1669339Y0991083
X1653197Y0994429
X1653197Y0987736
X1639638Y0997776
X1639638Y0991083
X1623496Y0994429
X1623496Y0987736
X1418176Y0989765
X1418101Y0993765
X1418101Y0997765
X1210111Y0997776
X1210111Y0991083
X1193969Y0994429
X1193969Y0987736
X1180410Y0997776
X1180410Y0991083
X1164268Y0994429
X1164268Y0987736
X0647354Y0994430
X0647354Y0987737
X0442034Y0989766
X0441959Y0997766
X0441959Y0993766
X0233969Y0997777
X0233969Y0991084
X0217827Y0994430
X0217827Y0987737
X0204268Y0997777
X0204268Y0991084
X0188126Y0994430
X0188126Y0987737
X1669339Y0984390
X1669339Y0977697
X1653197Y0981044
X1653197Y0974351
X1639638Y0984390
X1639638Y0977697
X1623496Y0981044
X1623496Y0974351
X1416301Y0974240
X1416301Y0981740
X1210111Y0984390
X1210111Y0977697
X1193969Y0981044
X1193969Y0974351
X1180410Y0984390
X1180410Y0977697
X1164268Y0981044
X1164268Y0974351
X0647354Y0981045
X0647354Y0974352
X0440159Y0974241
X0440159Y0981741
X0233969Y0984391
X0233969Y0977698
X0217827Y0981045
X0217827Y0974352
X0204268Y0984391
X0204268Y0977698
X0188126Y0981045
X0188126Y0974352
X1669339Y0971004
R02Y-0006693
X1653197Y0967658
X1653197Y0960965
X1639638Y0971004
R02Y-0006693
X1623496Y0967658
X1623496Y0960965
X1416301Y0966740
X1210111Y0971004
R02Y-0006693
X1193969Y0967658
X1193969Y0960965
X1180410Y0971004
R02Y-0006693
X1164268Y0967658
X1164268Y0960965
X0647354Y0967659
X0647354Y0960966
X0440159Y0966741
X0233969Y0971005
R02Y-0006693
X0217827Y0967659
X0217827Y0960966
X0204268Y0971005
R02Y-0006693
X0188126Y0967659
X0188126Y0960966
X1669339Y0950925
X1663889Y0944233
X1653197Y0954272
X1658647Y0947579
X1657597Y0942560
X1639638Y0950925
X1634188Y0944233
X1623496Y0954272
X1628946Y0947579
X1627896Y0942560
X1210111Y0950925
X1204661Y0944233
X1199419Y0947579
X1189569Y0942560
X1193969Y0954272
X1180410Y0950925
X1174960Y0944233
X1164268Y0954272
X1169718Y0947579
X1159868Y0942560
X0647354Y0954273
X0233969Y0950926
X0217827Y0954273
X0223277Y0947580
X0228519Y0944234
X0204268Y0950926
X0213427Y0942561
X0188126Y0954273
X0193576Y0947580
X0198818Y0944234
X0183726Y0942561
X1669339Y0927500
X1663889Y0934193
X1673739Y0939213
X1653197Y0930847
X1658647Y0937540
X1639638Y0927500
X1634188Y0934193
X1644038Y0939213
X1623496Y0930847
X1628946Y0937540
X1210111Y0927500
X1204661Y0934193
X1205711Y0939213
X1193969Y0930847
X1199419Y0937540
X1180410Y0927500
X1174960Y0934193
X1176010Y0939213
X1164268Y0930847
X1169718Y0937540
X0647354Y0930848
X0233969Y0927501
X0217827Y0930848
X0223277Y0937541
X0228519Y0934194
X0229569Y0939214
X0204268Y0927501
X0188126Y0930848
X0193576Y0937541
X0198818Y0934194
X0199868Y0939214
X1669339Y0920807
X1669339Y0914114
X1653197Y0924154
X1653197Y0917461
X1639638Y0920807
X1639638Y0914114
X1623496Y0924154
X1623496Y0917461
X1210111Y0920807
X1210111Y0914114
X1193969Y0924154
X1193969Y0917461
X1180410Y0920807
X1180410Y0914114
X1164268Y0924154
X1164268Y0917461
X0647354Y0924155
X0647354Y0917462
X0233969Y0920808
X0233969Y0914115
X0217827Y0924155
X0217827Y0917462
X0204268Y0920808
X0204268Y0914115
X0188126Y0924155
X0188126Y0917462
X1663889Y0907422
X1663889Y0897382
X1673739Y0902402
X1658647Y0910768
X1658647Y0900729
X1657597Y0905749
X1634188Y0907422
X1634188Y0897382
X1644038Y0902402
X1628946Y0910768
X1628946Y0900729
X1627896Y0905749
X1204661Y0907422
X1204661Y0897382
X1205711Y0902402
X1199419Y0910768
X1199419Y0900729
X1189569Y0905749
X1174960Y0907422
X1174960Y0897382
X1176010Y0902402
X1169718Y0910768
X1169718Y0900729
X1159868Y0905749
X0223277Y0910769
X0228519Y0907423
X0223277Y0900730
X0228519Y0897383
X0229569Y0902403
X0213427Y0905750
X0193576Y0910769
X0198818Y0907423
X0193576Y0900730
X0198818Y0897383
X0199868Y0902403
X0183726Y0905750
X1669339Y0890689
X1669339Y0883996
X1653197Y0894036
X1653197Y0887343
X1639638Y0890689
X1639638Y0883996
X1623496Y0894036
X1623496Y0887343
X1193969Y0894036
X1164268Y0894036
X0647354Y0894037
X0647354Y0887344
X0233969Y0890690
X0233969Y0883997
X0217827Y0894037
X0217827Y0887344
X0204268Y0890690
X0204268Y0883997
X0188126Y0894037
X0188126Y0887344
X1669339Y0877303
X1663889Y0870610
X1653197Y0880650
X1658647Y0873957
X1657597Y0868937
X1639638Y0877303
X1634188Y0870610
X1623496Y0880650
X1628946Y0873957
X1627896Y0868937
X0647354Y0880651
X0233969Y0877304
X0217827Y0880651
X0223277Y0873958
X0228519Y0870611
X0204268Y0877304
X0213427Y0868938
X0188126Y0880651
X0193576Y0873958
X0198818Y0870611
X0183726Y0868938
X1669339Y0853878
X1663889Y0860571
X1673739Y0865591
X1653197Y0857225
X1658647Y0863918
X1639638Y0853878
X1634188Y0860571
X1644038Y0865591
X1623496Y0857225
X1628946Y0863918
X1339347Y0857388
X1330277Y0857388
X0647354Y0857226
X0516572Y0865327
X0506261Y0865338
X0233969Y0853879
X0217827Y0857226
X0223277Y0863919
X0228519Y0860572
X0229569Y0865592
X0204268Y0853879
X0188126Y0857226
X0193576Y0863919
X0198818Y0860572
X0199868Y0865592
X1669339Y0847185
X1669339Y0840492
X1653197Y0850532
X1653197Y0843839
X1639638Y0847185
X1639638Y0840492
X1623496Y0850532
X1623496Y0843839
X1007587Y0844256
X0647354Y0850533
X0647354Y0843840
X0372000Y0849362
X0372000Y0840362
X0372000Y0837862
X0233969Y0847186
X0233969Y0840493
X0217827Y0850533
X0217827Y0843840
X0204268Y0847186
X0204268Y0840493
X0188126Y0850533
X0188126Y0843840
X1663889Y0833799
X1663889Y0823760
X1673739Y0828780
X1658647Y0837146
X1658647Y0827107
X1657597Y0832126
X1634188Y0833799
X1634188Y0823760
X1644038Y0828780
X1628946Y0837146
X1628946Y0827107
X1627896Y0832126
X1501338Y0825147
X1492673Y0828513
X1007587Y0835856
X1007587Y0833356
X1007587Y0824752
X0372000Y0828862
X0372000Y0826362
X0223277Y0827108
X0228519Y0833800
X0228519Y0823761
X0223277Y0837147
X0229569Y0828781
X0213427Y0832127
X0193576Y0837147
X0193576Y0827108
X0198818Y0833800
X0198818Y0823761
X0199868Y0828781
X0183726Y0832127
X1669339Y0817067
X1669339Y0810374
X1653197Y0820414
X1653197Y0813721
X1639638Y0817067
X1639638Y0810374
X1623496Y0820414
X1623496Y0813721
X1501730Y0811872
X1498177Y0817013
X1478177Y0817013
X1278677Y0808988
X1007587Y0822252
X1007587Y0813852
X1007587Y0811352
X0951839Y0812730
X0906387Y0818471
X0647354Y0820415
X0647354Y0813722
X0586000Y0808862
X0384499Y0819862
X0384500Y0810862
X0372000Y0816862
X0233969Y0817068
X0233969Y0810375
X0217827Y0820415
X0217827Y0813722
X0204268Y0817068
X0204268Y0810375
X0188126Y0820415
X0188126Y0813722
X1669339Y0803681
X1663889Y0796988
X1653197Y0807028
X1658647Y0800335
X1657597Y0795315
X1639638Y0803681
X1634188Y0796988
X1623496Y0807028
X1628946Y0800335
X1627896Y0795315
X1584849Y0793506
X1569518Y0806684
X1499243Y0803513
X1489177Y0803488
X1477177Y0803488
X1007587Y0802884
X1007587Y0800384
X0647354Y0807029
X0606559Y0796116
X0592612Y0805986
X0597071Y0799268
X0233969Y0803682
X0217827Y0807029
X0223277Y0800336
X0228519Y0796989
X0204268Y0803682
X0213427Y0795316
X0188126Y0807029
X0193576Y0800336
X0198818Y0796989
X0183726Y0795316
X1669339Y0780256
X1663889Y0786949
X1673739Y0791969
X1653197Y0783603
X1658647Y0790296
X1639638Y0780256
X1634188Y0786949
X1644038Y0791969
X1623496Y0783603
X1628946Y0790296
X1246748Y0785752
X1007587Y0791984
X1007587Y0789484
X1007587Y0778380
X1007587Y0780880
X0647354Y0783604
X0616171Y0780364
X0613761Y0790418
X0233969Y0780257
X0217827Y0783604
X0223277Y0790297
X0228519Y0786950
X0229569Y0791970
X0204268Y0780257
X0188126Y0783604
X0193576Y0790297
X0198818Y0786950
X0199868Y0791970
X1788142Y0773563
X1783592Y0763765
X1776550Y0767265
X1758442Y0773563
X1753892Y0763765
X1746850Y0767265
X1728741Y0773563
X1724191Y0763765
X1717149Y0767265
X1699040Y0773563
X1694490Y0763765
X1687448Y0767265
X1688348Y0790296
X1682898Y0783603
X1682898Y0776910
X1682898Y0813721
X1682898Y0820414
X1682898Y0807028
X1688348Y0800335
X1687298Y0795315
X1682898Y0843839
X1682898Y0850532
X1688348Y0837146
X1687298Y0832126
X1688348Y0827107
X1682898Y0857225
X1688348Y0863918
X1682898Y0887343
X1682898Y0894036
X1682898Y0880650
X1688348Y0873957
X1687298Y0868937
X1682898Y0924154
X1682898Y0917461
X1688348Y0900729
X1688348Y0910768
X1687298Y0905749
X1682898Y0954272
X1688348Y0947579
X1687298Y0942560
X1688348Y0937540
X1682898Y0930847
X1682898Y0974351
X1682898Y0981044
X1682898Y0960965
X1682898Y0967658
X1682898Y1004469
X1682898Y0987736
X1682898Y0994429
X1682898Y1071398
X1682898Y1061359
X1682898Y1047973
X1682898Y1054666
X1682898Y1034587
X1682898Y1041280
X1682898Y1114902
R02Y-0006693
X1688348Y1094823
X1688348Y1084784
X1687298Y1089804
X1682898Y1078091
X1687298Y1163426
X1682898Y1151713
X1688348Y1158406
X1682898Y1145020
X1682898Y1138327
X1687298Y1126615
X1688348Y1121595
X1688348Y1131634
X1688348Y1195217
X1687298Y1200237
X1688348Y1205256
X1682898Y1181831
X1682898Y1188524
X1682898Y1175138
X1688348Y1168445
X1682898Y1255453
X1688348Y1242067
X1682898Y1248760
X1688348Y1232028
X1687298Y1237048
X1682898Y1225335
R02Y-0006693
X1693590Y0786949
X1699040Y0780256
X1703440Y0791969
X1699040Y0810374
X1699040Y0817067
X1693590Y0796988
X1699040Y0803681
X1699040Y0840492
X1699040Y0847185
X1693590Y0833799
X1703440Y0828780
X1693590Y0823760
X1703440Y0865591
X1693590Y0860571
X1699040Y0853878
X1693590Y0897382
X1703440Y0902402
X1693590Y0907422
X1699040Y0890689
R02Y-0006693
X1693590Y0870610
X1699040Y0920807
X1699040Y0914114
X1699040Y0957618
X1699040Y0971004
X1699040Y0964311
X1699040Y0950925
X1693590Y0944233
X1703440Y0939213
X1699040Y0927500
X1693590Y0934193
X1699040Y0991083
X1699040Y0997776
X1699040Y0984390
X1699040Y0977697
X1699040Y1031240
R02Y0006693
X1699040Y1004469
X1693590Y1081437
X1703440Y1086457
X1699040Y1068051
X1699040Y1074744
X1699040Y1051319
X1699040Y1058012
X1693590Y1128288
X1703440Y1123268
X1699040Y1134981
X1693590Y1118248
X1699040Y1111555
X1699040Y1098170
X1699040Y1104862
X1693590Y1091477
X1699040Y1178485
X1699040Y1171792
X1703440Y1160079
X1693590Y1165099
X1693590Y1155059
X1699040Y1148366
X1699040Y1141674
X1699040Y1215296
X1699040Y1221988
X1699040Y1208603
X1703440Y1196890
X1693590Y1201910
X1699040Y1185177
X1693590Y1191870
X1699040Y1252107
X1699040Y1245414
X1703440Y1233701
X1693590Y1238721
X1693590Y1228681
X1712599Y0776910
X1718049Y0800335
X1716999Y0795315
X1712599Y0783603
X1718049Y0790296
X1712599Y0813721
X1712599Y0820414
X1712599Y0807028
X1712599Y0843839
X1712599Y0850532
X1718049Y0837146
X1716999Y0832126
X1718049Y0827107
X1718049Y0873957
X1712599Y0880650
X1716999Y0868937
X1712599Y0857225
X1718049Y0863918
X1718049Y0900729
X1718049Y0910768
X1716999Y0905749
X1712599Y0887343
X1712599Y0894036
X1718049Y0937540
X1712599Y0930847
R02Y-0006693
X1712599Y0960965
X1712599Y0967658
X1712599Y0954272
X1718049Y0947579
X1716999Y0942560
X1712599Y0987736
X1712599Y0994429
X1712599Y0974351
X1712599Y0981044
X1712599Y1047973
X1712599Y1054666
X1712599Y1034587
X1712599Y1041280
X1712599Y1004469
X1712599Y1101516
X1718049Y1094823
X1718049Y1084784
X1716999Y1089804
X1712599Y1078091
X1712599Y1071398
X1712599Y1061359
X1712599Y1145020
X1712599Y1138327
X1716999Y1126615
X1718049Y1121595
X1718049Y1131634
X1712599Y1114902
X1712599Y1108209
X1716999Y1200237
X1718049Y1205256
X1712599Y1181831
X1712599Y1188524
X1712599Y1175138
X1718049Y1168445
X1716999Y1163426
X1712599Y1151713
X1718049Y1158406
X1712599Y1255453
X1718049Y1242067
X1712599Y1248760
X1718049Y1232028
X1716999Y1237048
X1712599Y1225335
X1712599Y1211949
X1712599Y1218642
X1718049Y1195217
X1723291Y0796988
X1728741Y0803681
X1728741Y0780256
X1723291Y0786949
X1733141Y0791969
X1723291Y0833799
X1723291Y0823760
X1733141Y0828780
X1728741Y0810374
X1728741Y0817067
X1723291Y0860571
X1733141Y0865591
X1728741Y0853878
X1728741Y0840492
X1728741Y0847185
X1723291Y0897382
X1733141Y0902402
X1723291Y0907422
X1728741Y0890689
R02Y-0006693
X1723291Y0870610
X1733141Y0939213
X1728741Y0927500
X1723291Y0934193
X1728741Y0920807
X1728741Y0914114
X1728741Y0957618
X1728741Y0971004
X1728741Y0964311
X1728741Y0950925
X1723291Y0944233
X1728741Y1004469
X1728741Y0991083
X1728741Y0997776
X1728741Y0984390
X1728741Y0977697
X1728741Y1051319
X1728741Y1058012
X1728741Y1031240
X1728741Y1037933
X1728741Y1044626
X1728741Y1098170
X1728741Y1104862
X1723291Y1091477
X1723291Y1081437
X1733141Y1086457
X1728741Y1068051
X1728741Y1074744
X1728741Y1148366
X1728741Y1141674
X1723291Y1128288
X1733141Y1123268
X1728741Y1134981
X1723291Y1118248
X1728741Y1111555
X1728741Y1185177
X1723291Y1191870
X1728741Y1178485
X1728741Y1171792
X1723291Y1165099
X1733141Y1160079
X1723291Y1155059
X1723291Y1238721
X1723291Y1228681
X1733141Y1233701
X1728741Y1215296
X1728741Y1221988
X1728741Y1208603
X1733141Y1196890
X1723291Y1201910
X1728741Y1252107
X1728741Y1245414
X1747750Y0790296
X1742300Y0783603
X1742300Y0776910
X1742300Y0813721
X1742300Y0820414
X1742300Y0807028
X1747750Y0800335
X1746700Y0795315
X1742300Y0843839
X1742300Y0850532
X1747750Y0837146
X1746700Y0832126
X1747750Y0827107
X1742300Y0880650
X1747750Y0873957
X1746700Y0868937
X1742300Y0857225
X1747750Y0863918
X1747750Y0900729
X1747750Y0910768
X1746700Y0905749
X1742300Y0887343
X1742300Y0894036
X1747750Y0937540
X1742300Y0930847
R02Y-0006693
X1742300Y0967658
X1742300Y0954272
X1747750Y0947579
X1746700Y0942560
X1742300Y0987736
X1742300Y0994429
X1742300Y0974351
X1742300Y0981044
X1742300Y0960965
X1742300Y1034587
X1742300Y1041280
X1742300Y1004469
X1747750Y1084784
X1746700Y1089804
X1742300Y1078091
X1742300Y1071398
X1742300Y1061359
X1742300Y1047973
X1742300Y1054666
X1742300Y1114902
X1742300Y1108209
X1742300Y1101516
X1747750Y1094823
X1742300Y1145020
X1742300Y1138327
X1746700Y1126615
X1747750Y1121595
X1747750Y1131634
X1746700Y1163426
X1742300Y1151713
X1747750Y1158406
X1742300Y1181831
X1742300Y1188524
X1742300Y1175138
X1747750Y1168445
X1742300Y1211949
X1742300Y1218642
X1747750Y1195217
X1746700Y1200237
X1747750Y1205256
X1742300Y1255453
X1747750Y1242067
X1742300Y1248760
X1747750Y1232028
X1746700Y1237048
X1742300Y1225335
X1752992Y0796988
X1758442Y0780256
X1752992Y0786949
X1762842Y0791969
X1762842Y0828780
X1752992Y0833799
X1752992Y0823760
X1758442Y0810374
X1758442Y0817067
X1758442Y0803681
X1762842Y0865591
X1758442Y0853878
X1752992Y0860571
X1758442Y0840492
X1758442Y0847185
X1758442Y0890689
R02Y-0006693
X1752992Y0870610
X1758442Y0920807
X1758442Y0914114
X1762842Y0902402
X1752992Y0897382
X1752992Y0907422
X1758442Y0957618
X1758442Y0971004
X1758442Y0964311
X1758442Y0950925
X1752992Y0944233
X1762842Y0939213
X1758442Y0927500
X1752992Y0934193
X1758442Y1004469
X1758442Y0991083
X1758442Y0997776
X1758442Y0984390
X1758442Y0977697
X1758442Y1031240
X1758442Y1037933
X1758442Y1044626
X1758442Y1068051
X1758442Y1074744
X1758442Y1051319
X1758442Y1058012
X1758442Y1111555
X1752992Y1118248
X1758442Y1098170
X1758442Y1104862
X1752992Y1091477
X1762842Y1086457
X1752992Y1081437
X1758442Y1148366
X1758442Y1141674
X1762842Y1123268
X1752992Y1128288
X1758442Y1134981
X1758442Y1178485
X1758442Y1171792
X1762842Y1160079
X1752992Y1165099
X1752992Y1155059
X1758442Y1208603
X1762842Y1196890
X1752992Y1201910
X1758442Y1185177
X1752992Y1191870
X1758442Y1252107
X1758442Y1245414
X1762842Y1233701
X1752992Y1238721
X1752992Y1228681
X1758442Y1215296
X1758442Y1221988
X1772000Y0783603
X1777450Y0790296
X1772000Y0776910
X1772000Y0820414
X1772000Y0813721
X1777450Y0800335
X1776400Y0795315
X1772000Y0807028
X1772000Y0843839
X1772000Y0850532
X1777450Y0837146
X1776400Y0832126
X1777450Y0827107
X1777450Y0873957
X1772000Y0880650
X1776400Y0868937
X1777450Y0863918
X1772000Y0857225
X1777450Y0900729
X1777450Y0910768
X1776400Y0905749
X1772000Y0887343
X1772000Y0894036
X1777450Y0937540
X1772000Y0930847
R02Y-0006693
X1772000Y0974351
X1772000Y0981044
X1772000Y0960965
X1772000Y0967658
X1772000Y0954272
X1777450Y0947579
X1776400Y0942560
X1772000Y1004469
X1772000Y0987736
X1772000Y0994429
X1772000Y1071398
X1772000Y1061359
R02Y-0006693
X1772000Y1034587
X1772000Y1041280
X1772000Y1101516
X1777450Y1094823
X1777450Y1084784
X1776400Y1089804
X1772000Y1078091
X1776400Y1126615
X1777450Y1121595
X1777450Y1131634
X1772000Y1114902
X1772000Y1108209
X1776400Y1163426
X1777450Y1158406
X1772000Y1151713
R02Y-0006693
X1772000Y1181831
X1772000Y1188524
X1772000Y1175138
X1777450Y1168445
X1772000Y1211949
X1772000Y1218642
X1777450Y1195217
X1776400Y1200237
X1777450Y1205256
X1772000Y1255453
X1777450Y1242067
X1772000Y1248760
X1777450Y1232028
X1776400Y1237048
X1772000Y1225335
X1788142Y0780256
X1782692Y0786949
X1792542Y0791969
X1788142Y0810374
X1788142Y0817067
X1788142Y0803681
X1782692Y0796988
X1782692Y0860571
X1788142Y0840492
X1788142Y0847185
X1792542Y0828780
X1782692Y0833799
X1782692Y0823760
X1788142Y0890689
R02Y-0006693
X1782692Y0870610
X1792542Y0865591
X1788142Y0853878
X1788142Y0920807
X1788142Y0914114
X1792542Y0902402
X1782692Y0897382
X1782692Y0907422
X1788142Y0950925
X1782692Y0944233
X1792542Y0939213
X1788142Y0927500
X1782692Y0934193
X1788142Y0991083
X1788142Y0997776
X1788142Y0984390
X1788142Y0977697
X1788142Y0957618
X1788142Y0971004
X1788142Y0964311
X1788142Y1051319
X1788142Y1058012
X1788142Y1031240
X1788142Y1037933
X1788142Y1044626
X1788142Y1004469
X1792542Y1086457
X1782692Y1081437
X1788142Y1068051
X1788142Y1074744
X1788142Y1111555
X1782692Y1118248
X1788142Y1104862
X1788142Y1098170
X1782692Y1091477
X1788142Y1148366
X1788142Y1141674
X1792542Y1123268
X1782692Y1128288
X1788142Y1134981
X1788142Y1185177
X1782692Y1191870
X1788142Y1178485
X1788142Y1171792
X1792542Y1160079
X1782692Y1165099
X1782692Y1155059
X1788142Y1215296
X1788142Y1221988
X1788142Y1208603
X1792542Y1196890
X1782692Y1201910
X1788142Y1252107
X1788142Y1245414
X1792542Y1233701
X1782692Y1238721
X1782692Y1228681
X1669339Y0773563
X1664789Y0763765
X1653197Y0776910
X1657747Y0767265
X1639638Y0773563
X1635088Y0763765
X1623496Y0776910
X1628046Y0767265
X1205561Y0763765
X1175860Y0763765
X1146160Y0763765
R03X-0029701
X1050015Y0767265
X1150709Y1252107
X1150709Y1245414
X1150709Y1208603
X1146309Y1196890
X1145259Y1201910
X1150709Y1221988
X1150709Y1215296
X1145259Y1228681
X1146309Y1233701
X1145259Y1238721
X1145259Y1165099
X1146309Y1160079
X1145259Y1155059
X1150709Y1178485
X1150709Y1171792
X1150709Y1185177
X1145259Y1191870
X1150709Y1111555
X1145259Y1118248
X1145259Y1128288
X1146309Y1123268
X1150709Y1134981
X1150709Y1148366
X1150709Y1141674
X1150709Y1068051
X1150709Y1074744
X1145259Y1081437
X1146309Y1086457
X1150709Y1104862
X1150709Y1098170
X1145259Y1091477
X1150709Y1044626
R02Y-0006693
X1150709Y1058012
X1150709Y1051319
X1150709Y0957618
X1150709Y0971004
X1150709Y0964311
X1150709Y0984390
X1150709Y0977697
X1150709Y0997776
X1150709Y0991083
X1150709Y1004469
X1150709Y0920807
X1150709Y0914114
X1150709Y0927500
X1146309Y0939213
X1145259Y0934193
X1150709Y0950925
X1145259Y0944233
X1150709Y0877303
X1145259Y0870610
X1150709Y0890689
X1150709Y0883996
X1145259Y0897382
X1146309Y0902402
X1145259Y0907422
X1145259Y0833799
X1145259Y0823760
X1146309Y0828780
X1150709Y0847185
X1150709Y0840492
X1150709Y0853878
X1145259Y0860571
X1146309Y0865591
X1150709Y0780256
X1145259Y0786949
X1146309Y0791969
X1150709Y0803681
X1145259Y0796988
X1150709Y0817067
X1150709Y0810374
X1140017Y1242067
X1134567Y1248760
X1134567Y1255453
X1140017Y1195217
X1140017Y1205256
X1130167Y1200237
X1134567Y1218642
X1134567Y1211949
X1134567Y1225335
X1140017Y1232028
X1130167Y1237048
X1140017Y1158406
X1134567Y1151713
X1130167Y1163426
X1134567Y1175138
X1140017Y1168445
X1134567Y1181831
X1134567Y1188524
X1140017Y1121595
X1130167Y1126615
X1140017Y1131634
X1134567Y1145020
X1134567Y1138327
X1140017Y1084784
X1134567Y1078091
X1130167Y1089804
X1134567Y1101516
X1140017Y1094823
X1134567Y1114902
X1134567Y1108209
X1134567Y0994429
X1134567Y0987736
X1134567Y1004469
X1134567Y1041280
X1134567Y1034587
X1134567Y1054666
X1134567Y1047973
X1134567Y1071398
X1134567Y1061359
X1134567Y0960965
X1134567Y0967658
X1134567Y0981044
X1134567Y0974351
X1134567Y0924154
X1134567Y0917461
X1140017Y0937540
X1134567Y0930847
X1134567Y0954272
X1140017Y0947579
X1130167Y0942560
X1134567Y0880650
X1140017Y0873957
X1130167Y0868937
X1134567Y0894036
X1134567Y0887343
X1140017Y0900729
X1140017Y0910768
X1130167Y0905749
X1140017Y0837146
X1140017Y0827107
X1130167Y0832126
X1134567Y0843839
R02Y0006693
X1140017Y0863918
X1134567Y0783603
X1140017Y0790296
X1134567Y0807028
X1140017Y0800335
X1130167Y0795315
X1134567Y0820414
X1134567Y0813721
X1134567Y0776910
X1121008Y1208603
X1116608Y1196890
X1115558Y1201910
X1121008Y1221988
X1121008Y1215296
X1116608Y1233701
X1115558Y1228681
X1115558Y1238721
X1121008Y1252107
X1121008Y1245414
X1116608Y1160079
X1115558Y1165099
X1115558Y1155059
X1121008Y1178485
X1121008Y1171792
X1121008Y1185177
X1115558Y1191870
X1121008Y1111555
X1115558Y1118248
X1115558Y1128288
X1116608Y1123268
X1121008Y1134981
X1121008Y1148366
X1121008Y1141674
X1121008Y1068051
X1121008Y1074744
X1115558Y1081437
X1116608Y1086457
X1121008Y1104862
X1121008Y1098170
X1115558Y1091477
X1121008Y0997776
X1121008Y0991083
X1121008Y1004469
X1121008Y1044626
X1121008Y1037933
X1121008Y1031240
X1121008Y1058012
X1121008Y1051319
X1121008Y0950925
X1115558Y0944233
X1121008Y0957618
X1121008Y0971004
X1121008Y0964311
X1121008Y0984390
X1121008Y0977697
X1116608Y0902402
X1115558Y0897382
X1115558Y0907422
X1121008Y0920807
X1121008Y0914114
X1116608Y0939213
X1121008Y0927500
X1115558Y0934193
X1121008Y0840492
X1116608Y0865591
X1115558Y0860571
X1121008Y0853878
X1121008Y0877303
X1115558Y0870610
X1121008Y0890689
X1121008Y0883996
X1115558Y0796988
X1121008Y0803681
X1121008Y0817067
X1121008Y0810374
X1116608Y0828780
X1115558Y0833799
X1115558Y0823760
X1121008Y0847185
X1115558Y0786949
X1121008Y0780256
X1116608Y0791969
X1104866Y1218642
X1104866Y1211949
X1104866Y1225335
X1110316Y1232028
X1100466Y1237048
X1110316Y1242067
X1104866Y1248760
X1104866Y1255453
X1104866Y1175138
X1110316Y1168445
X1104866Y1181831
X1104866Y1188524
X1100466Y1200237
X1110316Y1195217
X1110316Y1205256
X1100466Y1126615
X1110316Y1121595
X1110316Y1131634
X1104866Y1145020
X1104866Y1138327
X1100466Y1163426
X1104866Y1151713
X1110316Y1158406
X1104866Y1061359
X1100466Y1089804
X1110316Y1084784
X1104866Y1078091
X1104866Y1101516
X1110316Y1094823
X1104866Y1114902
X1104866Y1108209
X1104866Y0994429
X1104866Y0987736
X1104866Y1004469
X1104866Y1041280
X1104866Y1034587
X1104866Y1054666
X1104866Y1047973
X1104866Y1071398
X1104866Y0954272
X1100466Y0942560
X1110316Y0947579
X1104866Y0960965
X1104866Y0967658
X1104866Y0981044
X1104866Y0974351
X1110316Y0900729
X1100466Y0905749
X1110316Y0910768
X1104866Y0924154
X1104866Y0917461
X1110316Y0937540
X1104866Y0930847
X1110316Y0863918
X1104866Y0857225
X1104866Y0880650
X1110316Y0873957
X1100466Y0868937
X1104866Y0894036
X1104866Y0887343
X1104866Y0820414
X1104866Y0813721
X1100466Y0832126
X1110316Y0837146
X1110316Y0827107
X1104866Y0843839
X1104866Y0850532
X1104866Y0776910
X1110316Y0790296
X1104866Y0783603
X1104866Y0807028
X1100466Y0795315
X1110316Y0800335
X1091308Y1252107
X1091308Y1245414
X1091308Y1185177
X1085858Y1191870
X1091308Y1208603
X1086908Y1196890
X1085858Y1201910
X1091308Y1221988
X1091308Y1215296
X1086908Y1233701
X1085858Y1228681
X1085858Y1238721
X1091308Y1148366
X1091308Y1141674
X1086908Y1160079
X1085858Y1165099
X1085858Y1155059
X1091308Y1178485
X1091308Y1171792
X1085858Y1081437
X1086908Y1086457
X1091308Y1104862
X1091308Y1098170
X1085858Y1091477
X1091308Y1111555
X1085858Y1118248
X1085858Y1128288
X1086908Y1123268
X1091308Y1134981
X1091308Y1044626
X1091308Y1037933
X1091308Y1031240
X1091308Y1058012
X1091308Y1051319
X1091308Y1068051
X1091308Y1074744
X1091308Y0957618
X1091308Y0971004
X1091308Y0964311
X1091308Y0984390
X1091308Y0977697
X1091308Y0997776
X1091308Y0991083
X1091308Y1004469
X1086908Y0902402
X1085858Y0897382
X1085858Y0907422
X1091308Y0920807
X1091308Y0914114
X1086908Y0939213
X1091308Y0927500
X1085858Y0934193
X1091308Y0950925
X1085858Y0944233
X1086908Y0865591
X1085858Y0860571
X1091308Y0853878
X1091308Y0877303
X1085858Y0870610
X1091308Y0890689
X1091308Y0883996
X1085858Y0796988
X1091308Y0803681
X1091308Y0817067
X1091308Y0810374
X1086908Y0828780
X1085858Y0833799
X1085858Y0823760
X1091308Y0847185
X1091308Y0840492
X1085858Y0786949
X1091308Y0780256
X1086908Y0791969
X1075166Y1218642
X1075166Y1211949
X1075166Y1225335
X1080616Y1232028
X1070766Y1237048
X1080616Y1242067
X1075166Y1248760
X1075166Y1255453
X1070766Y1163426
X1075166Y1151713
X1080616Y1158406
X1075166Y1175138
X1080616Y1168445
X1075166Y1181831
X1075166Y1188524
X1080616Y1195217
X1070766Y1200237
X1080616Y1205256
X1075166Y1114902
X1075166Y1108209
X1070766Y1126615
X1080616Y1121595
X1080616Y1131634
X1075166Y1145020
X1075166Y1138327
X1075166Y1054666
X1075166Y1047973
X1075166Y1071398
X1075166Y1061359
X1080616Y1084784
X1070766Y1089804
X1075166Y1078091
X1075166Y1101516
X1080616Y1094823
X1075166Y0981044
X1075166Y0974351
X1075166Y0994429
X1075166Y0987736
X1075166Y1004469
X1075166Y1041280
X1075166Y1034587
X1080616Y0937540
X1075166Y0930847
X1075166Y0954272
X1080616Y0947579
X1070766Y0942560
X1075166Y0960965
X1075166Y0967658
X1075166Y0880650
X1080616Y0873957
X1070766Y0868937
X1075166Y0894036
X1075166Y0887343
X1080616Y0900729
X1070766Y0905749
X1080616Y0910768
X1075166Y0924154
X1075166Y0917461
X1080616Y0837146
X1080616Y0827107
X1070766Y0832126
X1075166Y0843839
R02Y0006693
X1080616Y0863918
X1075166Y0776910
X1075166Y0783603
X1080616Y0790296
X1075166Y0807028
X1080616Y0800335
X1070766Y0795315
X1075166Y0820414
X1075166Y0813721
X1061607Y1208603
X1057207Y1196890
X1056157Y1201910
X1061607Y1221988
X1061607Y1215296
X1056157Y1228681
X1057207Y1233701
X1056157Y1238721
X1061607Y1252107
X1061607Y1245414
X1061607Y1148366
X1061607Y1141674
X1057207Y1160079
X1056157Y1165099
X1056157Y1155059
X1061607Y1178485
X1061607Y1171792
X1061607Y1185177
X1056157Y1191870
X1056157Y1081437
X1057207Y1086457
X1061607Y1104862
X1061607Y1098170
X1056157Y1091477
X1061607Y1111555
X1056157Y1118248
X1056157Y1128288
X1057207Y1123268
X1061607Y1134981
X1061607Y1031240
X1061607Y1044626
X1061607Y1037933
X1061607Y1058012
X1061607Y1051319
X1061607Y1068051
X1061607Y1074744
X1056157Y0944233
X1061607Y0950925
X1061607Y0957618
X1061607Y0971004
X1061607Y0964311
X1061607Y0984390
X1061607Y0977697
X1061607Y0997776
X1061607Y0991083
X1061607Y1004469
X1057207Y0902402
X1056157Y0897382
X1056157Y0907422
X1061607Y0920807
X1061607Y0914114
X1057207Y0939213
X1056157Y0934193
X1061607Y0927500
X1061607Y0840492
X1061607Y0847185
X1057207Y0865591
X1056157Y0860571
X1061607Y0853878
X1061607Y0877303
X1056157Y0870610
X1061607Y0890689
X1061607Y0883996
X1061607Y0780256
X1056157Y0786949
X1057207Y0791969
X1056157Y0796988
X1061607Y0803681
X1061607Y0817067
X1061607Y0810374
X1057207Y0828780
X1056157Y0833799
X1056157Y0823760
X1050915Y1232028
X1045465Y1225335
X1041065Y1237048
X1050915Y1242067
X1045465Y1248760
X1045465Y1255453
X1045465Y1145020
X1045465Y1138327
X1041065Y1163426
X1045465Y1151713
X1050915Y1158406
X1045465Y1175138
X1050915Y1168445
X1045465Y1181831
X1045465Y1188524
X1050915Y1195217
X1050915Y1205256
X1041065Y1200237
X1045465Y1218642
X1045465Y1211949
X1045465Y1034587
X1045465Y1054666
X1045465Y1047973
X1045465Y1071398
X1045465Y1061359
X1041065Y1089804
X1050915Y1084784
X1045465Y1078091
X1045465Y1101516
X1050915Y1094823
X1045465Y1114902
X1045465Y1108209
X1041065Y1126615
X1050915Y1121595
X1050915Y1131634
X1050915Y0937540
X1045465Y0930847
X1045465Y0954272
X1041065Y0942560
X1050915Y0947579
X1045465Y0960965
X1045465Y0967658
X1045465Y0981044
X1045465Y0974351
X1045465Y0994429
X1045465Y0987736
X1045465Y1004469
X1045465Y1041280
X1045465Y0843839
R02Y0006693
X1050915Y0863918
X1045465Y0880650
X1050915Y0873957
X1041065Y0868937
X1045465Y0894036
X1045465Y0887343
X1050915Y0900729
X1041065Y0905749
X1050915Y0910768
X1045465Y0924154
X1045465Y0917461
X1045465Y0776910
X1045465Y0783603
X1050915Y0790296
X1045465Y0807028
X1041065Y0795315
X1050915Y0800335
X1045465Y0820414
X1045465Y0813721
X1041065Y0832126
X1050915Y0837146
X1050915Y0827107
X1061607Y0773563
X1079716Y0767265
X1091308Y0773563
X1109416Y0767265
X1121008Y0773563
X1139117Y0767265
X1150709Y0773563
X1168818Y0767265
X1164268Y0776910
X1180410Y0773563
X1198519Y0767265
X1193969Y0776910
X1210111Y0773563
X1169718Y0790296
X1164268Y0783603
X1174960Y0786949
X1180410Y0780256
X1176010Y0791969
X1199419Y0790296
X1193969Y0783603
X1204661Y0786949
X1210111Y0780256
X1205711Y0791969
X1169718Y0800335
X1164268Y0807028
X1159868Y0795315
X1174960Y0796988
X1180410Y0803681
X1199419Y0800335
X1193969Y0807028
X1189569Y0795315
X1204661Y0796988
X1210111Y0803681
X1164268Y0813721
X1164268Y0820414
X1180410Y0810374
X1180410Y0817067
X1193969Y0813721
X1193969Y0820414
X1210111Y0810374
X1210111Y0817067
X1169718Y0827107
X1169718Y0837146
X1159868Y0832126
X1174960Y0823760
X1174960Y0833799
X1176010Y0828780
X1199419Y0827107
X1199419Y0837146
X1189569Y0832126
X1204661Y0823760
X1204661Y0833799
X1205711Y0828780
X1164268Y0843839
X1164268Y0850532
X1180410Y0840492
X1180410Y0847185
X1193969Y0843839
X1193969Y0850532
X1210111Y0840492
X1210111Y0847185
X1169718Y0863918
X1164268Y0857225
X1174960Y0860571
X1180410Y0853878
X1176010Y0865591
X1199419Y0863918
X1193969Y0857225
X1204661Y0860571
X1210111Y0853878
X1205711Y0865591
X1169718Y0873957
X1164268Y0880650
X1159868Y0868937
X1174960Y0870610
X1180410Y0877303
X1199419Y0873957
X1193969Y0880650
X1189569Y0868937
X1204661Y0870610
X1210111Y0877303
X1164268Y0887343
X1180410Y0883996
X1180410Y0890689
X1193969Y0887343
X1210111Y0883996
X1210111Y0890689
X1102230Y1384770
X1134930Y1384770
X1167830Y1384770
X1200690Y1384572
X1271517Y1338596
X1304421Y1338539
X1337221Y1338739
X1103888Y1386721
X1136588Y1386721
X1169488Y1386721
X1202288Y1386721
X1273175Y1340547
X1306079Y1340490
X1338879Y1340690
X1051684Y1350724
X1048684Y1350724
X1054684Y1350724
X1067929Y1337702
X1060721Y1313954
X1057684Y1350724
X1060684Y1350724
X1073733Y1388198
X1083368Y1385268
X1083319Y1372853
R02X-0002430
X1078459Y1367253
X1079215Y1360497
X1076615Y1360497
X1084415Y1363454
X1081815Y1363454
X1084415Y1360497
X1081815Y1360497
X1080889Y1367253
X1083319Y1367253
X1081815Y1357390
X1076615Y1357390
X1079215Y1357390
X1084415Y1357390
X1070949Y1337752
X1092905Y1360437
X1092905Y1363394
X1091959Y1357406
X1089515Y1357390
X1098229Y1354852
X1096979Y1357352
X1095629Y1354852
X1098229Y1349652
X1095629Y1349652
X1098229Y1352252
X1095629Y1352252
X1087015Y1357390
X1095809Y1337824
X1098409Y1337824
X1113489Y1372853
X1111059Y1372853
X1111059Y1367253
X1114415Y1360497
R02X-0002600
X1114415Y1363454
X1113489Y1367253
X1114415Y1357390
X1109215Y1357390
X1111815Y1357390
X1109289Y1337752
X1103529Y1337792
X1115919Y1367253
X1125505Y1360437
X1125505Y1363394
X1117015Y1357390
X1124559Y1357406
X1122115Y1357390
X1119615Y1357390
X1128229Y1354852
X1129579Y1357352
X1128229Y1349652
X1128229Y1352252
X1115919Y1372853
X1117015Y1360497
X1117015Y1363454
X1115968Y1385268
X1143759Y1372853
X1143759Y1367253
X1144515Y1360497
X1141915Y1360497
X1130829Y1354852
X1144515Y1357390
X1141915Y1357390
X1130829Y1349652
X1130829Y1352252
X1133619Y1337794
X1143219Y1337834
X1136219Y1337794
X1146189Y1367253
X1148619Y1367253
X1158205Y1360437
X1158205Y1363394
X1149715Y1357390
X1147115Y1357390
X1154815Y1357390
X1152315Y1357390
X1157259Y1357406
X1145819Y1337834
X1154839Y1337834
X1157439Y1337834
X1148668Y1385268
X1148619Y1372853
X1146189Y1372853
X1147115Y1363454
X1149715Y1360497
X1149715Y1363454
X1147115Y1360497
X1150458Y1433146
X1163529Y1354852
X1162279Y1357352
X1163529Y1349652
X1160929Y1349652
X1163529Y1352252
X1160929Y1352252
X1164909Y1337884
X1167509Y1337884
X1180015Y1357390
X1174815Y1357390
X1177415Y1357390
X1187715Y1357390
X1185215Y1357390
X1182615Y1357390
X1179089Y1367253
X1181519Y1367253
X1181568Y1385268
X1181519Y1372853
R02X-0002430
X1176659Y1367253
X1180015Y1360497
R02X-0002600
X1180015Y1363454
X1182615Y1360497
X1182615Y1363454
X1191105Y1360437
X1191105Y1363394
X1196429Y1354852
X1195179Y1357352
X1190159Y1357406
X1193829Y1354852
X1196429Y1349652
X1193829Y1349652
X1196429Y1352252
X1193829Y1352252
X1202399Y1338105
X1199899Y1338065
X1196259Y1321549
X1193659Y1321549
X1196259Y1324049
X1193659Y1324049
X1202689Y1324032
X1202689Y1321492
X1193659Y1326589
X1196159Y1326549
X1211889Y1367253
X1214319Y1367253
X1207615Y1357390
R04X0002600
X1211299Y1338105
X1205189Y1323992
X1205189Y1321492
X1214368Y1385268
X1209459Y1367253
X1209459Y1372853
X1211889Y1372853
X1214319Y1372853
X1207615Y1360497
R02X0002600
X1212815Y1363454
X1215415Y1360497
X1215415Y1363454
X1220515Y1357390
X1229229Y1354852
X1226629Y1354852
X1227979Y1357352
X1222959Y1357406
X1229229Y1349652
X1226629Y1349652
X1229229Y1352252
X1226629Y1352252
X1229809Y1338105
X1219463Y1338122
X1232409Y1338105
X1223905Y1360437
X1223905Y1363394
X1240240Y1339578
X1252359Y1339122
X1249880Y1326707
X1247450Y1321107
X1247450Y1326707
X1250806Y1317308
X1253406Y1317308
X1252310Y1326707
X1249880Y1321107
X1252310Y1321107
X1248206Y1311244
X1245606Y1311244
X1248206Y1314351
X1245606Y1314351
X1250806Y1311244
X1253406Y1311244
X1250806Y1314351
X1253406Y1314351
X1247050Y1291721
X1249650Y1291721
X1261896Y1317248
X1264620Y1308706
R02Y-0002600
X1265970Y1311206
X1267220Y1303506
X1267220Y1308706
X1267220Y1306106
X1256006Y1311244
X1258506Y1311244
X1260950Y1311260
X1261896Y1314291
X1268070Y1291624
X1260050Y1291721
X1257450Y1291721
X1258121Y1342686
X1280346Y1326679
X1280346Y1321079
X1282776Y1326679
X1282776Y1321079
X1278502Y1311216
X1281102Y1311216
X1281102Y1314323
X1278502Y1314323
X1270670Y1291624
X1285206Y1321079
X1294792Y1317220
X1283702Y1311216
X1286302Y1311216
X1283702Y1314323
X1286302Y1314323
X1288902Y1311216
X1293846Y1311232
X1291402Y1311216
X1297516Y1308678
X1297516Y1303478
X1297516Y1306078
X1294792Y1314263
X1295750Y1291721
X1285255Y1339094
X1283702Y1317280
X1286302Y1317280
X1285206Y1326679
X1313250Y1326622
X1313250Y1321022
X1298866Y1311178
X1300116Y1308678
X1311406Y1311159
X1311406Y1314266
X1300116Y1303478
X1300116Y1306078
X1298350Y1291721
X1302890Y1291759
X1305600Y1291759
X1315680Y1321022
X1318110Y1321022
X1327696Y1317163
X1319206Y1311159
X1319206Y1314266
X1326750Y1311175
X1324306Y1311159
X1321806Y1311159
X1314006Y1311159
X1314006Y1314266
X1316606Y1311159
X1316606Y1314266
X1327696Y1314206
X1319206Y1317223
X1316606Y1317223
X1318110Y1326622
X1315680Y1326622
X1318159Y1339037
X1330420Y1308621
X1330420Y1303421
X1330420Y1306021
X1333020Y1303421
X1333020Y1306021
X1331770Y1311121
X1333020Y1308621
X1330080Y1291861
X1332680Y1291861
X1335670Y1291899
X1338440Y1291949
X1348480Y1321222
X1350910Y1321222
X1344206Y1314466
X1344206Y1311359
X1352006Y1314466
R02X-0002600
X1354606Y1311359
X1357106Y1311359
X1352006Y1311359
R02X-0002600
X1350959Y1339237
X1346050Y1326822
X1346050Y1321222
X1349406Y1317423
X1352006Y1317423
X1350910Y1326822
X1348480Y1326822
X1360496Y1317363
X1359550Y1311375
X1365820Y1303621
X1363220Y1303621
X1363220Y1306221
X1365820Y1306221
X1364570Y1311321
X1363220Y1308821
X1368305Y1309840
X1365820Y1308821
X1360496Y1314406
X1361830Y1291809
X1364490Y1293694
X1371422Y1359024
X1378632Y1346153
X1383492Y1346153
X1381062Y1346153
X1383541Y1358568
X1376788Y1333797
X1376788Y1330690
X1378632Y1340553
X1384588Y1333797
X1384588Y1330690
X1381988Y1333797
X1381988Y1330690
X1379388Y1333797
X1379388Y1330690
X1387188Y1330690
X1384588Y1336754
X1381988Y1336754
X1381062Y1340553
X1383492Y1340553
X1393078Y1336694
X1393078Y1333737
X1398902Y1322952
X1396302Y1322952
X1398902Y1325552
X1398902Y1328152
X1396302Y1325552
X1396302Y1328152
X1399240Y1311980
X1401740Y1311980
X1392132Y1330706
X1389688Y1330690
X1397652Y1330652
X1401406Y1334918
X1405716Y1310618
X1406608Y1282606
X1408690Y1324803
R04X0003000
X1372149Y1334890
X1339429Y1315570
X1306799Y1315440
X1273869Y1315300
X1240899Y1315460
X1202988Y1361490
X1170138Y1361800
X1104448Y1361680
X1071908Y1361660
X1137218Y1361660
X1648337Y1451313
X1685963Y1402187
X1687621Y1404138
X1627181Y1448016
X1627242Y1436148
X1627052Y1424716
X1643283Y1431541
X1643183Y1419441
X1643283Y1425541
X1641904Y1348567
X1641904Y1351467
X1648857Y1403424
X1654774Y1402619
X1662010Y1390170
X1651301Y1378765
X1660166Y1374707
X1662766Y1374707
X1660166Y1377814
X1662766Y1377814
X1662010Y1384570
X1658904Y1348567
X1658904Y1351467
X1650177Y1348567
X1650177Y1351467
X1651187Y1301335
X1651187Y1306535
X1651187Y1303935
X1660594Y1301335
X1660594Y1306535
X1660594Y1303935
X1651187Y1298735
X1660594Y1298735
X1655957Y1445116
X1662465Y1444358
X1655383Y1419441
X1655383Y1431541
X1649283Y1431541
X1649283Y1419441
X1655383Y1425541
X1675187Y1301335
X1675187Y1306535
X1675187Y1303935
X1675187Y1298735
X1673066Y1374707
X1667966Y1380771
X1667966Y1377814
X1665366Y1374707
X1665366Y1380771
X1665366Y1377814
X1670566Y1374707
X1667966Y1374707
X1675510Y1374723
X1664440Y1384570
X1666870Y1384570
X1675901Y1380551
X1675901Y1377594
X1674831Y1348366
X1674831Y1351266
X1666290Y1444391
X1672273Y1420567
X1672907Y1429928
X1674777Y1407694
X1672277Y1407694
X1671067Y1405418
X1666919Y1402585
X1664440Y1390170
X1666870Y1390170
X1684708Y1301035
X1684708Y1306235
X1684708Y1303635
X1684708Y1298435
X1680530Y1374669
X1692948Y1374807
X1692948Y1377914
X1683896Y1378765
X1679180Y1369569
X1681780Y1369569
X1681780Y1366969
X1679180Y1366969
X1681780Y1372169
X1679180Y1372169
X1679133Y1348520
X1687233Y1348420
X1679133Y1351420
X1687233Y1351320
X1687357Y1440268
X1684677Y1440258
X1697222Y1384670
X1699652Y1384670
X1695533Y1348420
X1695533Y1351320
X1699087Y1301035
X1699087Y1306235
X1699087Y1303635
X1699087Y1298435
X1699701Y1402685
X1697222Y1390270
X1694792Y1390270
X1699652Y1390270
X1698148Y1374807
X1695548Y1374807
X1698148Y1380871
X1695548Y1377914
X1698148Y1377914
X1705848Y1374807
X1703348Y1374807
X1700748Y1374807
X1700748Y1380871
X1700748Y1377914
X1694792Y1384670
X1708754Y1306188
X1708754Y1303588
X1708754Y1298388
X1708292Y1374823
X1713312Y1374769
X1716267Y1375178
X1708678Y1377664
X1708678Y1380621
X1719902Y1363409
X1719902Y1365909
X1719902Y1368509
X1714562Y1369669
X1711962Y1369669
X1714562Y1367069
X1711962Y1367069
X1709533Y1348620
X1709533Y1351520
X1721754Y1302088
X1708754Y1300988
X1721754Y1304688
X1723917Y1377178
X1723917Y1380518
X1735202Y1363179
X1735202Y1365679
X1735202Y1368279
X1743072Y1432211
X1599139Y1400464
X1368305Y1307340
X1718813Y1351350
X1718813Y1348450
X1721847Y1307298
X1721754Y1299488
X1732624Y1304918
X1732624Y1302318
X1732717Y1307528
X1732624Y1299718
X1035645Y0773582
X1025493Y0768719
X1007587Y0769980
X1007587Y0767480
X0800408Y0767266
X0807451Y0763765
X0777900Y0763766
X0770708Y0767266
X0748049Y0763766
X0741007Y0767266
X0711306Y0767266
X0718348Y0763766
X0681605Y0767266
X0688647Y0763766
X0651904Y0767266
X0658946Y0763766
X0392910Y1317880
X0392950Y1315280
X0444561Y1321622
X0441561Y1321622
X0427251Y1291747
X0431830Y1311240
X0435561Y1321622
X0432561Y1321622
X0438561Y1321622
X0421023Y1330671
X0413559Y1330709
X0416003Y1330725
X0411059Y1330709
X0424333Y1331447
X0421091Y1311219
X0423521Y1311969
X0422273Y1328171
R02Y-0002600
X0419673Y1328171
X0419673Y1322971
X0419673Y1325571
X0416949Y1333756
X0416949Y1336713
X0404933Y1340572
X0407363Y1340572
X0402503Y1340572
X0405859Y1336773
X0408459Y1336773
X0400659Y1333816
R03X0002600
X0403259Y1330709
X0400659Y1330709
X0405859Y1330709
X0408459Y1330709
X0396129Y1334717
X0402503Y1346172
R02X0002430
X0407412Y1358587
X0395267Y1358621
X0385701Y1291828
X0388361Y1293713
X0384367Y1314425
X0388441Y1311340
X0383421Y1311394
X0387091Y1303640
X0389691Y1303640
X0387091Y1308840
X0387091Y1306240
X0389691Y1308840
X0389691Y1306240
X0394951Y1311259
X0392176Y1309859
X0384367Y1317382
X0373277Y1311378
R02X-0002600
X0373277Y1314485
X0368077Y1314485
X0370677Y1314485
X0375877Y1311378
X0378477Y1311378
X0375877Y1314485
X0380977Y1311378
X0372351Y1321241
X0374781Y1321241
X0373277Y1317442
X0374781Y1326841
X0369921Y1321241
X0369921Y1326841
X0372351Y1326841
X0375877Y1317442
X0374830Y1339256
X0363547Y1315386
X0353951Y1291880
X0356551Y1291880
X0362311Y1291968
X0359541Y1291918
X0351567Y1314225
X0355641Y1311140
X0354291Y1303440
X0354291Y1308640
X0354291Y1306040
X0356891Y1303440
X0356891Y1308640
X0356891Y1306040
X0351567Y1317182
X0343077Y1317242
X0340477Y1317242
X0337121Y1326641
X0339551Y1326641
X0337121Y1321041
X0341981Y1326641
X0342030Y1339056
X0343077Y1311178
X0345677Y1311178
X0343077Y1314285
X0348177Y1311178
X0350621Y1311194
X0340477Y1311178
X0337877Y1311178
X0337877Y1314285
X0340477Y1314285
X0339551Y1321041
X0341981Y1321041
X0326761Y1291778
X0322221Y1291740
X0329471Y1291778
X0322737Y1311197
X0323987Y1308697
R02Y-0002600
X0335277Y1311178
X0335277Y1314285
X0330747Y1315186
X0310173Y1317299
X0307573Y1317299
X0306647Y1326698
X0309077Y1326698
X0309126Y1339113
X0319621Y1291740
X0318663Y1314282
X0310173Y1311235
X0310173Y1314342
X0307573Y1311235
X0307573Y1314342
X0312773Y1311235
X0315273Y1311235
X0317717Y1311251
X0321387Y1303497
X0321387Y1308697
X0321387Y1306097
X0318663Y1317239
X0306647Y1321098
X0309077Y1321098
X0291941Y1291378
X0304973Y1311235
X0302373Y1311235
X0304973Y1314342
X0302373Y1314342
X0297843Y1315243
X0304217Y1321098
X0304217Y1326698
X0294541Y1291378
X0281992Y1342705
X0277277Y1317327
X0281321Y1291740
X0283921Y1291740
X0285767Y1314310
X0289841Y1311225
X0291091Y1303525
X0288491Y1303525
X0291091Y1308725
X0291091Y1306125
X0288491Y1308725
X0288491Y1306125
X0277277Y1311263
X0277277Y1314370
X0279877Y1311263
X0282377Y1311263
X0284821Y1311279
X0285767Y1317267
X0274091Y1291740
X0271491Y1291740
X0274677Y1311263
X0269477Y1311263
X0272077Y1311263
X0274677Y1314370
X0269477Y1314370
X0272077Y1314370
X0273751Y1321126
X0276181Y1321126
X0264947Y1315271
X0274677Y1317327
X0273751Y1326726
X0276181Y1326726
X0271321Y1321126
X0271321Y1326726
X0264085Y1339175
X0276230Y1339141
X0247725Y1338141
X0258071Y1338124
X0260671Y1338124
X0254891Y1349671
X0257491Y1349671
X0248777Y1357409
X0251221Y1357425
X0254891Y1354871
X0254891Y1352271
X0257491Y1354871
X0256241Y1357371
X0257491Y1352271
X0252167Y1360456
X0252167Y1363413
X0235877Y1360516
X0238477Y1360516
X0237721Y1367272
X0237721Y1372872
X0240151Y1372872
X0242581Y1372872
X0242630Y1385287
X0232961Y1321404
X0232961Y1323904
X0239561Y1338124
X0246277Y1357409
X0235877Y1357409
X0238477Y1357409
R02X0002600
X0243677Y1360516
X0241077Y1360516
X0241077Y1363473
X0243677Y1363473
X0240151Y1367272
X0242581Y1367272
X0231347Y1361417
X0230171Y1321404
X0230171Y1323904
X0221881Y1323918
X0224481Y1321418
X0221881Y1321418
X0224481Y1323918
X0221881Y1326418
X0224481Y1326418
X0230661Y1338124
X0221341Y1338068
X0223941Y1338068
X0227871Y1338124
X0222091Y1349671
X0224691Y1349671
X0218421Y1357425
X0222091Y1352271
X0222091Y1354871
X0223441Y1357371
X0224691Y1352271
X0224691Y1354871
X0219367Y1363413
X0219367Y1360456
X0209781Y1367272
X0203077Y1360516
X0205677Y1360516
X0210877Y1360516
X0208277Y1360516
X0208277Y1363473
X0210877Y1363473
X0207351Y1372872
X0204921Y1372872
X0204921Y1367272
X0209781Y1372872
X0209830Y1385287
X0203077Y1357409
X0205677Y1357409
X0213477Y1357409
X0208277Y1357409
X0210877Y1357409
X0215977Y1357409
X0207351Y1367272
X0193171Y1337903
X0195771Y1337903
X0191791Y1349671
X0189191Y1349671
X0191791Y1352271
X0191791Y1354871
X0189191Y1352271
X0189191Y1354871
X0190541Y1357371
X0198547Y1361417
X0177977Y1360516
X0175377Y1360516
X0175377Y1363473
X0177977Y1363473
X0174451Y1372872
X0176881Y1372872
X0172777Y1360516
X0176930Y1385287
X0174081Y1337853
X0183101Y1337853
X0185701Y1337853
X0180577Y1357409
R02X-0002600
X0185521Y1357425
X0183077Y1357409
X0172777Y1357409
X0186467Y1363413
X0186467Y1360456
X0174451Y1367272
X0176881Y1367272
X0165647Y1361417
X0170177Y1360516
X0172021Y1372872
X0172021Y1367272
X0161881Y1337813
X0164481Y1337813
X0171481Y1337853
X0159091Y1349671
X0159091Y1352271
X0157841Y1357371
X0159091Y1354871
X0170177Y1357409
X0144230Y1385287
X0145277Y1360516
X0142677Y1363473
X0145277Y1363473
X0142677Y1360516
X0144181Y1372872
X0150377Y1357409
X0142677Y1357409
X0147877Y1357409
X0145277Y1357409
X0156491Y1349671
X0152821Y1357425
X0156491Y1352271
X0156491Y1354871
X0153767Y1363413
X0153767Y1360456
X0144181Y1367272
X0131791Y1337811
X0137551Y1337771
X0137477Y1357409
X0140077Y1357409
X0141751Y1367272
X0132947Y1361417
X0137477Y1360516
X0140077Y1360516
X0141751Y1372872
X0139321Y1372872
X0139321Y1367272
X0121207Y1360686
X0121207Y1363643
X0126671Y1337843
X0124071Y1337843
X0117777Y1357409
X0123891Y1349671
X0126491Y1349671
X0120221Y1357425
X0123891Y1352271
X0123891Y1354871
X0126491Y1352271
X0125241Y1357371
X0126491Y1354871
X0115277Y1357409
X0099211Y1337771
X0104877Y1357409
R03X0002600
X0111581Y1367272
X0109151Y1367272
X0100347Y1361417
X0104877Y1360516
R03X0002600
X0110077Y1363473
X0112677Y1363473
X0109151Y1372872
X0106721Y1372872
X0106721Y1367272
X0111581Y1372872
X0101995Y1388247
X0111630Y1385287
X0090150Y1314560
X0096191Y1337721
X0088500Y1350300
X0091000Y1350300
X0092791Y1341302
X0092941Y1346172
X0090501Y1338952
X0132150Y1386740
X0362750Y1340709
X0329950Y1340509
X0297046Y1340566
X0230550Y1386740
X0197750Y1386740
X0164850Y1386740
X0228892Y1384789
X0196092Y1384789
X0163192Y1384789
X0130492Y1384789
X0295388Y1338615
X0328292Y1338558
X0361092Y1338758
X0663496Y0773564
X0677055Y0776911
X0693197Y0773564
X0776010Y1380750
X0816400Y1233702
X0816400Y0828781
X0816400Y0865592
R02Y0036811
X0816400Y1086458
R03Y0036811
X0801308Y1242068
X0801308Y1168446
X0812000Y1171793
X0812000Y1178486
X0806550Y1191871
X0812000Y1185178
X0800258Y1200238
X0801308Y1205257
X0806550Y1201911
X0801308Y1195218
X0812000Y1208604
X0812000Y1215297
X0812000Y1221989
X0800258Y1237049
X0806550Y1238722
X0801308Y1232029
X0806550Y1228682
X0812000Y1252108
X0812000Y1245415
X0801308Y1084785
X0800258Y1089805
X0806550Y1081438
X0801308Y1094824
X0806550Y1091478
X0812000Y1104863
X0812000Y1098171
X0806550Y1118249
X0812000Y1111556
X0801308Y1131635
X0812000Y1134982
X0801308Y1121596
X0800258Y1126616
X0806550Y1128289
X0812000Y1141675
X0812000Y1148367
X0801308Y1158407
X0806550Y1155060
X0800258Y1163427
X0806550Y1165100
X0812000Y0977698
R04Y0006693
X0812000Y1031241
R04Y0006693
X0812000Y1074745
X0812000Y1068052
X0812000Y0883997
X0812000Y0890690
X0801308Y0910769
X0800258Y0905750
X0806550Y0907423
X0801308Y0900730
X0806550Y0897383
X0812000Y0914115
X0812000Y0920808
X0806550Y0934194
X0812000Y0927501
X0801308Y0937541
X0806550Y0944234
X0801308Y0947580
X0800258Y0942561
X0812000Y0950926
X0812000Y0964312
X0812000Y0971005
X0812000Y0957619
X0801308Y0800336
X0800258Y0795316
X0806550Y0796989
X0812000Y0803682
R02Y0006693
X0806550Y0823761
X0806550Y0833800
X0801308Y0827108
X0801308Y0837147
X0800258Y0832127
X0812000Y0840493
R02Y0006693
X0801308Y0863919
X0806550Y0860572
X0800258Y0868938
X0806550Y0870611
X0801308Y0873958
X0812000Y0877304
X0801308Y0790297
X0806550Y0786950
X0812000Y0780257
X0786700Y1196891
X0795858Y1211950
R02Y0006693
X0786700Y1233702
X0795858Y1248761
X0795858Y1255454
X0795858Y1138328
R02Y0006693
X0786700Y1160080
X0795858Y1175139
X0795858Y1188525
X0795858Y1181832
X0795858Y1078092
X0786700Y1086458
X0795858Y1101517
R02Y0006693
X0786700Y1123269
X0795858Y0987737
X0795858Y0994430
X0795858Y1004470
X0795858Y1034588
X0795858Y1041281
R03Y0006693
X0795858Y1071399
X0795858Y0954273
X0795858Y0967659
X0795858Y0960966
X0795858Y0974352
X0795858Y0981045
X0795858Y0887344
X0795858Y0894037
X0786700Y0902403
X0795858Y0917462
R02Y0006693
X0786700Y0939214
X0786700Y0828781
X0795858Y0850533
X0795858Y0843840
X0795858Y0857226
X0786700Y0865592
X0795858Y0880651
X0795858Y0776911
X0786700Y0791970
X0795858Y0783604
X0795858Y0807029
X0795858Y0813722
X0795858Y0820415
X0770558Y1237049
X0776850Y1238722
X0771608Y1232029
X0776850Y1228682
X0782300Y1245415
X0782300Y1252108
X0771608Y1242068
X0769521Y1297199
X0769521Y1302299
X0769521Y1299699
X0769521Y1304899
X0770469Y1375500
X0773069Y1375500
X0782300Y1171793
X0771608Y1168446
X0782300Y1178486
X0776850Y1191871
X0782300Y1185178
X0771608Y1205257
X0776850Y1201911
X0770558Y1200238
X0771608Y1195218
X0782300Y1208604
X0782300Y1221989
X0782300Y1215297
X0782300Y1134982
X0771608Y1131635
X0771608Y1121596
X0770558Y1126616
X0776850Y1128289
X0782300Y1141675
X0782300Y1148367
X0771608Y1158407
X0776850Y1155060
X0770558Y1163427
X0776850Y1165100
X0770558Y1089805
X0771608Y1084785
X0776850Y1081438
X0771608Y1094824
X0776850Y1091478
X0782300Y1104863
X0782300Y1098171
X0782300Y1111556
X0776850Y1118249
X0782300Y1004470
X0782300Y1044627
X0782300Y1037934
X0782300Y1031241
X0782300Y1058013
X0782300Y1051320
X0782300Y1074745
X0782300Y1068052
X0782300Y0950926
X0770558Y0942561
X0771608Y0947580
X0776850Y0944234
X0782300Y0964312
X0782300Y0971005
X0782300Y0957619
X0782300Y0977698
X0782300Y0984391
X0782300Y0997777
X0782300Y0991084
X0770558Y0905750
X0771608Y0910769
X0776850Y0907423
X0771608Y0900730
X0776850Y0897383
X0782300Y0914115
R02Y0006693
X0776850Y0934194
X0771608Y0937541
X0782300Y0840493
X0782300Y0853879
X0771608Y0863919
X0776850Y0860572
X0770558Y0868938
X0776850Y0870611
X0782300Y0877304
X0771608Y0873958
X0782300Y0883997
X0782300Y0890690
X0782300Y0803682
X0770558Y0795316
X0771608Y0800336
X0776850Y0796989
X0782300Y0817068
X0782300Y0810375
X0771608Y0827108
X0776850Y0833800
X0776850Y0823761
X0770558Y0832127
X0771608Y0837147
X0782300Y0847186
X0782300Y0780257
X0771608Y0790297
X0776850Y0786950
X0765579Y1375480
X0760559Y1375534
X0758115Y1375518
X0755615Y1375518
X0761800Y1349131
X0761800Y1352031
X0764229Y1370380
X0764229Y1367780
X0766829Y1367780
X0766829Y1370380
X0766829Y1372880
X0764229Y1372880
X0761130Y1377975
X0761130Y1380932
X0756999Y1196891
X0766158Y1218643
X0766158Y1211950
X0756999Y1233702
X0766158Y1225336
X0766158Y1248761
X0766158Y1255454
X0759854Y1297246
X0759854Y1299746
X0759854Y1302346
X0759854Y1304946
X0766158Y1151714
X0756999Y1160080
X0766158Y1175139
X0766158Y1188525
X0766158Y1181832
X0766158Y1101517
X0766158Y1108210
X0766158Y1114903
X0756999Y1123269
X0766158Y1138328
X0766158Y1145021
X0766158Y1034588
X0766158Y1041281
X0766158Y1054667
X0766158Y1047974
X0766158Y1061360
X0766158Y1071399
X0766158Y1078092
X0756999Y1086458
X0766158Y0967659
X0766158Y0960966
X0766158Y0981045
X0766158Y0974352
X0766158Y0994430
X0766158Y0987737
X0766158Y1004470
X0766158Y0917462
X0766158Y0924155
X0766158Y0930848
X0756999Y0939214
X0766158Y0954273
X0756999Y0865592
X0766158Y0857226
X0766158Y0880651
X0766158Y0894037
X0766158Y0887344
X0756999Y0902403
X0766158Y0820415
X0766158Y0813722
X0756999Y0828781
X0766158Y0850533
X0766158Y0843840
X0766158Y0776911
X0756999Y0791970
X0766158Y0783604
X0766158Y0807029
X0749489Y1390981
X0747059Y1390981
X0751919Y1390981
X0751968Y1403396
X0752599Y1245415
X0752599Y1252108
X0741907Y1242068
X0745475Y1297246
X0745475Y1299746
X0745475Y1302346
X0745475Y1304946
X0739500Y1349131
X0739500Y1352031
X0751919Y1385381
X0749489Y1385381
X0750415Y1375518
X0750415Y1378625
X0750415Y1381582
X0745215Y1375518
X0747815Y1375518
X0747815Y1378625
X0745215Y1378625
X0747059Y1385381
X0753015Y1375518
X0753015Y1378625
X0753015Y1381582
X0741907Y1205257
X0747149Y1201911
X0740857Y1200238
X0741907Y1195218
X0752599Y1208604
X0752599Y1221989
X0752599Y1215297
X0740857Y1237049
X0747149Y1238722
X0741907Y1232029
X0747149Y1228682
X0747149Y1155060
X0741907Y1158407
X0747149Y1165100
X0740857Y1163427
X0741907Y1168446
X0752599Y1171793
X0752599Y1178486
X0747149Y1191871
X0752599Y1185178
X0747149Y1118249
X0752599Y1111556
X0741907Y1131635
X0752599Y1134982
X0741907Y1121596
X0740857Y1126616
X0747149Y1128289
X0752599Y1141675
X0752599Y1148367
X0752599Y1074745
X0752599Y1068052
X0740857Y1089805
X0741907Y1084785
X0747149Y1081438
X0747149Y1091478
X0741907Y1094824
X0752599Y1104863
X0752599Y1098171
X0752599Y0997777
X0752599Y0991084
X0752599Y1004470
X0752599Y1044627
X0752599Y1037934
X0752599Y1031241
X0752599Y1058013
X0752599Y1051320
X0741907Y0937541
X0752599Y0927501
X0740857Y0942561
X0741907Y0947580
X0747149Y0944234
X0752599Y0950926
X0752599Y0964312
X0752599Y0971005
X0752599Y0957619
X0752599Y0977698
X0752599Y0984391
X0740857Y0905750
X0741907Y0910769
X0747149Y0907423
X0741907Y0900730
X0747149Y0897383
X0752599Y0914115
X0752599Y0920808
X0747149Y0934194
X0752599Y0847186
X0752599Y0840493
X0741907Y0863919
X0747149Y0860572
X0752599Y0853879
X0740857Y0868938
X0747149Y0870611
X0741907Y0873958
X0752599Y0877304
R02Y0006693
X0740857Y0795316
X0741907Y0800336
X0747149Y0796989
X0752599Y0803682
X0752599Y0817068
X0752599Y0810375
X0740857Y0832127
X0741907Y0837147
X0741907Y0827108
X0747149Y0833800
X0747149Y0823761
X0741907Y0790297
X0747149Y0786950
X0752599Y0780257
X0727777Y1375434
X0725333Y1375418
X0732797Y1375380
X0736280Y1379580
X0736457Y1225336
X0727298Y1233702
X0736457Y1248761
X0736457Y1255454
X0735954Y1297546
X0735954Y1300046
X0735954Y1302646
X0735954Y1305246
X0730900Y1349231
X0727098Y1349077
X0730900Y1352131
X0727098Y1351977
X0731447Y1370280
X0731447Y1367680
X0734047Y1367680
X0734047Y1370280
X0731447Y1372880
X0734047Y1372880
X0728348Y1377875
X0728348Y1380832
X0736457Y1188525
X0736457Y1181832
X0727298Y1196891
X0736457Y1218643
X0736457Y1211950
X0736457Y1138328
R02Y0006693
X0727298Y1160080
X0736457Y1175139
X0736457Y1101517
X0736457Y1108210
X0736457Y1114903
X0727298Y1123269
X0736457Y1041281
X0736457Y1034588
X0736457Y1054667
X0736457Y1047974
X0736457Y1061360
X0736457Y1071399
X0736457Y1078092
X0727298Y1086458
X0736457Y0967659
X0736457Y0960966
X0736457Y0981045
X0736457Y0974352
X0736457Y0994430
X0736457Y0987737
X0736457Y1004470
X0736457Y0917462
X0736457Y0924155
X0736457Y0930848
X0727298Y0939214
X0736457Y0954273
X0736457Y0880651
X0736457Y0894037
X0736457Y0887344
X0727298Y0902403
X0736457Y0820415
X0736457Y0813722
X0727298Y0828781
X0736457Y0850533
X0736457Y0843840
X0736457Y0857226
X0727298Y0865592
X0736457Y0776911
X0727298Y0791970
X0736457Y0783604
X0736457Y0807029
X0709551Y1406578
X0722141Y1405912
X0712433Y1375418
X0717633Y1375418
X0715033Y1375418
X0717633Y1381482
X0712433Y1378525
X0717633Y1378525
X0715033Y1378525
X0714277Y1385281
X0722833Y1375418
X0720233Y1375418
X0720233Y1381482
X0720233Y1378525
X0716707Y1390881
X0714277Y1390881
X0719137Y1390881
X0719186Y1403296
X0722898Y1245415
X0722898Y1252108
X0712206Y1242068
X0711954Y1297546
X0721361Y1297546
X0711954Y1300046
R02Y0002600
X0721361Y1300046
R02Y0002600
X0710221Y1349488
X0710221Y1351988
X0719137Y1385281
X0716707Y1385281
X0712206Y1205257
X0717448Y1201911
X0711156Y1200238
X0712206Y1195218
X0722898Y1208604
X0722898Y1221989
X0722898Y1215297
X0711156Y1237049
X0717448Y1238722
X0712206Y1232029
X0717448Y1228682
X0712206Y1158407
X0717448Y1155060
X0711156Y1163427
X0717448Y1165100
X0712206Y1168446
X0722898Y1171793
X0722898Y1178486
X0717448Y1191871
X0722898Y1185178
X0722898Y1104863
X0722898Y1098171
X0717448Y1118249
X0722898Y1111556
X0712206Y1131635
X0722898Y1134982
X0711156Y1126616
X0712206Y1121596
X0717448Y1128289
X0722898Y1141675
X0722898Y1148367
X0722898Y1074745
X0722898Y1068052
X0711156Y1089805
X0712206Y1084785
X0717448Y1081438
X0717448Y1091478
X0712206Y1094824
X0722898Y0997777
X0722898Y0991084
X0722898Y1004470
X0722898Y1044627
X0722898Y1037934
X0722898Y1031241
X0722898Y1058013
X0722898Y1051320
X0717448Y0934194
X0712206Y0937541
X0722898Y0927501
X0711156Y0942561
X0712206Y0947580
X0717448Y0944234
X0722898Y0950926
X0722898Y0964312
X0722898Y0971005
X0722898Y0957619
X0722898Y0977698
X0722898Y0984391
X0722898Y0890690
X0711156Y0905750
X0712206Y0910769
X0717448Y0907423
X0712206Y0900730
X0717448Y0897383
X0722898Y0914115
X0722898Y0920808
X0722898Y0840493
X0722898Y0847186
X0712206Y0863919
X0717448Y0860572
X0722898Y0853879
X0711156Y0868938
X0717448Y0870611
X0712206Y0873958
X0722898Y0877304
X0722898Y0883997
X0717448Y0796989
X0711156Y0795316
X0712206Y0800336
X0722898Y0803682
X0722898Y0817068
X0722898Y0810375
X0711156Y0832127
X0712206Y0837147
X0712206Y0827108
X0717448Y0833800
X0717448Y0823761
X0712206Y0790297
X0717448Y0786950
X0722898Y0780257
X0661713Y1373981
X0706756Y1248761
X0706756Y1255454
X0697483Y1297506
X0697483Y1302606
X0697483Y1300006
X0697483Y1305206
X0701771Y1349488
X0701771Y1351988
X0699467Y1366110
X0699467Y1363510
X0699467Y1368710
X0703568Y1379476
X0706756Y1218643
X0706756Y1211950
X0706756Y1225336
X0706756Y1151714
X0706756Y1175139
X0706756Y1188525
X0706756Y1181832
X0706756Y1101517
X0706756Y1108210
X0706756Y1114903
X0706756Y1138328
X0706756Y1145021
X0706756Y1034588
X0706756Y1054667
X0706756Y1047974
X0706756Y1061360
X0706756Y1071399
X0706756Y1078092
X0706756Y0981045
X0706756Y0974352
X0706756Y0994430
X0706756Y0987737
X0706756Y1004470
X0706756Y1041281
X0706756Y0930848
X0706756Y0954273
X0706756Y0967659
X0706756Y0960966
X0706756Y0880651
X0706756Y0894037
X0706756Y0887344
X0706756Y0917462
X0706756Y0924155
X0706756Y0850533
X0706756Y0843840
X0706756Y0857226
X0706756Y0783604
X0706756Y0807029
X0706756Y0820415
X0706756Y0813722
X0706756Y0776911
X0683052Y1349548
X0683052Y1352048
X0685187Y1366100
X0685187Y1363500
X0685187Y1368700
X0650036Y1350877
X0653836Y1350877
X0657836Y1350877
X0661685Y1367283
X0659559Y1391027
X0655702Y1391107
X0647445Y1392605
X0688076Y1297506
X0688076Y1302606
X0688076Y1300006
X0688076Y1305206
X0643395Y1372857
X0644795Y1378257
X0632695Y1378257
X0638695Y1378257
X0632695Y1372257
X0643563Y1392581
X0674552Y1349488
X0674552Y1351988
X0638436Y1350877
X0646236Y1350877
X0642436Y1350877
X0644795Y1366157
X0632695Y1366157
X0638695Y1366157
X0616527Y1390732
X0616654Y1382864
X0739888Y1404849
X0738230Y1402898
X0722898Y0773564
R02X0029701
X0812000Y0773564
X0663496Y0780257
X0658046Y0786950
X0652804Y0790297
X0677055Y0783604
X0667896Y0791970
X0693197Y0780257
X0687747Y0786950
X0682505Y0790297
X0697597Y0791970
X0663496Y0803682
X0658046Y0796989
X0652804Y0800336
X0651754Y0795316
X0677055Y0807029
X0693197Y0803682
X0687747Y0796989
X0682505Y0800336
X0681455Y0795316
X0663496Y0817068
X0663496Y0810375
X0677055Y0820415
X0677055Y0813722
X0693197Y0817068
X0693197Y0810375
X0658046Y0823761
X0658046Y0833800
X0652804Y0827108
X0652804Y0837147
X0651754Y0832127
X0667896Y0828781
X0687747Y0823761
X0687747Y0833800
X0682505Y0827108
X0682505Y0837147
X0681455Y0832127
X0697597Y0828781
X0663496Y0847186
X0663496Y0840493
X0677055Y0850533
X0677055Y0843840
X0693197Y0847186
X0693197Y0840493
X0663496Y0853879
X0658046Y0860572
X0652804Y0863919
X0677055Y0857226
X0667896Y0865592
X0693197Y0853879
X0687747Y0860572
X0682505Y0863919
X0697597Y0865592
X0663496Y0877304
X0658046Y0870611
X0652804Y0873958
X0651754Y0868938
X0677055Y0880651
X0693197Y0877304
X0687747Y0870611
X0682505Y0873958
X0681455Y0868938
X0663496Y0890690
X0663496Y0883997
X0677055Y0894037
X0677055Y0887344
X0693197Y0890690
X0693197Y0883997
X0658046Y0907423
X0658046Y0897383
X0652804Y0910769
X0652804Y0900730
X0651754Y0905750
X0667896Y0902403
X0687747Y0907423
X0687747Y0897383
X0682505Y0910769
X0682505Y0900730
X0681455Y0905750
X0697597Y0902403
X0663496Y0920808
X0663496Y0914115
X0677055Y0924155
X0677055Y0917462
X0693197Y0920808
X0693197Y0914115
X0663496Y0927501
X0658046Y0934194
X0652804Y0937541
X0677055Y0930848
X0667896Y0939214
X0693197Y0927501
X0687747Y0934194
X0682505Y0937541
X0697597Y0939214
X0663496Y0950926
X0658046Y0944234
X0652804Y0947580
X0651754Y0942561
X0677055Y0954273
X0693197Y0950926
X0687747Y0944234
X0682505Y0947580
X0681455Y0942561
X0663496Y0971005
R02Y-0006693
X0677055Y0967659
X0677055Y0960966
X0693197Y0971005
R02Y-0006693
X0663496Y0984391
X0663496Y0977698
X0677055Y0981045
X0677055Y0974352
X0693197Y0984391
X0693197Y0977698
X0663496Y0997777
X0663496Y0991084
X0677055Y0994430
X0677055Y0987737
X0693197Y0997777
X0693197Y0991084
X0663496Y1004470
X0677055Y1004470
X0693197Y1004470
X0663496Y1044627
R02Y-0006693
X0677055Y1041281
X0677055Y1034588
X0693197Y1044627
R02Y-0006693
X0677055Y1047974
X0770990Y1351991
X0770990Y1349091
X0647354Y0776911
X0634288Y0766646
X0233969Y0773564
X0217827Y0776911
X0229419Y0763119
X0222377Y0767266
X0204268Y0773564
X0188126Y0776911
X0199718Y0763766
X0192676Y0767266
X0174567Y0773564
X0162975Y0767266
X0170017Y0763766
X0144866Y0773564
X0133124Y0767266
X0140316Y0763766
X0115166Y0773564
X0103574Y0767266
X0110616Y0763766
X0085465Y0773564
X0080915Y0763766
X0064923Y0795316
X0064923Y0868938
X0064923Y0832127
X0064923Y0905750
X0064923Y0942561
X0064923Y1126616
X0064923Y1089805
R02Y0073622
X0064923Y1200238
X0081065Y0791970
X0074773Y0790297
X0069323Y0783604
X0080015Y0786950
X0069323Y0776911
X0069323Y0850533
X0069323Y0843840
X0074773Y0837147
X0074773Y0827108
X0081065Y0828781
X0080015Y0833800
X0080015Y0823761
X0069323Y0820415
X0069323Y0813722
X0074773Y0800336
X0069323Y0807029
X0080015Y0796989
X0081065Y0902403
X0080015Y0897383
X0069323Y0894037
X0069323Y0887344
X0074773Y0873958
X0069323Y0880651
X0080015Y0870611
X0074773Y0863919
X0069323Y0857226
X0081065Y0865592
X0080015Y0860572
X0069323Y0967659
X0069323Y0960966
X0074773Y0947580
X0069323Y0954273
X0080015Y0944234
X0069323Y0930848
X0074773Y0937541
X0080015Y0934194
X0081065Y0939214
X0069323Y0917462
X0069323Y0924155
X0074773Y0910769
X0080015Y0907423
X0074773Y0900730
X0069323Y1061360
X0069323Y1071399
X0069323Y1054667
R03Y-0006693
X0069323Y1004470
X0069323Y0994430
X0069323Y0987737
X0069323Y0981045
X0069323Y0974352
X0074773Y1131635
X0074773Y1121596
X0081065Y1123269
X0080015Y1128289
X0069323Y1108210
X0069323Y1114903
X0080015Y1118249
X0074773Y1094824
X0069323Y1101517
X0080015Y1091478
X0069323Y1078092
X0074773Y1084785
X0081065Y1086458
X0080015Y1081438
X0069323Y1188525
X0080015Y1191871
X0069323Y1181832
X0074773Y1168446
X0069323Y1175139
X0074773Y1158407
X0069323Y1151714
X0080015Y1155060
X0081065Y1160080
X0080015Y1165100
X0069323Y1138328
X0069323Y1145021
X0069323Y1255454
X0069323Y1248761
X0074773Y1242068
X0074773Y1232029
X0069323Y1225336
X0081065Y1233702
X0080015Y1228682
X0080015Y1238722
X0069323Y1218643
X0069323Y1211950
X0074773Y1205257
X0074773Y1195218
X0080015Y1201911
X0081065Y1196891
X0085465Y0780257
X0085465Y0817068
X0085465Y0810375
X0094624Y0795316
X0085465Y0803682
X0094624Y0832127
X0085465Y0853879
R02Y-0006693
X0085465Y0883997
X0085465Y0890690
X0094624Y0868938
X0085465Y0877304
X0085465Y0914115
X0085465Y0920808
X0094624Y0905750
X0094624Y0942561
X0085465Y0950926
X0085465Y0927501
X0085465Y0964312
X0085465Y0971005
X0085465Y0957619
X0085465Y1004470
X0085465Y0997777
X0085465Y0991084
X0085465Y0977698
X0085465Y0984391
X0085465Y1058013
X0085465Y1051320
X0085465Y1037934
X0085465Y1031241
X0085465Y1044627
X0094624Y1089805
X0085465Y1074745
X0085465Y1068052
X0085465Y1111556
X0085465Y1104863
X0085465Y1098171
X0085465Y1141675
X0085465Y1148367
X0085465Y1134982
X0094624Y1126616
X0085465Y1171793
X0085465Y1178486
X0094624Y1163427
X0094624Y1200238
X0085465Y1208604
X0085465Y1185178
X0094624Y1237049
X0085465Y1221989
X0085465Y1215297
X0085465Y1245415
X0085465Y1252108
X0110766Y0791970
X0109716Y0786950
X0099024Y0783604
X0104474Y0790297
X0099024Y0776911
X0110766Y0828781
X0109716Y0833800
X0109716Y0823761
X0104474Y0837147
X0104474Y0827108
X0099024Y0820415
X0099024Y0813722
X0109716Y0796989
X0104474Y0800336
X0099024Y0807029
X0099024Y0894037
X0099024Y0887344
X0109716Y0870611
X0104474Y0873958
X0099024Y0880651
X0110766Y0865592
X0109716Y0860572
X0104474Y0863919
X0099024Y0857226
R02Y-0006693
X0099024Y0967659
X0099024Y0960966
X0109716Y0944234
X0104474Y0947580
X0099024Y0954273
X0109716Y0934194
X0110766Y0939214
X0099024Y0930848
X0104474Y0937541
X0099024Y0917462
X0099024Y0924155
X0109716Y0907423
X0104474Y0910769
X0110766Y0902403
X0109716Y0897383
X0104474Y0900730
X0104474Y1084785
X0099024Y1061360
X0099024Y1071399
X0099024Y1054667
R03Y-0006693
X0099024Y1004470
X0099024Y0994430
X0099024Y0987737
X0099024Y0981045
X0099024Y0974352
X0099024Y1138328
X0099024Y1145021
X0104474Y1131635
X0110766Y1123269
X0109716Y1128289
X0104474Y1121596
X0109716Y1118249
X0099024Y1108210
X0099024Y1114903
X0109716Y1091478
X0104474Y1094824
X0099024Y1101517
X0110766Y1086458
X0109716Y1081438
X0099024Y1078092
X0099024Y1218643
X0099024Y1211950
X0109716Y1201911
X0110766Y1196891
X0104474Y1205257
X0104474Y1195218
X0109716Y1191871
X0099024Y1188525
X0099024Y1181832
X0104474Y1168446
X0099024Y1175139
X0109716Y1155060
X0110766Y1160080
X0109716Y1165100
X0099024Y1151714
X0104474Y1158407
X0099024Y1255454
X0099024Y1248761
X0104474Y1242068
X0110766Y1233702
X0109716Y1238722
X0109716Y1228682
X0099024Y1225336
X0104474Y1232029
X0115166Y0780257
X0115166Y0803682
X0124324Y0795316
X0124324Y0832127
X0115166Y0817068
X0115166Y0810375
X0115166Y0847186
X0115166Y0840493
X0124324Y0868938
X0115166Y0877304
X0115166Y0853879
X0124324Y0905750
X0115166Y0883997
X0115166Y0890690
X0124324Y0942561
X0115166Y0950926
X0115166Y0927501
X0115166Y0914115
X0115166Y0920808
X0115166Y0977698
X0115166Y0984391
X0115166Y0964312
X0115166Y0971005
X0115166Y0957619
X0115166Y1058013
X0115166Y1051320
R03Y-0006693
X0115166Y1004470
R02Y-0006693
X0124324Y1089805
X0115166Y1074745
X0115166Y1068052
X0115166Y1134982
X0124324Y1126616
X0115166Y1111556
X0115166Y1104863
X0115166Y1098171
X0115166Y1171793
X0115166Y1178486
X0124324Y1163427
X0115166Y1141675
X0115166Y1148367
X0124324Y1200238
X0115166Y1208604
X0115166Y1185178
X0115166Y1245415
X0115166Y1252108
X0124324Y1237049
X0115166Y1221989
X0115166Y1215297
X0128724Y0776911
X0128724Y0820415
X0128724Y0813722
X0139416Y0796989
X0134174Y0800336
X0128724Y0807029
X0140466Y0791970
X0128724Y0783604
X0139416Y0786950
X0134174Y0790297
X0140466Y0865592
X0139416Y0860572
X0134174Y0863919
X0128724Y0857226
R02Y-0006693
X0134174Y0827108
X0140466Y0828781
X0139416Y0833800
X0139416Y0823761
X0134174Y0837147
X0128724Y0930848
X0139416Y0934194
X0140466Y0939214
X0134174Y0937541
X0128724Y0917462
X0128724Y0924155
X0139416Y0907423
X0134174Y0910769
X0140466Y0902403
X0139416Y0897383
X0134174Y0900730
X0128724Y0894037
X0128724Y0887344
X0139416Y0870611
X0128724Y0880651
X0134174Y0873958
X0128724Y1004470
X0128724Y0994430
X0128724Y0987737
X0128724Y0981045
X0128724Y0974352
R02Y-0006693
X0139416Y0944234
X0134174Y0947580
X0128724Y0954273
X0134174Y1094824
X0139416Y1091478
X0128724Y1101517
X0128724Y1078092
X0140466Y1086458
X0134174Y1084785
X0139416Y1081438
X0128724Y1061360
X0128724Y1071399
X0128724Y1054667
R03Y-0006693
X0128724Y1151714
X0139416Y1155060
X0134174Y1158407
X0140466Y1160080
X0139416Y1165100
X0128724Y1138328
X0128724Y1145021
X0134174Y1131635
X0140466Y1123269
X0134174Y1121596
X0139416Y1128289
X0128724Y1108210
X0139416Y1118249
X0128724Y1114903
X0139416Y1238722
X0140466Y1233702
X0139416Y1228682
X0128724Y1218643
X0128724Y1211950
X0139416Y1201911
X0134174Y1205257
X0140466Y1196891
X0134174Y1195218
X0128724Y1188525
X0139416Y1191871
X0128724Y1181832
X0134174Y1168446
X0128724Y1175139
X0128724Y1255454
X0128724Y1248761
X0134174Y1242068
X0134174Y1232029
X0128724Y1225336
X0144866Y0780257
X0144866Y0803682
X0154025Y0795316
X0154025Y0832127
X0144866Y0817068
X0144866Y0810375
X0144866Y0847186
X0144866Y0840493
X0144866Y0853879
X0154025Y0905750
X0144866Y0883997
X0144866Y0890690
X0154025Y0868938
X0144866Y0877304
X0144866Y0927501
X0144866Y0914115
X0144866Y0920808
X0144866Y0977698
X0144866Y0984391
X0144866Y0964312
X0144866Y0971005
X0144866Y0957619
X0144866Y0950926
X0154025Y0942561
X0144866Y1044627
R02Y-0006693
X0144866Y1004470
R02Y-0006693
X0154025Y1089805
X0144866Y1074745
X0144866Y1068052
X0144866Y1058013
X0144866Y1051320
X0144866Y1111556
X0144866Y1104863
X0144866Y1098171
X0154025Y1163427
X0144866Y1141675
X0144866Y1148367
X0144866Y1134982
X0154025Y1126616
X0154025Y1200238
X0144866Y1208604
X0144866Y1185178
X0144866Y1171793
X0144866Y1178486
X0154025Y1237049
X0144866Y1221989
X0144866Y1215297
X0144866Y1245415
X0144866Y1252108
X0158425Y0776911
X0163875Y0827108
X0158425Y0820415
X0158425Y0813722
X0169117Y0796989
X0158425Y0807029
X0163875Y0800336
X0170167Y0791970
X0169117Y0786950
X0158425Y0783604
X0163875Y0790297
X0158425Y0894037
X0158425Y0887344
X0169117Y0870611
X0158425Y0880651
X0163875Y0873958
X0170167Y0865592
X0169117Y0860572
X0158425Y0857226
X0163875Y0863919
X0158425Y0850533
X0158425Y0843840
X0170167Y0828781
X0169117Y0833800
X0169117Y0823761
X0163875Y0837147
X0169117Y0934194
X0170167Y0939214
X0158425Y0930848
X0163875Y0937541
X0158425Y0917462
X0158425Y0924155
X0169117Y0907423
X0163875Y0910769
X0170167Y0902403
X0169117Y0897383
X0163875Y0900730
X0158425Y1004470
X0158425Y0994430
X0158425Y0987737
X0158425Y0981045
X0158425Y0974352
R02Y-0006693
X0169117Y0944234
X0158425Y0954273
X0163875Y0947580
X0169117Y1091478
X0158425Y1101517
X0163875Y1094824
X0170167Y1086458
X0169117Y1081438
X0158425Y1078092
X0163875Y1084785
X0158425Y1061360
X0158425Y1071399
X0158425Y1054667
R03Y-0006693
X0158425Y1151714
X0163875Y1158407
X0158425Y1138328
X0158425Y1145021
X0163875Y1131635
X0170167Y1123269
X0169117Y1128289
X0163875Y1121596
X0169117Y1118249
X0158425Y1108210
X0158425Y1114903
X0158425Y1218643
X0158425Y1211950
X0169117Y1201911
X0170167Y1196891
X0163875Y1205257
X0163875Y1195218
X0169117Y1191871
X0158425Y1188525
R02Y-0006693
X0163875Y1168446
X0169117Y1155060
X0170167Y1160080
X0169117Y1165100
X0158425Y1255454
X0158425Y1248761
X0163875Y1242068
X0170167Y1233702
X0169117Y1228682
X0169117Y1238722
X0158425Y1225336
X0163875Y1232029
X0174567Y0817068
R02Y-0006693
X0174567Y0780257
X0174567Y0847186
X0174567Y0840493
X0174567Y0883997
X0174567Y0890690
X0174567Y0877304
X0174567Y0853879
X0174567Y0914115
X0174567Y0920808
X0174567Y0964312
X0174567Y0971005
X0174567Y0957619
X0174567Y0950926
X0174567Y0927501
X0174567Y1004470
R02Y-0006693
X0174567Y0977698
X0174567Y0984391
X0174567Y1058013
R04Y-0006693
X0174567Y1104863
X0174567Y1098171
X0174567Y1074745
X0174567Y1068052
X0174567Y1134982
X0174567Y1111556
X0174567Y1171793
X0174567Y1178486
X0174567Y1141675
X0174567Y1148367
X0174567Y1208604
X0174567Y1185178
X0174567Y1245415
X0174567Y1252108
X0174567Y1221989
X0174567Y1215297
X1783592Y0756765
X1776550Y0760265
X1776550Y0756765
X1753892Y0756765
X1746850Y0760265
X1746850Y0756765
X1724191Y0756765
X1717149Y0760265
X1717149Y0756765
X1694490Y0756765
X1687448Y0760265
X1687448Y0756765
X1664789Y0756765
X1657747Y0760265
X1657747Y0756765
X1635088Y0756765
X1628046Y0760265
X1628046Y0756765
X1205561Y0756765
X1198519Y0760265
X1198519Y0756765
X1175860Y0756765
X1168818Y0760265
X1168818Y0756765
X1146159Y0756765
X1139117Y0760265
X1139117Y0756765
X1116458Y0756765
X1109416Y0760265
X1109416Y0756765
X1086758Y0756765
X1079716Y0760265
X1079716Y0756765
X1057057Y0756765
X1050015Y0760265
X1050015Y0756765
X1025493Y0758819
X1007703Y0759012
X0872986Y0753451
X0869406Y0753541
X0800408Y0760266
X0800408Y0756766
X0807450Y0756766
X0770708Y0760266
X0770708Y0756766
X0777900Y0756766
X0741007Y0760266
X0741007Y0756766
X0748049Y0756766
X0718348Y0756766
X0711306Y0760178
X0711306Y0756766
X0688647Y0756766
X0681671Y0760178
X0681605Y0756766
X0651904Y0760266
X0651904Y0756766
X0658946Y0756766
X0229419Y0756766
X0222377Y0756766
X0222377Y0760266
X0199718Y0756766
X0192676Y0756766
X0192676Y0760266
X0170017Y0756766
X0162975Y0756766
X0162975Y0760266
X0133124Y0760266
X0133124Y0756766
X0140316Y0756766
X0103574Y0760266
X0103574Y0756766
X0110616Y0756766
X0073873Y0760266
X0073873Y0756766
X0080915Y0756766
X0035852Y0694822
X0035852Y0697322
X1708305Y0679720
X0688078Y0675493
X0654676Y0674806
X0643649Y0674781
X0640129Y0674890
X0634529Y0674890
X0152705Y0683218
X0035852Y0675510
X0035852Y0683910
X0035852Y0686410
X1745502Y0660088
X1742652Y0671494
X1726334Y0670345
X1207177Y0668115
X1201440Y0668138
X0946366Y0668811
X0930926Y0664791
X0906570Y0663930
X0660062Y0672761
X0149672Y0665500
X0035852Y0664480
X0035852Y0673010
X1733083Y0654034
X1723259Y0653641
X1718241Y0652105
X0726952Y0648667
X0712319Y0654954
X1706101Y0641658
X1701121Y0641658
X0951099Y0632206
X0935783Y0634051
X0867590Y0642420
X0724001Y0636790
X0713280Y0636897
X1132387Y0615658
X0955529Y0614017
X0927127Y0619251
X0906734Y0619373
X0906597Y0628426
X1195729Y0591022
X0939391Y0600571
X0926983Y0604751
X0899678Y0601043
X0903556Y0614062
X0715037Y0603278
X0697392Y0601686
X1181445Y0592868
X1191646Y0589567
X1188192Y0589263
X0935649Y0590751
X0945006Y0593609
X0907035Y0590172
X0902376Y0594657
X0714583Y0587642
X0651046Y0587300
X0645446Y0587300
X0639482Y0587488
X0633882Y0587488
X1208400Y0591631
X1185117Y0571807
X0934302Y0578318
X0906597Y0579695
X0711556Y0575081
X0701496Y0580556
X0691496Y0575081
X1032579Y0559934
X1027579Y0558932
X1022461Y0558932
X1015961Y0554432
X0914575Y0560027
X0823777Y0560988
X1771236Y0557224
X1043180Y0547027
X1027520Y0552724
X1015061Y0547574
X1012211Y0547574
X0826552Y0543612
X0740638Y0549900
X0738260Y0553625
X0704500Y0555862
X0700500Y0545862
X0370090Y0697482
X0404771Y0698670
X0401880Y0696220
X0371724Y0699450
X0337030Y0697750
X0338664Y0699660
X0402457Y0722615
X0395179Y0723792
X0392579Y0723792
X0395179Y0726899
X0392579Y0726899
X0382435Y0726883
X0389979Y0723792
X0389979Y0726899
X0384879Y0726899
X0387379Y0726899
X0381802Y0723746
X0369557Y0722615
X0377415Y0726937
X0378765Y0732037
X0376165Y0732037
X0378765Y0729437
X0376165Y0729437
X0364739Y0723724
X0359539Y0723724
X0362139Y0723724
X0356939Y0723724
X0364739Y0726831
X0359539Y0726831
X0362139Y0726831
X0356939Y0726831
X0354339Y0726831
X0351839Y0726831
X0336457Y0722815
X0349395Y0726815
X0344375Y0726869
X0343125Y0731969
X0345725Y0731969
X0343125Y0729369
X0345725Y0729369
X0348449Y0723784
X0331679Y0723992
R03X-0002600
X0331679Y0727099
R03X-0002600
X0318779Y0727099
X0311315Y0727137
X0316335Y0727083
X0310065Y0732237
X0310065Y0729637
X0312665Y0732237
X0312665Y0729637
X0321279Y0727099
X0315912Y0723996
X0298991Y0726348
X0305121Y0726348
X0279171Y0724988
X0277055Y0722649
X0397779Y0723792
X0397779Y0726899
X0310065Y0734837
X0312665Y0734837
X0313255Y0746279
X0343125Y0734569
X0345725Y0734569
X0349625Y0746269
X0342425Y0746269
X0339825Y0746269
X0362625Y0746269
X0360025Y0746269
X0352225Y0746269
X0378765Y0734637
X0376165Y0734637
X0370825Y0746169
X0373425Y0746169
X0439011Y0741317
X0436411Y0741317
X0439011Y0743917
X0436411Y0743917
X0439011Y0738717
X0436411Y0738717
X0436811Y0736147
X0439411Y0736147
X0436811Y0733527
X0439411Y0733527
X0513012Y0617749
X0513012Y0620706
X0283062Y0703936
X0283062Y0700979
X0315912Y0721039
X0348449Y0720827
X0381802Y0720789
X0414682Y0706096
X0414682Y0703139
X0447162Y0681366
X0447162Y0678409
X0479822Y0654946
X0479822Y0651989
X0524805Y0614036
X0522375Y0614036
X0491505Y0648136
X0489075Y0648136
X0458905Y0674636
X0456475Y0674636
X0426505Y0699236
X0424075Y0699236
X0393505Y0717036
X0391075Y0717036
X0360465Y0716968
X0358035Y0716968
X0327405Y0717236
X0324975Y0717236
X0294635Y0697086
X0292205Y0697086
X0376600Y0577400
X0376671Y0562380
X0369171Y0569880
X0328966Y0548030
X0328966Y0543012
X0239843Y0709715
X0391026Y0699021
X0357986Y0698953
X0319657Y0696415
X0324926Y0699221
X0287832Y0674150
X0304301Y0679037
X0292156Y0679071
X0540106Y0657325
X0271571Y0644796
X0259426Y0644830
X0254671Y0642138
X0501171Y0630087
X0489026Y0630121
X0452565Y0652837
X0456426Y0656621
X0424026Y0681221
X0547993Y0616406
X0553993Y0616406
X0550993Y0616406
X0533857Y0619615
X0527235Y0614036
X0527235Y0608436
X0521279Y0617835
X0523879Y0617835
X0522375Y0608436
X0524805Y0608436
X0559993Y0616406
X0556993Y0616406
X0221493Y0676906
X0270857Y0668515
X0260979Y0672708
R02X0002600
X0260979Y0669601
X0260979Y0666644
X0266179Y0669601
X0263579Y0669601
X0264335Y0662845
X0255779Y0672708
X0258379Y0672708
X0258379Y0669601
X0258379Y0666644
X0259475Y0657245
R02X0002430
X0253279Y0672708
X0250835Y0672692
X0247165Y0675246
X0245815Y0672746
X0244565Y0675246
X0230493Y0676906
X0224493Y0676906
X0227493Y0676906
X0495779Y0657999
X0495779Y0654892
X0500457Y0653715
X0485379Y0657999
R02X0002600
X0490579Y0654892
X0487979Y0654892
X0493179Y0657999
X0493179Y0654892
X0490579Y0651935
X0487979Y0651935
X0493935Y0648136
X0480435Y0657983
X0482879Y0657999
X0491505Y0642536
X0489075Y0642536
X0493935Y0642536
X0474165Y0665737
X0476765Y0665737
X0474165Y0663137
X0476765Y0663137
X0469046Y0657062
X0474165Y0660537
X0476765Y0660537
X0475415Y0658037
X0461335Y0674636
X0461335Y0669036
X0456475Y0669036
X0458905Y0669036
X0528771Y0643138
X0534271Y0643138
X0529079Y0623899
X0529079Y0620792
X0521771Y0643138
X0514771Y0643138
X0516179Y0623899
X0518679Y0623899
X0521279Y0623899
X0523879Y0623899
X0521279Y0620792
X0523879Y0620792
X0513735Y0623883
X0526479Y0623899
X0526479Y0620792
X0507465Y0631637
X0510065Y0631637
X0507465Y0626437
X0507465Y0629037
X0508715Y0623937
X0510065Y0626437
X0510065Y0629037
X0277295Y0714687
R02Y-0002600
X0272603Y0695510
X0272603Y0692910
X0263839Y0692049
X0247165Y0680446
X0254448Y0692050
X0247165Y0677846
X0244565Y0680446
X0239443Y0691015
X0242543Y0691115
X0244565Y0677846
X0233493Y0676906
X0327405Y0711636
X0329835Y0717236
X0323879Y0721035
X0326479Y0721035
X0324975Y0711636
X0329835Y0711636
X0303657Y0702815
X0296309Y0706949
X0296309Y0703842
X0298909Y0706949
X0298909Y0703842
X0297065Y0697086
X0288509Y0706949
X0291109Y0706949
X0291109Y0703842
X0293709Y0706949
X0293709Y0703842
X0291109Y0700885
X0293709Y0700885
X0294635Y0691486
X0297065Y0691486
X0292205Y0691486
X0279895Y0714687
X0279895Y0712087
X0278545Y0706987
X0286009Y0706949
X0283565Y0706933
X0279895Y0709487
X0389979Y0720835
X0391075Y0711436
X0356939Y0720767
X0359539Y0720767
X0358035Y0711368
X0362895Y0711368
X0360465Y0711368
X0362895Y0716968
X0447835Y0684483
X0443235Y0684637
X0436130Y0683281
X0441565Y0687037
R02Y0002600
X0444165Y0687037
X0444165Y0692237
X0444165Y0689637
X0440591Y0684518
X0443991Y0719437
X0443991Y0716837
X0446591Y0719437
X0446591Y0716837
X0435457Y0704915
X0441725Y0702449
X0444325Y0702449
X0422979Y0705992
X0425579Y0705992
X0422979Y0703035
X0425579Y0703035
X0428179Y0705992
X0420379Y0709099
R03X0002600
X0428935Y0699236
X0417879Y0709099
X0415435Y0709083
X0430779Y0705992
X0430779Y0709099
X0424075Y0693636
X0428935Y0693636
X0426505Y0693636
X0409165Y0716837
R02Y-0002600
X0411765Y0716837
R02Y-0002600
X0410415Y0709137
X0392579Y0720835
X0393505Y0711436
X0395935Y0711436
X0395935Y0717036
X0463179Y0681392
X0463179Y0684499
X0467957Y0680315
X0455379Y0681392
X0452779Y0684499
X0455379Y0684499
X0457979Y0681392
X0460579Y0681392
X0457979Y0684499
X0460579Y0684499
X0450279Y0684499
X0455379Y0678435
X0457979Y0678435
X0534471Y0595987
X0522326Y0596021
X0385443Y0597279
X0343182Y0591335
X0343182Y0586415
X0403157Y0569415
X0351157Y0574415
X0265100Y0595078
X0266601Y0586578
X0274201Y0579478
X0292705Y0580275
X0203754Y0595174
X0200754Y0603274
X0203754Y0603274
X0200754Y0595174
X0203605Y0632385
X0206805Y0632385
X0200405Y0632385
X0200405Y0622385
X0203605Y0622385
X0206805Y0622385
X0236638Y0593556
X0233438Y0593556
X0283705Y0611485
X0284705Y0605485
X0283705Y0608485
X0286665Y0609470
X0280305Y0611485
X0273905Y0611485
X0277105Y0611485
X0280305Y0608485
X0273905Y0608485
X0277105Y0608485
X0270905Y0608485
X0304449Y0609570
X0311349Y0609632
X0300965Y0609570
X0307865Y0609570
X0290865Y0609470
X0297838Y0609585
X0294165Y0609570
X0403133Y0565415
X0351157Y0562415
X0399657Y0546915
X0387657Y0546876
X0391657Y0546816
X0395657Y0546894
X0356850Y0547893
X0350817Y0558248
X0353700Y0547893
X0345500Y0574415
X0369100Y0577400
X0384301Y0577446
X0369171Y0562380
X0384259Y0562426
X0333988Y0590633
X0281147Y0521803
X0272242Y0523076
X0250312Y0667180
X0250312Y0670080
X0261905Y0662845
X0259475Y0662845
X0334744Y0566086
X0488405Y0578572
X0365593Y0621622
X0077733Y0544464
X0048626Y0552365
X1513382Y0697750
X1515016Y0699670
X1480300Y0697750
X1481934Y0699670
X1497631Y0727099
X1495131Y0727099
X1492687Y0727083
X1487667Y0727137
X1492264Y0724106
X1474949Y0727099
X1469749Y0727099
X1472349Y0727099
X1472349Y0723992
X1474949Y0723992
X1469749Y0723992
X1479757Y0722865
X1467149Y0727099
X1467149Y0723992
X1464549Y0727099
X1462049Y0727099
X1459605Y0727083
X1454585Y0727137
X1455935Y0732237
X1455935Y0729637
X1458599Y0724002
X1453335Y0732237
X1453335Y0729637
X1422757Y0723597
X1422757Y0726097
X1578904Y0723840
X1545557Y0722897
X1553750Y0723840
X1551250Y0723840
X1535631Y0727099
X1533031Y0727099
X1535631Y0723992
X1533031Y0723992
X1530431Y0727099
X1540831Y0727099
X1538231Y0727099
X1540831Y0723992
X1538231Y0723992
X1520467Y0727137
X1519217Y0732237
X1519217Y0729637
X1527931Y0727099
X1525487Y0727083
X1521817Y0732237
X1521817Y0729637
X1525064Y0724106
X1508031Y0727099
R03X-0002600
X1508031Y0723992
R03X-0002600
X1512757Y0722897
X1489017Y0732237
X1489017Y0729687
X1486417Y0732237
X1486417Y0729637
X1453757Y0746097
X1453757Y0743597
X1453335Y0734837
X1455935Y0734837
X1481665Y0745809
X1484265Y0745809
X1489017Y0734837
X1486417Y0734837
X1508505Y0746119
X1505905Y0746119
X1518495Y0746119
X1515895Y0746119
X1519217Y0734837
X1521817Y0734837
X1543574Y0760361
X1543585Y0762919
X1543563Y0757803
X1546074Y0760361
X1546085Y0762919
X1546063Y0757803
X1545619Y0754832
X1548119Y0754832
X1545619Y0751952
X1548119Y0751952
X1546954Y0743561
X1546965Y0746119
X1554044Y0738059
X1554055Y0740617
X1556544Y0738059
X1556555Y0740617
X1562995Y0789522
X1608640Y0640660
X1426264Y0701572
X1426264Y0704529
X1458599Y0721045
X1492264Y0721149
X1525064Y0721149
X1558194Y0699209
X1558194Y0702166
X1590964Y0665440
X1590964Y0668397
X1623964Y0646440
X1623964Y0649397
X1360944Y0636042
X1360944Y0638999
X1393664Y0668992
X1393664Y0671949
X1635457Y0642527
X1633027Y0642527
X1602457Y0661527
X1600027Y0661527
X1569687Y0695296
X1567257Y0695296
X1536557Y0717236
X1534127Y0717236
X1503757Y0717404
X1501327Y0717404
X1470675Y0717236
X1468245Y0717236
X1437757Y0697659
X1435327Y0697659
X1405157Y0665079
X1402727Y0665079
X1372457Y0632179
X1370027Y0632179
X1303266Y0530413
X1303266Y0533713
X1299076Y0530023
X1341838Y0637721
X1344438Y0637721
X1333878Y0637721
X1339238Y0637721
X1336558Y0637721
X1317266Y0592522
X1317266Y0589522
X1308700Y0590300
X1300200Y0590600
X1325366Y0592522
X1325366Y0589522
X1494371Y0594462
X1439232Y0596291
X1498543Y0587841
X1532853Y0560264
X1443551Y0535318
X1464257Y0552977
X1465832Y0535330
X1318300Y0649000
X1632978Y0624512
X1645123Y0624478
X1369978Y0614164
X1382123Y0614130
X1613154Y0688238
X1613154Y0690738
X1587717Y0679128
X1585117Y0679128
X1586070Y0694330
X1586070Y0696830
X1567257Y0689696
X1572117Y0689696
X1569687Y0689696
X1566161Y0699095
X1566161Y0705159
X1566161Y0702052
X1568761Y0699095
X1571361Y0705159
X1571361Y0702052
X1568761Y0705159
X1568761Y0702052
X1573961Y0705159
X1573961Y0702052
X1572117Y0695296
X1578757Y0700965
X1578904Y0721340
X1558617Y0705143
X1561061Y0705159
X1553597Y0705197
X1554947Y0707697
X1554947Y0710297
X1552347Y0707697
X1552347Y0710297
X1554947Y0712897
X1552347Y0712897
X1563561Y0705159
X1538987Y0711636
X1538987Y0717236
X1533031Y0721035
X1535631Y0721035
X1534127Y0711636
X1536557Y0711636
X1500231Y0721035
X1502831Y0721035
X1503757Y0711636
X1501327Y0711636
X1506187Y0711636
X1506187Y0717236
X1467149Y0721035
X1469749Y0721035
X1473105Y0711636
R02X-0002430
X1473105Y0717236
X1434231Y0707522
X1434231Y0704415
X1434231Y0701458
X1426687Y0707506
X1429131Y0707522
X1431631Y0707522
X1440187Y0692059
R02X-0002430
X1446757Y0703265
X1439431Y0707522
X1442031Y0707522
X1442031Y0704415
X1439431Y0704415
X1436831Y0707522
X1436831Y0704415
X1436831Y0701458
X1440187Y0697659
X1421667Y0707560
X1423017Y0710060
X1423017Y0715260
X1423017Y0712660
X1387817Y0682680
X1390417Y0682680
X1387817Y0680080
X1390417Y0680080
X1388757Y0690897
X1388757Y0693397
X1416291Y0697631
X1416241Y0700281
X1420417Y0710060
X1420417Y0715260
X1420417Y0712660
X1653517Y0654928
X1652167Y0652428
X1656938Y0659021
X1653517Y0657528
X1653517Y0660128
X1651104Y0671768
X1662298Y0659021
R02X0002600
X1659618Y0659021
X1633027Y0636927
R02X0002430
X1620717Y0654928
X1619367Y0652428
X1624387Y0652374
X1618117Y0654928
X1637887Y0642527
X1631931Y0646326
X1634531Y0646326
X1629331Y0652390
X1626831Y0652390
X1631931Y0649283
X1637131Y0649283
X1634531Y0649283
X1639731Y0649283
X1631931Y0652390
X1637131Y0652390
X1634531Y0652390
X1639731Y0652390
X1644457Y0648265
X1650917Y0654928
X1618117Y0660128
X1620717Y0657528
X1620717Y0660128
X1618117Y0657528
X1623550Y0671768
X1621050Y0671768
X1650917Y0660128
X1650917Y0657528
X1648604Y0671768
X1602457Y0655927
X1600027Y0655927
X1604887Y0661527
X1604887Y0655927
X1598931Y0665326
X1598931Y0668283
X1598931Y0671390
X1601531Y0665326
X1601531Y0668283
X1601531Y0671390
X1604131Y0668283
X1604131Y0671390
X1606731Y0668283
X1606731Y0671390
X1615677Y0648488
X1611557Y0667165
X1596331Y0671390
X1585117Y0673928
X1585117Y0676528
X1587717Y0673928
X1587717Y0676528
X1593831Y0671390
X1591387Y0671374
X1586367Y0671428
X1579807Y0671268
X1402727Y0659479
X1401631Y0668878
X1401631Y0671835
X1401631Y0674942
X1399031Y0674942
X1396531Y0674942
X1394087Y0674926
X1387817Y0677480
X1389067Y0674980
X1390417Y0677480
X1407587Y0659479
X1405157Y0659479
X1414157Y0670665
X1407587Y0665079
X1404231Y0668878
X1409431Y0671835
R02X-0002600
X1406831Y0674942
X1409431Y0674942
X1404231Y0674942
X1370027Y0626579
X1368931Y0635978
X1368931Y0642042
X1368931Y0638935
X1372457Y0626579
X1374887Y0626579
X1374131Y0642042
X1374131Y0638935
X1374887Y0632179
X1381457Y0637865
X1371531Y0635978
X1371531Y0642042
X1371531Y0638935
X1376731Y0642042
X1376731Y0638935
X1371847Y0661328
X1380256Y0667466
X1380306Y0664816
X1352527Y0638278
X1355117Y0644580
X1356367Y0642080
X1357717Y0644580
X1361387Y0642026
X1363831Y0642042
X1366331Y0642042
X1355117Y0647180
X1355117Y0649780
X1357717Y0649780
X1357717Y0647180
X1357057Y0661328
X1364317Y0661368
X1546257Y0701097
X1534078Y0699221
X1599978Y0643512
X1562730Y0675180
X1566010Y0673210
X1567208Y0677281
X1576843Y0674425
X1402452Y0642825
X1402678Y0647064
X1414823Y0647030
X1354257Y0675765
X1436257Y0676265
X1435278Y0679644
X1447423Y0679610
X1468196Y0699221
X1468257Y0696265
X1501278Y0699221
X1456282Y0580977
R02Y-0004000
X1545960Y0565162
X1516257Y0559977
X1516357Y0555318
X1464257Y0564977
X1456282Y0568977
X1542902Y0543641
X1519930Y0543470
X1482257Y0567977
X1497257Y0567977
X1489757Y0567977
X1482257Y0560477
X1482257Y0552977
X1497257Y0560477
X1497257Y0552977
X1489757Y0552977
X1539693Y0535212
X1512757Y0537477
X1508757Y0537456
X1504757Y0537378
X1500757Y0537438
X1443551Y0539318
X1651959Y0689800
X1330758Y0535449
X1330773Y0531776
X1330820Y0525165
X1330758Y0528649
X1332673Y0549309
X1332673Y0545909
X1330658Y0542949
X1329673Y0549309
X1329673Y0545909
X1326673Y0544909
X1330658Y0538749
X1332673Y0552509
X1332673Y0555709
X1329673Y0552509
X1329673Y0555709
X1329673Y0558709
X1295532Y0539513
X1301666Y0555413
X1307766Y0563013
X1316266Y0564514
X1297487Y0590607
X1040097Y0529508
X1022686Y0538201
X1032354Y0538201
X1013306Y0528942
X1013306Y0526146
X0999031Y0528574
X0991031Y0528574
X0845126Y0530138
X0849126Y0530138
X0760500Y0534352
X0764500Y0534424
X0747637Y0534874
X0732500Y0533862
X0736500Y0533862
X0728500Y0533862
X0696500Y0529862
X0375943Y0524903
X0380771Y0524903
X0146982Y0526997
X0134812Y0530955
X0077790Y0537808
X0077733Y0526764
X0036402Y0528675
X1377862Y0511052
X1037212Y0510940
X1041254Y0523874
X1045254Y0521074
X1014206Y0510304
X0998056Y0523874
X0998056Y0518214
X0387440Y0525154
X0226687Y0522453
X0220687Y0522453
X0120891Y0521216
X0077790Y0520108
X0016342Y0516951
X0056719Y0531120
X0056800Y0524220
X0049889Y0531149
X0049848Y0524210
X0026887Y0541805
X0033257Y0540370
X0016512Y0533155
X0033184Y0523285
X0020587Y0523970
X1088730Y0509362
X0830743Y0500740
X0669955Y0495468
X0415984Y0507024
X0402184Y0507101
X1468395Y0487582
X1377862Y0485552
X1189540Y0481691
X1163113Y0481691
X1147813Y0492319
X1096473Y0489391
X1096473Y0484391
X1059055Y0492537
X1008789Y0493655
X1008789Y0488642
X0992037Y0485369
X0817426Y0487232
X0781242Y0489574
X0765008Y0487570
X0752409Y0484420
X0724143Y0484420
X0736661Y0484420
X0711544Y0484420
X0695796Y0487570
X0621309Y0483346
X0432343Y0494297
X0418543Y0494374
X0404743Y0494451
X0387184Y0494382
X0141642Y0491434
X1257016Y0467253
X1248902Y0470733
X1185707Y0470392
X1087000Y0477500
X1081133Y0461516
X1071239Y0479655
X0888560Y0469527
X0797252Y0471344
X0758709Y0468672
X0727292Y0474971
X0698946Y0468672
X0708395Y0474971
X0670000Y0465844
X0650268Y0479141
X0632996Y0478309
X0621916Y0465088
X0587812Y0474353
X0427225Y0478965
X0413425Y0479042
X0399625Y0479119
X0387184Y0470495
X0384668Y0471926
X1459682Y0450372
X1414000Y0460362
X1403500Y0458377
X1213866Y0455376
X1185707Y0460202
X1185707Y0465272
X1113943Y0452055
X1027760Y0451832
X0873884Y0453383
X0834251Y0459578
X0797252Y0459344
X0755559Y0456074
X0702095Y0449854
X0670000Y0457844
X0637504Y0454352
X0594430Y0463600
X1242429Y0447255
X1242429Y0443255
X1185952Y0448202
X1185952Y0440202
X1045015Y0444404
X0796333Y0439344
X0758709Y0437256
X0742961Y0465523
X0742961Y0440405
X0739811Y0446705
X0739811Y0443555
X0739811Y0462373
X0739811Y0459223
X0739811Y0456074
X0739811Y0449854
X0724143Y0443555
X0727292Y0443555
X0727292Y0446705
X0733512Y0443555
X0733512Y0446705
X0736661Y0443555
X0736661Y0462373
X0733512Y0462373
X0727292Y0459223
X0733512Y0459223
X0727292Y0462373
X0724143Y0462373
X0717843Y0459223
X0720993Y0456074
X0720993Y0459223
X0720993Y0462373
X0720993Y0449854
X0717843Y0465523
X0717843Y0440405
X0717843Y0446705
X0720993Y0446705
X0720993Y0443555
X0698946Y0437256
X0615075Y0443000
X0068365Y0443677
X0054762Y0444993
X0053800Y0435451
X0050002Y0449106
X0045022Y0449106
X0030680Y0438142
X1818874Y0423932
X1795468Y0421334
X1201157Y0431875
X1185952Y0432202
X1093722Y0427960
X1077418Y0421922
X1045100Y0427059
X1013365Y0433426
X0996232Y0424440
X0813175Y0422687
X0752409Y0421508
X0727292Y0421508
X0733512Y0427807
X0711544Y0421508
X0702095Y0421508
X0708395Y0430957
X0644673Y0425816
X0599164Y0432209
X0575917Y0421390
X0588723Y0423949
X0563230Y0426508
X0064150Y0434972
X0060393Y0427810
X0065380Y0427810
X0047619Y0421655
X0045182Y0425810
X0050138Y0425810
X1819374Y0410432
X1795479Y0408056
X1077418Y0416763
X1077418Y0411322
X1061456Y0406560
X1040891Y0406586
X0780808Y0419865
X0765008Y0418358
X0695796Y0418358
X0679862Y0409320
X0688249Y0405628
X0660885Y0412588
X0634566Y0407848
X0610935Y0409996
X0603283Y0419744
X0568433Y0415846
X0071772Y0421746
X0062808Y0418675
X0062833Y0409597
X0053825Y0421746
X0047618Y0412613
X1820144Y0398052
X1127471Y0404788
X1101942Y0395361
X1083583Y0395195
X1074800Y0391262
X1030525Y0391362
X1027724Y0397726
X1009618Y0396125
X0671753Y0397936
X0640317Y0391085
X0617985Y0390377
X0617985Y0398578
X0600520Y0401728
X0581985Y0404308
X0581985Y0390377
X0562208Y0401158
X1820656Y0388051
X1802929Y0385293
X1139200Y0385698
X1139200Y0380533
X1073204Y0383417
X1068827Y0389734
X1068143Y0383688
X1055934Y0385488
X0989227Y0389311
X0836840Y0382003
X0691547Y0386834
X0617985Y0379577
X0598208Y0376427
X0598208Y0387227
X0581985Y0379577
X0562208Y0376427
X0562208Y0387227
X0551200Y0377650
X0087520Y0386502
X0061340Y0384362
X0061250Y0396142
X0049250Y0396332
X0049400Y0384392
X0033686Y0383944
X0026771Y0398811
X0021345Y0387760
X0036524Y0398013
X0029962Y0401000
X0039226Y0395346
X0039410Y0384582
X1829732Y0367359
X1820307Y0373829
X1659610Y0394727
X1652610Y0394727
X1663610Y0394727
X1642135Y0414202
X1652810Y0407402
X1707444Y0407045
X1704444Y0407045
X1647110Y0434177
X1661110Y0434177
X1686154Y0434160
X1704624Y0433650
X1697214Y0433655
X1701124Y0433650
X1698014Y0424055
X1697914Y0427155
X1711144Y0425945
X1636800Y0432982
X1639800Y0432982
X1636800Y0429982
X1639800Y0429982
X1636800Y0426982
X1639800Y0426982
X1636800Y0438982
X1639800Y0438982
X1636800Y0435982
X1639800Y0435982
X1725500Y0383662
X1770520Y0368148
X1770520Y0364148
X1732660Y0372692
X1737260Y0368132
X1725400Y0372062
X1721400Y0374462
X1007083Y0363461
X0719500Y0360862
X0711500Y0360862
X0087654Y0376026
X0046834Y0360862
X1803129Y0362293
X0998460Y0354725
R02X-0005000
X0607871Y0359262
X0615464Y0347522
X0488076Y0350420
X0467644Y0353417
X0042809Y0360862
X0055190Y0360862
X0861377Y0344669
X0860152Y0333317
X0865132Y0333317
X0861377Y0339751
X0846275Y0335575
X0856397Y0344669
X0856397Y0339751
X0832686Y0331028
X0808401Y0341670
X0753959Y0343790
X0720328Y0344824
X0697400Y0345761
X0865132Y0328399
X0860152Y0328399
X0803264Y0330102
X0758959Y0319596
X0120016Y0320631
X1619909Y0306746
X1586291Y0306746
X1245825Y0305275
X1226094Y0305216
X1230094Y0314216
X0798621Y0312773
X0773944Y0312588
X0779121Y0306155
X0633805Y0302289
X0441320Y0310170
X0441320Y0304170
X0062930Y0312866
X0050500Y0311100
X1599837Y0295328
X1366156Y0292066
X1358094Y0286948
X1350156Y0292066
X1342094Y0286948
X1326094Y0286948
X1334156Y0292066
X1310156Y0292066
X1294156Y0292066
X1302094Y0286948
X1302094Y0298066
X1278156Y0292066
X1286094Y0286948
X1262156Y0292066
X1270094Y0286948
X1254094Y0286948
X1233345Y0300157
X1222094Y0286948
X1230156Y0292066
X1226094Y0297066
X1214156Y0292066
X1017870Y0294386
X0646285Y0297171
X0597223Y0298035
X0594698Y0298035
X0595723Y0289721
X0597223Y0306090
X0594698Y0306090
X0597223Y0314145
X0594698Y0314145
X0594698Y0322200
X0597223Y0322200
X0567323Y0300023
X0568573Y0321993
X0552699Y0291833
X0558743Y0313923
X0561691Y0315073
X0557953Y0317643
X0554893Y0317643
X0552153Y0319123
X0554943Y0320563
X0558003Y0320563
X0549093Y0319123
X0560643Y0317683
X0556323Y0315273
X0538567Y0294777
X0542813Y0319173
X0545873Y0319173
X0441320Y0298170
X0120016Y0300654
X0066289Y0301357
X0047892Y0290137
X0035689Y0301357
X0017292Y0290137
X1246094Y0280573
X1238094Y0280573
X0992915Y0280389
X0995189Y0274002
X0982455Y0275443
X0942779Y0277731
X0942763Y0272340
X0916268Y0277859
X0452480Y0273420
X0484063Y0313956
X0508081Y0314124
X0510606Y0314124
X0455813Y0310173
X0458873Y0310173
X0448852Y0283318
X0470953Y0308643
X0467893Y0308643
X0465153Y0310123
X0467943Y0311563
X0471003Y0311563
X0462093Y0310123
X0473643Y0308683
X0469323Y0306273
X0471743Y0304923
X0474691Y0306073
X0465699Y0282833
X0480323Y0291023
X0510223Y0297090
X0507698Y0297090
X0510223Y0305145
X0507698Y0305145
X0508723Y0280721
X0507698Y0289035
X0510223Y0289035
X0062930Y0282866
X0044600Y0280357
X1007669Y0258222
X1007669Y0268884
X0995189Y0263340
X0982455Y0264781
X0928224Y0264072
X0604718Y0257562
X0575524Y0261171
X0587140Y0257630
X0546800Y0262800
X0483800Y0270440
X0412715Y0270165
X0412715Y0262165
X1574546Y0251294
X1514900Y0251839
X1516452Y0249724
X1513348Y0253954
X1335260Y0251594
X1335260Y0241594
X1335260Y0246594
X1277732Y0251594
X1277732Y0241594
X1277732Y0246594
X1012220Y0243638
X1021220Y0243638
X0533097Y0246780
X0462703Y0242342
X0460624Y0244103
X0443400Y0247880
X0423730Y0249570
X0412715Y0254165
X0420288Y0244184
X1684942Y0234000
X1654419Y0233062
X1335260Y0236594
X1277732Y0236594
X0935497Y0231358
X0909320Y0231358
X0623605Y0228777
X0578172Y0231393
X0588554Y0229277
X0569004Y0228571
X0553100Y0227700
X0511170Y0227882
X0487541Y0226527
X0471371Y0231764
X0463653Y0237390
X0457731Y0237588
X0463402Y0229970
X0434420Y0239930
X0440029Y0240381
X0422936Y0232793
X0422936Y0228147
X1673223Y0220857
X1629597Y0221842
X1602270Y0229530
X1555481Y0218326
X1552981Y0220826
X1514576Y0219730
X0991553Y0216809
X0968692Y0219589
X0971192Y0219589
X0935497Y0217185
X0935497Y0224272
X0909320Y0224271
X0909320Y0217185
X0856701Y0304862
X0853201Y0297462
X0829167Y0288063
X0840288Y0287593
X0829572Y0296511
X0795668Y0298801
X0780618Y0296345
X0773221Y0296262
X0757464Y0284087
X0755335Y0295589
X0880944Y0283347
X0880944Y0286347
X0836163Y0279355
X0816322Y0284369
X0797444Y0271469
X0797594Y0282233
X0774485Y0286879
X0765285Y0276374
X0756692Y0278942
X0858528Y0262382
X0857334Y0276117
X0854225Y0283527
X0854225Y0280027
X0854334Y0276117
X0863934Y0276917
X0860834Y0276817
X0852801Y0288562
X0862044Y0290047
X0852780Y0291559
X0847939Y0265092
X0853800Y0265057
X0832525Y0268579
X0806984Y0265653
X0791341Y0264848
X0754291Y0269322
X0754286Y0266319
X0773457Y0249792
X0852207Y0229878
X0854707Y0229878
X0830340Y0228143
X0845221Y0216532
X0849711Y0212062
X0719195Y0213199
X0714203Y0213199
X0701927Y0219685
X0701927Y0213779
X0682264Y0224116
X0623605Y0219277
X0612414Y0227041
X0607834Y0222611
X0577859Y0212196
X0585296Y0222954
X0588554Y0221277
X0573911Y0212196
X0541013Y0222441
X0517973Y0211998
X0515151Y0220166
X0511170Y0224930
X0500269Y0225071
X0498776Y0213285
X0491635Y0212577
X0457931Y0212703
X0453783Y0217646
X0439299Y0220046
X0433124Y0225205
X0433124Y0222253
X0411800Y0220200
X0396977Y0216685
X0384600Y0221800
X0379200Y0298772
X0355832Y0297855
X0360433Y0294030
X0359734Y0288768
X0386563Y0280370
X0355733Y0275059
X0349695Y0286712
X0349676Y0276708
X0390461Y0267694
X0390461Y0270694
X0390461Y0275194
X0380012Y0243615
X0380181Y0236674
X0371318Y0218629
X0372528Y0231859
X0369428Y0231759
X0379028Y0232559
X0379023Y0228649
X0379023Y0225149
X0352418Y0222329
X0352418Y0225329
X0128367Y0212241
X1529384Y0201245
X1019936Y0210463
X1019936Y0207333
X1019803Y0218099
X1008068Y0198387
X0935497Y0203012
X0935497Y0210098
X0925321Y0203399
X0909320Y0210098
X0909161Y0203012
X0714203Y0201365
X0719195Y0201365
X0719195Y0208207
X0714203Y0208207
X0701927Y0207874
X0701927Y0201968
X0673301Y0211332
X0673691Y0200672
X0643012Y0199313
X0643012Y0201913
X0564603Y0200304
X0564603Y0197778
X0531280Y0210922
X0519579Y0207435
X0511771Y0199576
X0495232Y0197516
X0486600Y0200800
X0498776Y0209285
X0483467Y0209755
X0431299Y0204145
X0128367Y0197241
X0128367Y0207241
X0128367Y0202241
X0045423Y0207224
X0045423Y0202224
X0045423Y0212224
X1292082Y0184051
X1263582Y0185051
X1200012Y0185187
X1011358Y0195324
X1023221Y0191574
X0988593Y0189347
X0935497Y0195925
X0927134Y0189386
X0909298Y0195925
X0878221Y0192055
X0762300Y0188910
X0714203Y0189865
X0714203Y0184873
X0719195Y0189865
X0719195Y0184873
X0714203Y0196373
X0719195Y0196373
X0701927Y0190157
X0701927Y0196063
X0701927Y0184252
X0642481Y0184862
X0613207Y0182229
X0590300Y0190660
X0596661Y0188775
X0600793Y0193185
X0547196Y0195256
X0495232Y0189516
X0486682Y0197516
X0045423Y0197224
X1665100Y0166762
X1627410Y0172008
X1292082Y0171551
X1263582Y0168051
R02Y0004000
X1263582Y0180551
X1215528Y0172395
X1189701Y0173187
X1189727Y0177187
X1006436Y0176843
X0992506Y0184553
X0996416Y0184548
X0999916Y0184548
X0993206Y0178053
X0993306Y0174953
X0917386Y0179500
X0863488Y0176332
X0758111Y0172636
X0714203Y0177865
X0714203Y0172873
X0719195Y0177865
X0719195Y0172873
X0701927Y0178346
X0701927Y0172441
X0649441Y0177003
X0599678Y0175534
X0585685Y0178125
X0445997Y0170701
X0326475Y0182855
X1847866Y0159124
X1684925Y0153762
X1684925Y0161762
X1665100Y0156762
X1453667Y0152166
X1438312Y0152166
X1292082Y0162051
X1292082Y0166051
X1263582Y0160051
X1263582Y0164051
X1200037Y0160987
X1200037Y0164987
X0999736Y0157943
X1002736Y0157943
X0874295Y0163862
X0851895Y0160141
X0771356Y0167518
X0744911Y0166887
X0701927Y0166535
X0692521Y0152482
R02X-0004000
X0618600Y0160750
X0593975Y0164440
X0563951Y0160644
X0556811Y0152742
X0494200Y0158800
X0457997Y0166400
X0465997Y0166400
X0441997Y0166400
X0429997Y0166400
X0391635Y0161091
X0339914Y0165170
X0294553Y0153819
X0299624Y0158706
X0288516Y0157065
X0283949Y0152506
X0264574Y0155206
X0264574Y0159206
X0242251Y0162515
X0233653Y0162074
X1754850Y0303930
X1752250Y0303850
X1778500Y0183790
X1819529Y0320321
X1817674Y0188699
X1797719Y0186610
X1795219Y0185910
X1807711Y0175083
X1807711Y0178083
X1804111Y0178083
X1789811Y0178083
X1750325Y0179827
X1759911Y0179890
X1764385Y0179890
X1757385Y0179890
X1752851Y0179827
X1766911Y0179890
X1773911Y0179890
X1771385Y0179890
X1779111Y0215090
X1776585Y0215090
X1772111Y0215090
X1769585Y0215090
X1783448Y0212957
X1808260Y0213232
X1791445Y0197497
X1791645Y0193397
X1796019Y0202030
X1803145Y0198697
X1799629Y0198870
X1795365Y0197567
X1803045Y0193397
X1800389Y0193424
X1797621Y0193373
X1794629Y0193323
X1805235Y0204650
X1800125Y0201857
X1803165Y0196127
X1802276Y0204713
X1805235Y0208950
X1795909Y0209128
X1802276Y0209013
X1798943Y0209044
X1795949Y0205580
X1798943Y0204744
X1810509Y0214660
X1813109Y0214660
X1813079Y0211850
X1810479Y0211850
X1748325Y0216427
X1765011Y0216490
X1762485Y0216490
X1750851Y0216427
X1755425Y0216427
X1757951Y0216427
X1808367Y0226375
X1808367Y0222450
X1811606Y0226438
X1808429Y0218837
X1811606Y0222513
X1811668Y0218900
X1775984Y0253779
X1775984Y0256779
X1778874Y0256799
X1778874Y0253799
X1787534Y0253769
X1787534Y0256769
X1795794Y0253719
X1795794Y0256719
X1804174Y0256739
X1804174Y0253739
X1807296Y0255033
X1763509Y0248341
X1766399Y0248361
X1763509Y0251341
X1766399Y0251361
X1755969Y0248524
X1758859Y0248544
X1755969Y0251524
X1758859Y0251544
X1749571Y0252317
X1752461Y0252337
X1749571Y0255317
X1752461Y0255337
X1730364Y0177588
X1837641Y0159275
X1825111Y0164393
X1812570Y0159275
X1800040Y0164393
X1787390Y0161834
X1818155Y0149325
X1805525Y0146716
X1684925Y0149762
X1652525Y0141762
X1300668Y0145739
X1306431Y0152830
X1306431Y0149330
X1285391Y0142553
X1278111Y0150030
X1255175Y0137553
X1255185Y0142553
X1255185Y0140053
X1231118Y0142125
X1218431Y0141530
X1215931Y0141530
X1023187Y0146580
X1020661Y0146580
X0829115Y0150273
X0824499Y0145198
X0770073Y0143438
X0724134Y0141288
X0625574Y0150177
X0568472Y0149226
X0549800Y0147000
X0553300Y0164500
X0514418Y0141171
X0518418Y0137171
X0514418Y0149171
X0526418Y0137171
X0530418Y0141171
X0530418Y0149171
X0513360Y0169190
X0503161Y0149895
X0530418Y0137171
X0522418Y0137171
X0514418Y0145171
X0514418Y0153171
X0522418Y0153171
X0530418Y0153171
X0530418Y0145171
X0488580Y0141942
X0479630Y0141942
X0403141Y0144300
X0387712Y0147441
X0375920Y0146577
X0299628Y0149203
X0262886Y0147391
X0249735Y0152694
X0252195Y0144320
X0242215Y0151788
X0205489Y0142790
X1736474Y0134953
X1733344Y0134953
X1673100Y0126762
X1492237Y0123842
X1495539Y0131237
X1483820Y0122713
X1463017Y0136368
X1461242Y0128242
X1440871Y0130118
X1300668Y0129739
X1300668Y0133739
X1300668Y0125739
X1239218Y0123739
X1239218Y0132739
X1239218Y0137239
X1239218Y0128239
X0821119Y0134632
X0825699Y0139062
X0707243Y0123946
X0704144Y0122602
X0691058Y0131408
X0705570Y0133760
X0642394Y0131172
X0570860Y0127510
X0565210Y0125819
X0576510Y0125819
X0553780Y0127140
X0492300Y0124389
X0496280Y0131442
X0487880Y0131442
X0482255Y0135722
X0482255Y0127322
X0478295Y0128020
X0470895Y0128020
X0414486Y0124179
X0414486Y0127579
X0411952Y0123051
X0411952Y0132751
X0402606Y0126065
X0402606Y0129465
X0366771Y0127665
X0366874Y0135157
X0224055Y0127146
X0203061Y0131158
X0187250Y0129674
X1747448Y0121413
X1745451Y0119585
X1684925Y0118762
X1522917Y0119912
X1404917Y0109037
X1360629Y0120380
X1307857Y0111353
X1266146Y0121022
X0831115Y0115223
X0819115Y0115223
X0630900Y0118920
X0570860Y0118310
X0553780Y0118740
X0546400Y0120700
X0535170Y0117630
X0535170Y0108730
X0516020Y0111770
X0521420Y0109829
X0511140Y0109829
X0448090Y0116007
X0436090Y0120007
X0440090Y0132007
X0436090Y0128007
X0452090Y0128007
X0436090Y0132007
R02X0008000
X0452090Y0124007
X0452090Y0116007
X0436090Y0116007
X0444090Y0116007
X0436090Y0124007
X0397426Y0116215
X0397426Y0112815
X0403734Y0118976
X0403734Y0110326
X0391600Y0121178
X0343036Y0122525
X0214107Y0113022
X0195979Y0109462
X1715550Y0102923
X1446869Y0105129
X1434513Y0106950
X1371259Y0098000
X1306449Y0092185
X1319667Y0105227
X1256064Y0101100
X1215581Y0094846
X1200518Y0100875
X1177429Y0093556
X0754634Y0105288
X0754634Y0108288
X0734524Y0098758
X0737624Y0098858
X0727986Y0105477
X0729900Y0098090
X0727986Y0101979
X0735734Y0111988
X0713420Y0102060
X0684954Y0104968
X0580098Y0096439
X0538620Y0093289
X0519240Y0094967
X0516020Y0102870
X0523831Y0102931
X0523831Y0095445
X0512654Y0094967
X0502815Y0106984
X0494810Y0105969
X0487590Y0105969
X0492300Y0121389
X0500836Y0119092
X0457056Y0093101
X0464456Y0093101
X0443014Y0092384
X0450414Y0092384
X0406243Y0100076
X1765034Y0080443
X1758534Y0079743
X1758539Y0083653
X1758539Y0087153
X1768134Y0080543
X1766244Y0093673
X1754364Y0100353
X1710886Y0082208
X1701114Y0077839
X1706094Y0077839
X1684094Y0077839
X1679114Y0077839
X1656980Y0077842
X1662065Y0077842
X1639960Y0077839
X1634980Y0077839
X1616756Y0077839
X1611776Y0077839
X1594756Y0077839
X1589776Y0077839
X1567776Y0077839
X1572756Y0077839
X1545776Y0077842
X1550756Y0077842
X1369808Y0087587
X1356868Y0085324
X1344958Y0085358
X1319667Y0087587
X1304705Y0079807
X1232812Y0088635
X1230312Y0088635
X1223455Y0091346
X1215581Y0091346
X1188472Y0080165
X1191488Y0091125
X1191488Y0087125
X1177429Y0089556
X1176972Y0086788
X0854108Y0091232
X0854578Y0099651
X0837792Y0085186
X0834616Y0094324
X0831298Y0104206
X0842865Y0110296
X0727944Y0088972
X0685783Y0078768
X0681895Y0082212
X0688552Y0079166
X0673751Y0078092
X0678664Y0088080
X0653821Y0090326
X0660775Y0078330
X0553821Y0077516
X0545935Y0077516
X0543277Y0088632
X0457502Y0087011
X0450102Y0087011
X0429685Y0088657
X0425555Y0082014
X0417617Y0079073
X0425555Y0092014
X0410701Y0099148
X0423376Y0096664
X0226705Y0077839
X0231685Y0077839
X0209685Y0077839
X0204705Y0077839
X0187656Y0077842
X0182571Y0077842
X0165551Y0077839
X0160571Y0077839
X0142347Y0077839
X0137367Y0077839
X0120347Y0077839
X0115367Y0077839
X0098347Y0077839
X0093367Y0077839
X0071367Y0077842
X0076347Y0077842
X1758047Y0068637
X1708004Y0075340
X1695094Y0071842
X1695094Y0066850
X1699204Y0075340
X1697000Y0069343
X1706094Y0072847
X1701114Y0072847
X1684094Y0072847
X1686004Y0075340
X1690114Y0071842
X1690114Y0066850
X1688200Y0069343
X1679114Y0072847
X1666070Y0069340
X1667980Y0071839
X1674870Y0069340
X1672960Y0066847
X1667980Y0066847
X1672960Y0071839
X1663866Y0075343
X1677204Y0075340
X1650960Y0071839
X1656980Y0072850
X1662065Y0072850
X1655066Y0075343
X1652870Y0069340
X1650960Y0066847
X1645980Y0066847
X1644070Y0069340
X1645980Y0071839
X1641870Y0075340
X1639960Y0072847
X1634980Y0072847
X1620862Y0069343
X1622776Y0066850
X1627756Y0066850
X1622776Y0071842
X1627756Y0071842
X1618666Y0075340
X1633070Y0075340
X1629662Y0069343
X1605756Y0066850
X1605756Y0071842
X1607666Y0069343
X1616756Y0072847
X1611776Y0072847
X1609866Y0075340
X1600776Y0066850
X1598866Y0069343
X1600776Y0071842
X1596666Y0075340
X1594756Y0072847
X1589776Y0072847
X1585666Y0069340
X1583756Y0066847
X1578776Y0066847
X1576866Y0069340
X1583756Y0071839
X1578776Y0071839
X1574666Y0075340
X1587866Y0075340
X1563666Y0069340
X1561756Y0066847
X1567776Y0072847
X1565866Y0075340
X1561756Y0071839
X1572756Y0072847
X1556776Y0066847
X1554866Y0069340
X1545776Y0072850
X1550756Y0072850
X1556776Y0071839
X1552662Y0075343
X1541666Y0069340
X1532866Y0069340
X1534776Y0066847
X1539756Y0066847
X1534776Y0071839
X1539756Y0071839
X1543862Y0075343
X1361550Y0067264
X1339840Y0072860
X1351750Y0072826
X1309185Y0074748
X1183354Y0077685
X1168687Y0074202
X1155577Y0073939
X0836127Y0062681
X0762199Y0129684
X0762199Y0126684
X0762173Y0123898
X0769475Y0075360
X0754621Y0074562
X0745131Y0069507
X0738044Y0071526
X0730958Y0071014
X0682891Y0072642
X0682946Y0069982
X0666411Y0069507
X0645151Y0069507
X0615190Y0070533
X0603379Y0070512
X0560426Y0069507
X0553340Y0069507
X0546253Y0069507
X0539166Y0069507
X0532080Y0069507
X0524993Y0069507
X0517907Y0069507
X0510815Y0069562
X0478949Y0064975
X0468228Y0070016
X0430500Y0072900
X0413949Y0069270
X0258253Y0133786
X0261383Y0133786
X0289553Y0121806
X0301747Y0121469
X0311754Y0121472
X0301747Y0124469
X0301747Y0127469
X0311754Y0127472
X0311754Y0124472
X0272361Y0120243
X0270364Y0118415
X0320053Y0088806
X0320053Y0085806
X0299943Y0079276
X0303043Y0079376
X0293448Y0085986
X0293448Y0082486
X0293443Y0078576
X0279273Y0099186
X0299653Y0092506
X0233595Y0075340
X0220685Y0071842
X0220685Y0066850
X0231685Y0072847
X0226705Y0072847
X0224795Y0075340
X0222591Y0069343
X0215705Y0071842
X0215705Y0066850
X0213791Y0069343
X0211595Y0075340
X0209685Y0072847
X0204705Y0072847
X0202795Y0075340
X0187656Y0072850
X0200461Y0069340
X0198551Y0066847
X0193571Y0066847
X0191661Y0069340
X0198551Y0071839
X0193571Y0071839
X0189457Y0075343
X0182571Y0072850
X0180657Y0075343
X0178461Y0069340
X0176551Y0066847
X0176551Y0071839
X0171571Y0066847
X0169661Y0069340
X0171571Y0071839
X0167461Y0075340
X0165551Y0072847
X0160571Y0072847
X0158661Y0075340
X0146453Y0069343
X0155253Y0069343
X0148367Y0066850
X0153347Y0066850
X0148367Y0071842
X0153347Y0071842
X0144257Y0075340
X0131347Y0066850
X0131347Y0071842
X0133257Y0069343
X0142347Y0072847
X0137367Y0072847
X0135457Y0075340
X0126367Y0066850
X0124457Y0069343
X0126367Y0071842
X0122257Y0075340
X0120347Y0072847
X0115367Y0072847
X0113457Y0075340
X0111257Y0069340
X0109347Y0066847
X0104367Y0066847
X0102457Y0069340
X0109347Y0071839
X0104367Y0071839
X0100257Y0075340
X0098347Y0072847
X0093367Y0072847
X0091457Y0075340
X0089257Y0069340
X0087347Y0066847
X0087347Y0071839
X0071367Y0072850
X0076347Y0072850
X0082367Y0066847
X0080457Y0069340
X0082367Y0071839
X0078253Y0075343
X0069453Y0075343
X0067257Y0069340
X0058457Y0069340
X0060367Y0071839
X0065347Y0071839
X0060367Y0066847
X0065347Y0066847
X1807546Y0059443
X1807515Y0056461
X1781966Y0123501
R02Y0002500
X1771881Y0123439
R02Y0002500
X1785144Y0089973
X1785144Y0086973
X1764644Y0122973
X1785072Y0053161
X1764366Y0057508
X1759666Y0057708
X1760485Y0048720
X1753398Y0048720
X1705386Y0048720
X1462405Y0061563
X1441141Y0053699
X1198694Y0057015
X1142830Y0053186
X0861351Y0061672
X0752261Y0059782
X0747488Y0049062
X0744988Y0049062
X0744477Y0058373
X0730131Y0060757
X0722581Y0049182
X0679719Y0059066
X0668763Y0049193
X0675849Y0049193
X0661676Y0049193
X0654590Y0049193
X0653570Y0058363
X0615180Y0049193
X0593920Y0049193
X0539156Y0049193
X0532070Y0049193
X0524763Y0049189
X0517896Y0049193
X0510810Y0049193
X0478949Y0055135
X0478949Y0060029
X0430564Y0056348
X0286076Y0048720
X0278989Y0048720
X0285499Y0053191
X1772886Y0037430
X1763840Y0037790
X1748116Y0037058
X1698290Y0040020
X1698300Y0048720
X1684117Y0040020
X1684127Y0048720
X1691203Y0040020
X1691213Y0048720
X1669943Y0040020
X1669953Y0048720
X1677030Y0040020
X1677040Y0048720
X1654156Y0040020
X1654166Y0048720
X1639983Y0040020
X1639993Y0048720
X1647069Y0040020
X1647079Y0048720
X1625809Y0040020
X1625819Y0048720
X1632896Y0040020
X1632906Y0048720
X1604117Y0040020
X1604127Y0048720
X1589943Y0040020
X1589953Y0048720
X1597030Y0040020
X1597040Y0048720
X1575770Y0040020
X1575780Y0048720
X1582857Y0040020
X1582867Y0048720
X1561597Y0040020
X1561607Y0048720
X1568683Y0040020
X1568693Y0048720
X1547424Y0040020
X1547434Y0048720
X1554510Y0040020
X1554520Y0048720
X0742841Y0039832
X0736791Y0039832
X0728981Y0039872
X0701839Y0045112
X0686855Y0043701
X0693672Y0032684
X0675887Y0045262
X0677594Y0036205
X0668739Y0045262
X0663703Y0032574
X0648487Y0044106
X0620390Y0036794
X0624937Y0044019
X0618427Y0043432
X0599284Y0032866
X0603064Y0044523
X0595682Y0044842
X0578621Y0045112
X0564431Y0045132
X0542723Y0039562
X0525001Y0042257
X0517915Y0042257
X0306716Y0039985
X0286716Y0040020
X0271596Y0040165
X0263276Y0034625
X0230967Y0040020
X0230977Y0048720
X0223881Y0040020
X0223891Y0048720
X0216794Y0040020
X0216804Y0048720
X0209708Y0040020
X0209718Y0048720
X0202621Y0040020
X0202631Y0048720
X0195534Y0040020
X0195544Y0048720
X0179747Y0040020
X0179757Y0048720
X0172660Y0040020
X0172670Y0048720
X0165574Y0040020
X0165584Y0048720
X0158487Y0040020
X0158497Y0048720
X0151400Y0040020
X0151410Y0048720
X0129708Y0040020
X0129718Y0048720
X0122621Y0040020
X0122631Y0048720
X0115534Y0040020
X0115544Y0048720
X0108448Y0040020
X0108458Y0048720
X0101361Y0040020
X0101371Y0048720
X0094274Y0040020
X0094284Y0048720
X0087188Y0040020
X0087198Y0048720
X0080101Y0040020
X0080111Y0048720
X0073015Y0040020
X0073025Y0048720
X1777420Y0024506
X1777420Y0019506
X1769420Y0019506
X1760475Y0028406
X1753388Y0028406
X1752008Y0025146
X1725286Y0028208
R02X0003500
X1720148Y0022910
X1705381Y0037108
X1705376Y0028406
X1698290Y0028406
X1698300Y0037106
X1697242Y0022037
X1699250Y0019541
X1683189Y0025977
X1685189Y0023981
X1690145Y0023981
X1691203Y0028406
X1691213Y0037106
X1684117Y0028406
X1684127Y0037106
X1685077Y0019541
X1690294Y0019541
X1683068Y0022037
X1678088Y0022037
X1692145Y0025977
X1692262Y0022037
X1669016Y0025977
X1671016Y0023981
X1675972Y0023981
X1669943Y0028406
X1669953Y0037106
X1676121Y0019541
X1677972Y0025977
X1677030Y0028406
X1677040Y0037106
X1654156Y0028406
X1654166Y0037106
X1653108Y0022037
X1655116Y0019541
X1633838Y0025977
X1639055Y0025977
X1646011Y0023981
X1641055Y0023981
X1639983Y0028406
X1639993Y0037106
X1640943Y0019541
X1646160Y0019541
X1638934Y0022037
X1633954Y0022037
X1648011Y0025977
X1647069Y0028406
X1647079Y0037106
X1648128Y0022037
X1624882Y0025977
X1631838Y0023981
X1626882Y0023981
X1625809Y0028406
X1625819Y0037106
X1632896Y0028406
X1632906Y0037106
X1631987Y0019541
X1604117Y0028406
X1604127Y0037106
X1605077Y0019541
X1597972Y0025977
X1589016Y0025977
X1597030Y0028406
X1597040Y0037106
X1591016Y0023981
X1595972Y0023981
X1589943Y0028406
X1589953Y0037106
X1588895Y0022037
X1590903Y0019541
X1596121Y0019541
X1598092Y0022037
X1603072Y0022037
X1583798Y0025977
X1574842Y0025977
X1581798Y0023981
X1582857Y0028406
X1582867Y0037106
X1576842Y0023981
X1575770Y0028406
X1575780Y0037106
X1574722Y0022037
X1576730Y0019541
X1583915Y0022037
X1581947Y0019541
X1562557Y0019541
X1569625Y0025977
X1560669Y0025977
X1567625Y0023981
X1568683Y0028406
X1568693Y0037106
X1562669Y0023981
X1561597Y0028406
X1561607Y0037106
X1560548Y0022037
X1569742Y0022037
X1567774Y0019541
X1546496Y0025977
X1548496Y0023981
X1553452Y0023981
X1547434Y0037106
X1547424Y0028406
X1555452Y0025977
X1554510Y0028406
X1554520Y0037106
X1553601Y0019541
X1555568Y0022037
X0787456Y0049379
R03X0022000
X0875345Y0051595
X0876133Y0073580
R02Y0022000
X0877462Y0139540
X0898720Y0145206
X0920720Y0145206
X0964720Y0145206
R02X0022000
X1021899Y0127590
X1021899Y0061590
X1040199Y0049379
R05X0022000
X1194199Y0049379
R14X0022000
X1524124Y0047570
X1528993Y0026115
X0649585Y0029298
X0518843Y0023788
R11X0022000
X0329535Y0049379
R07X0022000
X0318660Y0024989
X0291156Y0021395
X0286066Y0028406
X0278979Y0028406
X0285896Y0023965
X0272596Y0027185
X0259996Y0028365
X0249496Y0028365
X0256496Y0028365
X0252996Y0028365
X0243486Y0023005
X0224841Y0019541
X0222833Y0022037
X0217853Y0022037
X0230967Y0028406
X0230977Y0037106
X0223881Y0028406
X0223891Y0037106
X0217736Y0025977
X0203679Y0022037
X0208659Y0022037
X0215885Y0019541
X0210668Y0019541
X0209708Y0028406
X0209718Y0037106
X0216794Y0028406
X0216804Y0037106
X0215736Y0023981
X0210780Y0023981
X0202621Y0028406
X0202631Y0037106
X0203563Y0025977
X0208780Y0025977
X0201712Y0019541
X0195534Y0028406
X0195544Y0037106
X0201563Y0023981
X0196607Y0023981
X0194607Y0025977
X0180707Y0019541
X0178699Y0022037
X0173719Y0022037
X0179747Y0028406
X0179757Y0037106
X0172660Y0028406
X0172670Y0037106
X0173602Y0025977
X0159545Y0022037
X0164525Y0022037
X0171751Y0019541
X0166534Y0019541
X0157578Y0019541
X0165574Y0028406
X0165584Y0037106
X0166646Y0023981
X0171602Y0023981
X0164646Y0025977
X0158487Y0028406
X0158497Y0037106
X0159429Y0025977
X0151400Y0028406
X0151410Y0037106
X0152473Y0023981
X0157429Y0023981
X0150473Y0025977
X0128663Y0022037
X0130668Y0019541
X0129708Y0028406
X0129718Y0037106
X0123683Y0022037
X0121712Y0019541
X0116494Y0019541
X0114486Y0022037
X0115534Y0028406
X0115544Y0037106
X0121563Y0023981
X0116607Y0023981
X0122621Y0028406
X0122631Y0037106
X0114607Y0025977
X0123563Y0025977
X0107538Y0019541
X0109506Y0022037
X0102321Y0019541
X0100313Y0022037
X0101361Y0028406
X0101371Y0037106
X0102433Y0023981
X0108448Y0028406
X0108458Y0037106
X0107389Y0023981
X0100433Y0025977
X0109389Y0025977
X0093365Y0019541
X0095333Y0022037
X0086139Y0022037
X0087188Y0028406
X0087198Y0037106
X0088260Y0023981
X0094274Y0028406
X0094284Y0037106
X0093216Y0023981
X0086260Y0025977
X0095216Y0025977
X0088148Y0019541
X0081159Y0022037
X0079192Y0019541
X0080101Y0028406
X0080111Y0037106
X0081043Y0025977
X0073015Y0028406
X0073025Y0037106
X0079043Y0023981
X0074087Y0023981
X0072087Y0025977
X0010875Y1291721
R25Y-0022000
X1840700Y0722201
X0018960Y1598181
X0010875Y1577721
R06Y-0022000
X0028592Y1683961
R03Y-0022000
X0092596Y1737117
R06X0022000
X0266596Y1737117
X0312596Y1737117
X0334596Y1737117
X0356596Y1737117
X0422596Y1737117
R03X0022000
X0532596Y1737117
R06X0022000
X0752596Y1737117
X0773974Y1731920
X0795926Y1731918
X0817974Y1731920
R10X0022000
X1081974Y1731920
X1103351Y1737117
X1125351Y1737117
X1191351Y1737117
R11X0022000
X1499351Y1737117
R12X0022000
X1840700Y0832201
R04Y-0022000
X1828889Y1688578
R03Y-0022000
X1835198Y1601502
X1840700Y1580201
R06Y-0022000
X1840700Y1404201
X1840700Y1338201
X1840700Y1316201
R21Y-0022000
X1793070Y0025001
X1796781Y0046686
X1818615Y0049379
X1840615Y0049379
X1854479Y0066461
X1854479Y0110461
X1854479Y0132461
R07Y0022000
X1853692Y0308447
X1840700Y0326201
R12Y0022000
X1840700Y0656201
R02Y0022000
X0010875Y0719721
R03Y-0022000
X0010875Y0609721
R13Y-0022000
X0003001Y0303178
R08Y-0022000
X0003001Y0061178
X0021569Y0049379
X0043569Y0049379
X0054584Y0030335
X1762420Y0017031
X1697242Y0017045
X1683068Y0017045
X1678088Y0017045
X1692262Y0017045
X1653108Y0017045
X1638934Y0017045
X1633954Y0017045
X1648128Y0017045
X1588895Y0017045
X1598092Y0017045
X1603072Y0017045
X1574722Y0017045
X1583915Y0017045
X1560548Y0017045
X1569742Y0017045
X1555568Y0017045
X1528993Y0004115
X1550965Y0003001
R11X0022000
X0291000Y0014820
X0222833Y0017045
X0217853Y0017045
X0203679Y0017045
X0208659Y0017045
X0178699Y0017045
X0173719Y0017045
X0159545Y0017045
X0164525Y0017045
X0128663Y0017045
X0123683Y0017045
X0114486Y0017045
X0109506Y0017045
X0100313Y0017045
X0095333Y0017045
X0086139Y0017045
X0081159Y0017045
X0054584Y0008335
X0075928Y0003001
R11X0022000
X1740979Y1577905
X1736579Y1587480
X1749964Y1562537
X1749038Y1566186
X1746558Y1566186
X1749038Y1571786
X1746558Y1571786
X1753079Y1600150
X1753079Y1603050
X1753079Y1596650
X1746981Y1616550
X1750481Y1616550
X1743481Y1616550
X1747181Y1626750
X1750681Y1626750
X1743681Y1626750
X1754479Y1585905
X1753079Y1606550
X1761839Y1634223
X1769054Y1585705
X1772904Y1585005
X1740188Y1556371
X1740079Y1559505
X1751518Y1566186
X1752564Y1562537
X1747164Y1559430
X1747164Y1556323
X1749764Y1559430
X1749764Y1556323
X1744564Y1559430
X1744564Y1556323
X1752364Y1559430
X1752364Y1556323
X1755038Y1556238
X1751518Y1571786
X1769826Y1562559
X1761079Y1562605
X1761108Y1559446
X1761108Y1556339
X1758238Y1556238
X1768209Y1556000
X1785707Y1562537
X1785507Y1556323
X1785507Y1559430
X1784781Y1566186
X1782301Y1566186
X1775979Y1559805
X1775979Y1556805
X1780307Y1556323
X1780307Y1559430
X1782907Y1556323
X1782907Y1559430
X1782301Y1571786
X1784781Y1571786
X1789379Y1588478
X1816179Y1616550
X1809179Y1616550
X1812679Y1616550
X1787261Y1566186
X1787261Y1571786
X1788307Y1562537
X1788107Y1559430
X1788679Y1585805
X1804688Y1559371
X1772688Y1546871
X1772688Y1543871
X1768688Y1549871
X1768688Y1552871
X1769188Y1543871
X1769188Y1546871
X1776188Y1546871
X1776188Y1543871
X1801688Y1549371
X1801688Y1552871
X1801688Y1555871
X1801688Y1542371
X1801688Y1545871
X1790633Y1556195
X1793833Y1556195
X1788107Y1556323
X1796838Y1556125
X1804688Y1549371
X1804688Y1552871
X1804688Y1555871
X1804688Y1542371
X1804688Y1545871
X1737738Y1548021
X1740587Y1547946
X1743188Y1547871
X1743188Y1543871
X1740058Y1537419
X1742165Y1539620
X1737606Y1539807
X1744866Y1539589
X1741329Y1488405
X1741329Y1491405
X1741329Y1485405
X1741329Y1482405
X1756329Y1488405
X1756329Y1491405
X1756329Y1482405
X1756329Y1485405
X1764029Y1488405
X1764029Y1491405
X1764029Y1482405
X1764029Y1485405
X1779029Y1488405
X1779029Y1491405
X1779029Y1485405
X1779029Y1482405
X1788029Y1488405
X1788029Y1491405
X1788029Y1482405
X1788029Y1485405
X1803029Y1488405
X1803029Y1491405
X1812029Y1488405
X1812029Y1491405
X1803029Y1485405
X1803029Y1482405
X1812029Y1482405
X1812029Y1485405
X1827029Y1482405
X1827029Y1485405
X1827029Y1491405
X1827029Y1488405
X0050642Y1557451
X0061302Y1579997
X0058602Y1579997
X0063990Y1564727
X0063990Y1567627
X0063990Y1570427
X0063990Y1562177
X0063802Y1579997
X0078808Y1522839
X0093024Y1523287
X0088696Y1523769
X0088905Y1513835
X0088868Y1511285
X0085405Y1513835
X0085368Y1511285
X0081405Y1522835
X0081405Y1519835
X0081905Y1513835
X0081405Y1516835
X0081868Y1511285
X0093024Y1526394
X0088696Y1526769
X0082696Y1529095
X0095018Y1538750
X0095018Y1533150
X0082974Y1552051
X0085621Y1551969
X0103513Y1523098
X0106713Y1523098
X0109635Y1523158
X0100922Y1523287
X0095624Y1523287
X0098492Y1523287
X0101024Y1529501
X0100922Y1526394
X0095624Y1526394
X0098424Y1529501
X0098492Y1526394
X0097498Y1538750
X0097498Y1533150
X0099978Y1538750
X0099978Y1533150
X0101396Y1552769
X0102096Y1555442
X0116905Y1509335
X0116905Y1516335
X0116905Y1512835
X0116905Y1519835
X0116905Y1522835
X0114405Y1522835
X0114405Y1519835
X0114405Y1512835
X0114405Y1516335
X0114405Y1509335
X0116905Y1526335
X0063481Y1523287
X0059881Y1523287
X0066081Y1523287
X0057281Y1523287
X0052905Y1523335
X0059275Y1538750
R02X0002480
X0059275Y1533150
R02X0002480
X0062681Y1529501
X0063481Y1526394
X0059881Y1526394
X0065281Y1529501
X0066081Y1526394
X0057281Y1526394
X0052796Y1526469
X0071359Y1523186
X0068870Y1523147
X0074325Y1523303
X0074462Y1529665
X0074440Y1526385
X0067196Y1552869
X0049405Y1514835
X0055905Y1514835
X0055755Y1511885
X0052405Y1514835
X0047089Y1510268
X0047138Y1513072
X0037671Y1515214
X0033822Y1456075
X0033822Y1465075
X0033822Y1459075
X0033822Y1462075
X0042822Y1456075
X0042822Y1465075
X0042822Y1459075
X0042822Y1462075
X0057822Y1456075
X0057822Y1465075
X0057822Y1459075
X0057822Y1462075
X0066822Y1456075
X0066822Y1465075
X0066822Y1459075
X0066822Y1462075
X0085722Y1456075
X0088722Y1456075
X0081822Y1456075
X0085722Y1462075
X0085722Y1465075
X0088722Y1465075
X0088722Y1462075
X0081822Y1465075
X0081822Y1462075
X0160356Y0019541
X0153251Y0026477
X0124490Y0019541
X0117385Y0026477
X0110316Y0019541
X0103211Y0026477
X0096143Y0019541
X0089038Y0026477
X0081970Y0019541
X0218663Y0019541
X0211558Y0026477
X0204490Y0019541
X0197385Y0026477
X0174529Y0019541
X0167424Y0026477
X0074865Y0026477
X0163756Y0019541
X0156651Y0026477
X0127890Y0019541
X0120785Y0026477
X0113716Y0019541
X0106611Y0026477
X0099543Y0019541
X0092438Y0026477
X0085370Y0019541
X0222063Y0019541
X0214958Y0026477
X0207890Y0019541
X0200785Y0026477
X0177929Y0019541
X0170824Y0026477
X0078265Y0026477
X0642406Y0427614
X0622800Y0461348
X0749260Y0437256
X0802459Y0443218
X0553651Y0048842
X0583116Y0476745
X0711544Y0459223
X0553620Y0031048
X0544721Y0042892
X0539120Y0031340
X0666000Y0473844
X0714694Y0465523
X0708395Y0449854
X0950950Y0284662
X0988190Y0424626
X0658642Y0573893
X0966278Y0556736
X0635449Y0449797
X1466681Y0078590
X1152198Y1669629
X0162740Y1704885
X0154083Y1456007
X1131478Y1485427
X0684350Y1448911
X0162740Y1713172
X0771512Y0390862
X0771964Y0339716
X0433277Y0471970
X0640922Y0360342
X0152605Y1715941
X0817996Y0496219
X0785674Y0342279
X1406666Y1616332
X1458795Y1687083
X1418755Y1654999
X1680029Y1715609
X1680029Y1710609
X0817393Y0491594
X0749260Y0478121
X1695100Y0166762
X1051873Y0305482
X1040836Y0510894
X0776345Y0545733
X0714322Y0056286
X0705666Y0048010
X0698946Y0481271
X0903340Y0505105
X0910752Y0286141
X0728500Y0513362
X0787446Y0495344
X0813187Y0498362
X1364369Y0120380
X0797405Y0487464
X0794357Y0559996
X0432000Y1650000
X0396452Y1577738
X0090892Y1654749
X0459500Y1659000
X0812983Y0471344
X0815753Y0644219
X0865394Y0801244
X0701114Y1640345
X0462753Y1641289
X0743050Y0139182
X0583685Y0070678
X0679737Y0217763
X0733512Y0421508
X0618680Y0511302
X0554984Y0045312
X0551591Y0443665
X0780977Y0459524
X0774964Y0514204
X0755559Y0484420
X0770042Y0446829
X0749260Y0434106
X0746110Y0440405
X0742961Y0437256
X0786877Y0427344
X0758709Y0430957
X0770530Y0423460
X0772610Y0434690
X0785923Y0419194
X0758709Y0427807
X0720993Y0474971
X0717843Y0478121
X0770918Y0442510
X0752409Y0434106
X0746110Y0437256
X0714694Y0427807
X0703500Y0401290
X0846000Y0423362
X0085103Y1433051
X0837754Y0335345
X0442297Y0474442
X0639000Y0364862
X0739811Y0437256
X0714694Y0424657
X1191000Y1425900
X1296000Y1427700
X0768304Y0374362
X1515936Y0484412
X0783770Y0422454
X0755559Y0430957
X0752409Y0443555
X0768301Y0438223
X0717843Y0427807
X0769648Y0430511
X0717843Y0424657
X0782700Y0415284
X0755559Y0427807
X0763500Y0386862
X0752409Y0430957
X1695100Y0131762
X0766304Y0372862
X0772119Y0333537
X1695100Y0136762
X0768130Y0335363
X0767500Y0390862
X0755559Y0446705
X0733512Y0437256
X0733512Y0434106
X0856647Y0616786
X0925643Y0616620
X0935783Y0631192
X0756800Y0517050
X0742961Y0471822
X0926449Y0577806
X0935766Y0587692
X0749260Y0474971
X1418982Y1175144
X1695100Y0126762
X1597621Y1365384
X0720400Y0517440
X0720993Y0481271
X0057752Y0808020
X0665689Y0550294
X0113042Y0686285
X0365852Y0516466
X0719841Y0537348
X0720993Y0478121
X0716500Y0517362
X0694812Y0680188
X0700205Y0733211
X0724143Y0474971
X1182713Y0733815
X0724500Y0521862
X0783653Y0631671
X1118435Y0625307
X0724336Y0537527
X0724143Y0471822
X1473728Y0813552
X0727253Y0610689
X0835059Y0660940
X0724684Y0545864
X0310396Y0050365
X0232529Y0114830
X0698946Y0487570
X0615903Y0493474
X0563763Y0486350
X0924724Y0372211
X0727564Y0368862
X1797929Y0385293
X1783700Y0050011
X0749260Y0468672
X0681333Y0212326
X0204088Y0138912
X1725344Y0359334
X1022674Y0357848
X0998859Y0437141
X0842825Y0448739
X0685781Y0070022
X0786102Y0507536
X0742961Y0487570
X0575331Y0047672
X0720993Y0424657
X1355222Y1200561
X0719500Y0390862
X0947821Y0386567
X1043377Y0452740
X1042389Y0733426
X0637432Y0428935
X0655917Y0497964
X0715371Y0654726
X0705245Y0430957
X0708395Y0434106
X0635243Y0433518
X0658758Y0497964
X0725812Y0654713
X0626555Y0343929
X0140471Y0670445
X0383525Y0443386
X0631694Y0341300
X0140600Y0683029
X0380935Y0443386
X1718465Y0657982
X1091730Y0509362
X0860328Y0475162
X0666000Y0437844
X0711544Y0437256
X0702095Y0427807
X0870220Y0430424
X1716030Y0668182
X1085730Y0509362
X0899000Y0481038
X0662016Y0417897
X1182950Y0577030
X0665774Y0571762
X0670018Y0418690
X1182594Y0587759
X0664454Y0574896
X0606032Y0418968
X0687500Y0390680
X0739811Y0468672
X0752500Y0513362
X0189760Y1731564
X0370533Y1658605
X0391526Y1582373
X0189760Y1723041
X0817849Y0550871
X0829106Y0439279
X0178376Y1720559
X0182533Y1676854
X0202076Y1717845
X0827237Y0550771
X0828751Y0471344
X0199747Y1675603
X0389333Y1598816
X0762800Y0493654
X0755559Y0481271
X1695100Y0161762
X1034412Y0567416
X0765809Y0563410
X1062923Y0295053
X0700000Y0386790
X0714694Y0434106
X0711544Y0434106
X0705245Y0427807
X0705245Y0424657
X0746110Y0427807
X0746110Y0424657
X0743500Y0386962
X0742961Y0427807
X0742961Y0424657
X0736661Y0468672
X0767500Y0401470
X0714694Y0437256
X0757258Y0408763
X0720993Y0437256
X0852209Y0507211
X0771039Y0511292
X0857887Y0459847
X0816109Y0455344
X0717843Y0474971
X0724500Y0517362
X0707500Y0382362
X0717843Y0437256
X0755559Y0478121
X0739553Y0388270
X0739811Y0427807
X0700300Y0382502
X0708395Y0424657
X0708395Y0427807
X0695500Y0382362
X0711544Y0478121
X0703774Y0513463
X0736661Y0434106
X0736661Y0430957
X0747629Y0406163
X0720993Y0421508
X0759500Y0402098
X0717843Y0430957
X0786877Y0443344
X0755559Y0443555
X0719640Y0386862
X0720993Y0434106
X0714694Y0481271
X0720993Y0468672
X0728500Y0521862
X0711500Y0382362
X0717843Y0434106
X0714694Y0430957
X0690105Y0401775
X0711544Y0430957
X0749260Y0471822
X0739811Y0424657
X0720993Y0471822
X0708210Y0537816
X0736661Y0424657
X0748254Y1674771
X1139037Y1611383
X1409286Y1605796
X1124875Y1490042
X0750418Y1468893
X0745001Y1516471
X0565185Y0047982
X1695100Y0151762
X1580519Y0497650
X0957380Y0515233
X0774998Y0511306
X0752409Y0487570
X0978827Y0303412
X1564268Y1338440
X1568456Y1311533
X1566901Y1347726
X0752965Y0537678
X0749260Y0484420
X1547216Y1480812
X1572906Y1366759
X0752500Y0545862
X1029200Y0351614
X1024546Y0511254
X0754825Y0163397
X0361744Y0120713
X0190000Y0143000
X0827621Y0302962
X0830418Y0311865
X0803893Y0301969
X0799935Y0286823
X0798205Y0279146
X1828669Y0379552
X1488647Y0134562
X0782641Y0310888
X0769861Y0302462
X0812867Y0278860
X0846189Y0281419
X1560454Y1279004
X0736500Y0537862
X0739811Y0471822
X0740500Y0545862
X0739811Y0474971
X0739811Y0478121
X0764500Y0513340
X0746110Y0484420
X0736670Y0545864
X0687665Y0073202
X1559181Y1287165
X1554377Y1278763
X0690028Y0070142
X0740500Y0537862
X1561927Y1269901
X0745645Y0545880
X0692390Y0072692
X1557510Y1280291
X0777200Y0530250
X0694752Y0070212
X1597177Y1282288
X0701081Y0072450
X0741851Y0553544
X0728576Y0537476
X0739811Y0481271
X0741200Y0577470
X0699476Y0069982
X0923386Y0193563
X0632281Y0441904
X0765950Y0190669
X0764983Y0368052
X0856213Y0191545
X0639211Y0438191
X0909023Y0294734
X0889351Y0195489
X0353281Y0859620
X0356535Y0849708
X0356895Y0859791
X0357400Y0855982
X1295519Y0389561
X0703500Y0374362
X0352813Y0812188
X0018691Y0167208
X1302226Y0389355
X0659354Y0393938
X0356313Y0812188
X0011782Y0167036
X0359813Y0812188
X0019684Y0237154
X0661297Y0409857
X1305426Y0389355
X0363313Y0812088
X0022409Y0230021
X0691500Y0382462
X1299026Y0389355
X0584271Y1263988
X0723531Y0368862
X0720993Y0430957
X0883731Y0651690
X0719500Y0374362
X0840357Y0382813
X0884410Y0794332
X0564283Y1231192
X0739185Y0521394
X0727292Y0468672
X0822790Y0785838
X0751885Y0666724
X0675272Y1434525
X0055099Y1292676
X0620800Y0474700
X0639757Y0533440
X0751500Y0390862
X0679062Y0455140
X0427615Y1280417
X0610551Y1262988
X0347885Y1206426
X0060547Y1276036
X0747696Y0332772
X0379633Y0493942
X0606811Y0429528
X0626388Y0330536
X0756347Y0360851
X0285258Y0799314
X0437084Y0501865
X0743500Y0368862
X0633406Y0497964
X0681352Y0681305
X0751500Y0368862
X0663580Y0731509
X0564669Y1238907
X0424024Y1272144
X0728695Y0550943
X0649592Y0540078
X0608940Y1265991
X0427615Y1275417
X0055099Y1298676
X0699431Y0513344
X0278547Y0523041
X0055099Y1289676
X0615591Y1282038
X0642310Y0535773
X0694111Y0537881
X0427615Y1282917
X0642617Y0389299
X0771512Y0386862
X0637314Y0393680
X0764331Y0374401
X1605801Y1286168
X0822772Y0788359
X0762656Y0667835
X0768340Y0563678
X0673671Y1431922
X0564407Y0431638
X0780046Y0328268
X0542983Y0334531
X0828751Y0455344
X0232981Y0743983
X0457424Y0497978
X0723500Y0390862
X0268991Y0783248
X0468638Y0514096
X0720499Y0533474
X0756500Y0513340
X0630758Y0505874
X0529095Y0452049
X0742961Y0468672
X1082866Y0403068
X1050956Y0591090
X0740500Y0513362
X0741624Y0580707
X0920989Y0614132
X0847941Y0538325
X0756186Y0529888
X0611896Y0535178
X0572121Y0437038
X0561346Y1228547
X0424024Y1267144
X0707500Y0390862
X0271161Y0780588
X0452084Y0511870
X0783351Y0499221
X0460441Y0499842
X0755500Y0390862
X0257071Y0772770
X0751652Y0386862
X0254671Y0776388
X0739500Y0368862
X0364821Y0861852
X0093775Y0197241
X0364897Y0852564
X0093775Y0202241
X0369626Y0860717
X0093775Y0207241
X0366864Y0857274
X0093775Y0212241
X1431400Y0533400
X1395302Y0256136
X1593303Y0239250
X0699500Y0374362
X0666192Y0598660
X1305100Y0662100
X1120321Y0635832
X1435400Y0536200
X1395302Y0251136
X1593303Y0234250
X0695500Y0374362
X0662992Y0598660
X1302500Y0664500
X1235215Y0777213
X1573326Y0543351
X0695500Y0390862
X0704549Y0655238
X1112190Y0651962
X1593303Y0244250
X1383715Y0241594
X1431300Y0538800
X1383715Y0236594
X1593658Y0252010
X1233084Y0772582
X0699500Y0390862
X0707833Y0655325
X1307700Y0664600
X1116540Y0651070
X0717843Y0421508
X1538587Y1245065
X0877459Y0802356
X0885916Y0653912
X0734166Y0360782
X0833219Y0375992
X0742961Y0474971
X1590921Y1309276
X0748661Y0517060
X0847435Y0555496
X0759500Y0390791
X1047515Y0444404
X1132340Y0471702
X1543980Y1258312
X1311715Y1221042
X1030190Y0735023
X0759500Y0386862
X1034899Y0444404
X1275177Y0808963
X0658613Y0599534
X1108076Y0646774
X0577845Y0437151
X0731500Y0386862
X1469950Y0813232
X0945602Y0664653
X0735500Y0368862
X0923103Y0362852
X1024509Y0500168
X1542747Y1253602
X0732500Y0513362
X1132340Y0468202
X0868496Y0776516
X1529306Y1177468
X1550517Y1232905
X0870591Y0785437
X1548360Y1234750
X1327029Y1206788
X1032736Y0735320
X1039015Y0444404
X0747500Y0390862
X1328992Y1209788
X1042015Y0444404
X0755500Y0386862
X1035269Y0735474
X1551113Y1238088
X0797252Y0443344
X0805199Y0620347
X0868539Y0790882
X1206590Y0481403
X1598467Y1267539
X1155268Y0212344
X1121077Y0511498
X0724500Y0513362
X0980690Y0387784
X0715500Y0374362
X1244986Y0787578
X0711617Y0513531
X0724246Y0627939
X1114467Y0640802
X1575024Y1306373
X0728500Y0529862
X0843655Y0555683
X0716500Y0521862
X0717843Y0481271
X0954757Y0593045
X0985668Y0389311
X0791723Y0574946
X0744500Y0513362
X1058231Y0523238
X0911980Y0585280
X0920031Y0577846
X0752195Y0554761
X1251177Y0784488
X1132855Y0609373
X0764500Y0521862
X1027504Y0485637
X1266568Y0809078
X0867733Y0575522
X0747500Y0368862
X1138387Y0615658
X1129387Y0615658
X0944264Y0587884
X0944264Y0420403
X0747454Y0386817
X1260427Y0809008
X1257527Y0808938
X0941764Y0587884
X0941764Y0420403
X0743500Y0390862
X1126387Y0615658
X1329244Y0871161
X1236100Y0773844
X1192039Y0638492
X1249065Y0236594
X1325543Y0871161
X1241057Y0782278
X1194539Y0638492
X1249065Y0241594
X1243207Y0779428
X1197039Y0638492
X1249065Y0246594
X1248130Y0783354
X1199539Y0638492
X1249065Y0251594
X0708395Y0465523
X0662000Y0473862
X0708395Y0462373
X0670000Y0469824
X1185913Y0093634
X0945380Y0233962
X0739652Y0390862
X0939938Y0386423
X0772100Y0532700
X0742961Y0484420
X1544911Y1260654
X0704201Y0072112
X0772000Y0545862
X0567127Y1249536
X1532896Y1234836
X0850016Y0087341
X0837251Y0093221
X0677305Y0057947
X0661601Y0075562
X0847473Y0094754
X0340436Y0120555
X0275116Y0028565
X0343446Y0131170
X0858630Y0060293
X1515854Y0119810
X1748708Y0026641
X1494891Y0121171
X0836780Y0068008
X0841585Y0094181
X0839899Y0087248
X1336812Y0856383
X1332812Y0856383
X0513572Y0865327
X0509572Y0865327
X0080318Y0539413
X0193679Y1640052
X0080318Y0543313
X0193679Y1643452
X0653999Y1423357
X0653999Y1426757
X0691276Y1455112
X0694676Y1455112
X0080948Y0521613
X0516058Y0046613
X0080948Y0525513
X0512658Y0046613
X0674013Y0042464
X0670613Y0042464
X1572331Y1348205
X1337399Y0098084
X1232081Y0460580
X1564758Y1367834
X1547195Y1478165
X0822794Y0767511
X0753231Y0678679
X0826474Y0435344
X0686994Y1629077
X0718129Y1624330
X0629808Y1668863
X0749260Y0481271
X0753252Y0495234
X1695100Y0156762
X1035860Y0485976
X0752500Y0517362
X1040060Y0313528
X1305685Y0074748
X0758709Y0446705
X1016764Y0350082
X1299196Y0076209
X0938570Y0233152
X0777612Y0403505
X0765008Y0446705
X0782712Y0260466
X1327541Y0105227
X1562820Y1309360
X0736661Y0487570
X1144663Y0500319
X1695100Y0141762
X0644975Y1725236
X0755765Y0666904
X0822864Y0783262
X0660930Y1730277
X0728938Y0517520
X0724143Y0468672
X0284035Y0796850
X0442084Y0511870
X0728652Y0545862
X1195108Y0668148
X0727292Y0471822
X0736362Y0636854
X1298000Y0657500
X0886150Y1582833
X0844150Y1582833
X0699000Y1604500
X0699500Y1596500
X0760650Y1587733
X0757610Y1589023
X0886150Y1570633
X0844150Y1570633
X0714474Y1566333
X0894150Y1602633
R02X-0042000
X0723408Y1608740
X0936150Y1590233
X0894850Y1587733
X0894150Y1590633
X0886150Y1594633
X0852150Y1590633
X0852850Y1587733
X0844150Y1594633
X0810150Y1590633
X0810850Y1587733
X0802150Y1594633
X0767750Y1584108
X0723963Y1585790
X0721963Y1587790
X0719963Y1585790
X0699610Y1584523
X0936150Y1582233
X0802150Y1582833
X0714110Y1581475
X0699610Y1576523
R02Y-0004000
X0886150Y1578633
R02X-0042000
X0760650Y1574733
X0760650Y1578733
X0802150Y1570633
X0760650Y1570633
M00
X0329331Y1734212
X0345079Y1734212
X0337205Y1728700
X0352953Y1728700
X0329331Y1724763
X0337205Y1723976
X0345079Y1724763
X0352953Y1723976
X0329331Y1720039
X0345079Y1720039
X0337205Y1714527
X0352953Y1714527
X0329331Y1710590
X0337205Y1709803
X0345079Y1710590
X0352953Y1709803
X0329331Y1705866
X0345079Y1705866
X0337205Y1700354
X0352953Y1700354
X0329331Y1696417
X0337205Y1695629
X0345079Y1696417
X0352953Y1695629
X0329331Y1691692
X0345079Y1691692
X0337205Y1686180
X0352953Y1686180
X0329331Y1682244
X0337205Y1681456
X0345079Y1682244
X0352953Y1681456
X0329331Y1677519
X0345079Y1677519
X0337205Y1672007
X0352953Y1672007
X0297835Y1734212
X0313583Y1734212
X0305709Y1728700
X0321457Y1728700
X0297835Y1724763
X0305709Y1723976
X0313583Y1724763
X0321457Y1723976
X0297835Y1720039
X0313583Y1720039
X0305709Y1714527
X0321457Y1714527
X0297835Y1710590
X0305709Y1709803
X0313583Y1710590
X0321457Y1709803
X0297835Y1705866
X0313583Y1705866
X0305709Y1700354
X0321457Y1700354
X0297835Y1696417
X0305709Y1695629
X0313583Y1696417
X0321457Y1695629
X0297835Y1691692
X0313583Y1691692
X0305709Y1686180
X0321457Y1686180
X0297835Y1682244
X0305709Y1681456
X0313583Y1682244
X0321457Y1681456
X0297835Y1677519
X0313583Y1677519
X0305709Y1672007
X0321457Y1672007
X0262401Y1734212
X0278149Y1734212
X0270275Y1728700
X0286023Y1728700
X0262401Y1724763
X0270275Y1723976
X0278149Y1724763
X0286023Y1723976
X0262401Y1720039
X0278149Y1720039
X0270275Y1714527
X0286023Y1714527
X0262401Y1710590
X0270275Y1709803
X0278149Y1710590
X0286023Y1709803
X0262401Y1705866
X0278149Y1705866
X0270275Y1700354
X0286023Y1700354
X0262401Y1696417
X0270275Y1695629
X0278149Y1696417
X0286023Y1695629
X0262401Y1691692
X0278149Y1691692
X0270275Y1686180
X0286023Y1686180
X0262401Y1682244
X0270275Y1681456
X0278149Y1682244
X0286023Y1681456
X0262401Y1677519
X0278149Y1677519
X0270275Y1672007
X0286023Y1672007
X0262401Y1668070
X0270275Y1667283
X0278149Y1668070
X0286023Y1667283
X0262401Y1663346
X0278149Y1663346
X0270275Y1657834
X0286023Y1657834
X0262401Y1653897
X0270275Y1653110
X0278149Y1653897
X0286023Y1653110
X0262401Y1649173
X0278149Y1649173
X0270275Y1643661
X0286023Y1643661
X0230905Y1734212
X0246653Y1734212
X0238779Y1728700
X0254527Y1728700
X0230905Y1724763
X0238779Y1723976
X0246653Y1724763
X0254527Y1723976
X0230905Y1720039
X0246653Y1720039
X0238779Y1714527
X0254527Y1714527
X0230905Y1710590
X0238779Y1709803
X0246653Y1710590
X0254527Y1709803
X0230905Y1705866
X0246653Y1705866
X0238779Y1700354
X0254527Y1700354
X0230905Y1696417
X0238779Y1695629
X0246653Y1696417
X0254527Y1695629
X0230905Y1691692
X0246653Y1691692
X0238779Y1686180
X0254527Y1686180
X0230905Y1682244
X0238779Y1681456
X0246653Y1682244
X0254527Y1681456
X0230905Y1677519
X0246653Y1677519
X0238779Y1672007
X0254527Y1672007
X0230905Y1668070
X0238779Y1667283
X0246653Y1668070
X0254527Y1667283
X0230905Y1663346
X0246653Y1663346
X0238779Y1657834
X0254527Y1657834
X0230905Y1653897
X0238779Y1653110
X0246653Y1653897
X0254527Y1653110
X0230905Y1649173
X0246653Y1649173
X0238779Y1643661
X0254527Y1643661
X0526574Y1734212
X0542322Y1734212
X0534448Y1728700
X0550196Y1728700
X0526574Y1724763
X0534448Y1723976
X0542322Y1724763
X0550196Y1723976
X0526574Y1720039
X0542322Y1720039
X0534448Y1714527
X0550196Y1714527
X0526574Y1710590
X0534448Y1709803
X0542322Y1710590
X0550196Y1709803
X0526574Y1705866
X0542322Y1705866
X0534448Y1700354
X0550196Y1700354
X0526574Y1696417
X0534448Y1695629
X0542322Y1696417
X0550196Y1695629
X0526574Y1691692
X0542322Y1691692
X0534448Y1686180
X0550196Y1686180
X0526574Y1682244
X0534448Y1681456
X0542322Y1682244
X0550196Y1681456
X0526574Y1677519
X0542322Y1677519
X0534448Y1672007
X0550196Y1672007
X0495078Y1734212
X0510826Y1734212
X0502952Y1728700
X0518700Y1728700
X0495078Y1724763
X0502952Y1723976
X0510826Y1724763
X0518700Y1723976
X0495078Y1720039
X0510826Y1720039
X0502952Y1714527
X0518700Y1714527
X0495078Y1710590
X0502952Y1709803
X0510826Y1710590
X0518700Y1709803
X0495078Y1705866
X0510826Y1705866
X0502952Y1700354
X0518700Y1700354
X0495078Y1696417
X0502952Y1695629
X0510826Y1696417
X0518700Y1695629
X0495078Y1691692
X0510826Y1691692
X0502952Y1686180
X0518700Y1686180
X0495078Y1682244
X0502952Y1681456
X0510826Y1682244
X0518700Y1681456
X0495078Y1677519
X0510826Y1677519
X0502952Y1672007
X0518700Y1672007
X0593504Y1734212
X0609252Y1734212
X0601378Y1728700
X0617126Y1728700
X0593504Y1724763
X0601378Y1723976
X0609252Y1724763
X0617126Y1723976
X0593504Y1720039
X0609252Y1720039
X0601378Y1714527
X0617126Y1714527
X0593504Y1710590
X0601378Y1709803
X0609252Y1710590
X0617126Y1709803
X0593504Y1705866
X0609252Y1705866
X0601378Y1700354
X0617126Y1700354
X0593504Y1696417
X0601378Y1695629
X0609252Y1696417
X0617126Y1695629
X0593504Y1691692
X0609252Y1691692
X0601378Y1686180
X0617126Y1686180
X0593504Y1682244
X0601378Y1681456
X0609252Y1682244
X0617126Y1681456
X0593504Y1677519
X0609252Y1677519
X0601378Y1672007
X0617126Y1672007
X0562008Y1734212
X0577756Y1734212
X0569882Y1728700
X0585630Y1728700
X0562008Y1724763
X0569882Y1723976
X0577756Y1724763
X0585630Y1723976
X0562008Y1720039
X0577756Y1720039
X0569882Y1714527
X0585630Y1714527
X0562008Y1710590
X0569882Y1709803
X0577756Y1710590
X0585630Y1709803
X0562008Y1705866
X0577756Y1705866
X0569882Y1700354
X0585630Y1700354
X0562008Y1696417
X0569882Y1695629
X0577756Y1696417
X0585630Y1695629
X0562008Y1691692
X0577756Y1691692
X0569882Y1686180
X0585630Y1686180
X0562008Y1682244
X0569882Y1681456
X0577756Y1682244
X0585630Y1681456
X0562008Y1677519
X0577756Y1677519
X0569882Y1672007
X0585630Y1672007
X1337204Y1734212
X1352952Y1734212
X1345078Y1728700
X1360826Y1728700
X1337204Y1724763
X1345078Y1723976
X1352952Y1724763
X1360826Y1723976
X1337204Y1720039
X1352952Y1720039
X1345078Y1714527
X1360826Y1714527
X1337204Y1710590
X1345078Y1709803
X1352952Y1710590
X1360826Y1709803
X1337204Y1705866
X1352952Y1705866
X1345078Y1700354
X1360826Y1700354
X1337204Y1696417
X1345078Y1695629
X1352952Y1696417
X1360826Y1695629
X1337204Y1691692
X1352952Y1691692
X1345078Y1686180
X1360826Y1686180
X1337204Y1682244
X1345078Y1681456
X1352952Y1682244
X1360826Y1681456
X1337204Y1677519
X1352952Y1677519
X1345078Y1672007
X1360826Y1672007
X1305708Y1734212
X1321456Y1734212
X1313582Y1728700
X1329330Y1728700
X1305708Y1724763
X1313582Y1723976
X1321456Y1724763
X1329330Y1723976
X1305708Y1720039
X1321456Y1720039
X1313582Y1714527
X1329330Y1714527
X1305708Y1710590
X1313582Y1709803
X1321456Y1710590
X1329330Y1709803
X1305708Y1705866
X1321456Y1705866
X1313582Y1700354
X1329330Y1700354
X1305708Y1696417
X1313582Y1695629
X1321456Y1696417
X1329330Y1695629
X1305708Y1691692
X1321456Y1691692
X1313582Y1686180
X1329330Y1686180
X1305708Y1682244
X1313582Y1681456
X1321456Y1682244
X1329330Y1681456
X1305708Y1677519
X1321456Y1677519
X1313582Y1672007
X1329330Y1672007
X1270274Y1734212
X1286022Y1734212
X1278148Y1728700
X1293896Y1728700
X1270274Y1724763
X1278148Y1723976
X1286022Y1724763
X1293896Y1723976
X1270274Y1720039
X1286022Y1720039
X1278148Y1714527
X1293896Y1714527
X1270274Y1710590
X1278148Y1709803
X1286022Y1710590
X1293896Y1709803
X1270274Y1705866
X1286022Y1705866
X1278148Y1700354
X1293896Y1700354
X1270274Y1696417
X1278148Y1695629
X1286022Y1696417
X1293896Y1695629
X1270274Y1691692
X1286022Y1691692
X1278148Y1686180
X1293896Y1686180
X1270274Y1682244
X1278148Y1681456
X1286022Y1682244
X1293896Y1681456
X1270274Y1677519
X1286022Y1677519
X1278148Y1672007
X1293896Y1672007
X1238778Y1734212
X1254526Y1734212
X1246652Y1728700
X1262400Y1728700
X1238778Y1724763
X1246652Y1723976
X1254526Y1724763
X1262400Y1723976
X1238778Y1720039
X1254526Y1720039
X1246652Y1714527
X1262400Y1714527
X1238778Y1710590
X1246652Y1709803
X1254526Y1710590
X1262400Y1709803
X1238778Y1705866
X1254526Y1705866
X1246652Y1700354
X1262400Y1700354
X1238778Y1696417
X1246652Y1695629
X1254526Y1696417
X1262400Y1695629
X1238778Y1691692
X1254526Y1691692
X1246652Y1686180
X1262400Y1686180
X1238778Y1682244
X1246652Y1681456
X1254526Y1682244
X1262400Y1681456
X1238778Y1677519
X1254526Y1677519
X1246652Y1672007
X1262400Y1672007
X1534448Y1734212
X1550196Y1734212
X1542322Y1728700
X1558070Y1728700
X1534448Y1724763
X1542322Y1723976
X1550196Y1724763
X1558070Y1723976
X1534448Y1720039
X1550196Y1720039
X1542322Y1714527
X1558070Y1714527
X1534448Y1710590
X1542322Y1709803
X1550196Y1710590
X1558070Y1709803
X1534448Y1705866
X1550196Y1705866
X1542322Y1700354
X1558070Y1700354
X1534448Y1696417
X1542322Y1695629
X1550196Y1696417
X1558070Y1695629
X1534448Y1691692
X1550196Y1691692
X1542322Y1686180
X1558070Y1686180
X1534448Y1682244
X1542322Y1681456
X1550196Y1682244
X1558070Y1681456
X1534448Y1677519
X1550196Y1677519
X1542322Y1672007
X1558070Y1672007
X1502952Y1734212
X1518700Y1734212
X1510826Y1728700
X1526574Y1728700
X1502952Y1724763
X1510826Y1723976
X1518700Y1724763
X1526574Y1723976
X1502952Y1720039
X1518700Y1720039
X1510826Y1714527
X1526574Y1714527
X1502952Y1710590
X1510826Y1709803
X1518700Y1710590
X1526574Y1709803
X1502952Y1705866
X1518700Y1705866
X1510826Y1700354
X1526574Y1700354
X1502952Y1696417
X1510826Y1695629
X1518700Y1696417
X1526574Y1695629
X1502952Y1691692
X1518700Y1691692
X1510826Y1686180
X1526574Y1686180
X1502952Y1682244
X1510826Y1681456
X1518700Y1682244
X1526574Y1681456
X1502952Y1677519
X1518700Y1677519
X1510826Y1672007
X1526574Y1672007
X1601378Y1734212
X1617126Y1734212
X1609252Y1728700
X1625000Y1728700
X1601378Y1724763
X1609252Y1723976
X1617126Y1724763
X1625000Y1723976
X1601378Y1720039
X1617126Y1720039
X1609252Y1714527
X1625000Y1714527
X1601378Y1710590
X1609252Y1709803
X1617126Y1710590
X1625000Y1709803
X1601378Y1705866
X1617126Y1705866
X1609252Y1700354
X1625000Y1700354
X1601378Y1696417
X1609252Y1695629
X1617126Y1696417
X1625000Y1695629
X1601378Y1691692
X1617126Y1691692
X1609252Y1686180
X1625000Y1686180
X1601378Y1682244
X1609252Y1681456
X1617126Y1682244
X1625000Y1681456
X1601378Y1677519
X1617126Y1677519
X1609252Y1672007
X1625000Y1672007
X1569882Y1734212
X1585630Y1734212
X1577756Y1728700
X1593504Y1728700
X1569882Y1724763
X1577756Y1723976
X1585630Y1724763
X1593504Y1723976
X1569882Y1720039
X1585630Y1720039
X1577756Y1714527
X1593504Y1714527
X1569882Y1710590
X1577756Y1709803
X1585630Y1710590
X1593504Y1709803
X1569882Y1705866
X1585630Y1705866
X1577756Y1700354
X1593504Y1700354
X1569882Y1696417
X1577756Y1695629
X1585630Y1696417
X1593504Y1695629
X1569882Y1691692
X1585630Y1691692
X1577756Y1686180
X1593504Y1686180
X1569882Y1682244
X1577756Y1681456
X1585630Y1682244
X1593504Y1681456
X1569882Y1677519
X1585630Y1677519
X1577756Y1672007
X1593504Y1672007
M00
X0337205Y1733425
X0352953Y1733425
X0329331Y1729488
X0345079Y1729488
X0337205Y1719251
X0352953Y1719251
X0329331Y1715314
X0345079Y1715314
X0337205Y1705078
X0352953Y1705078
X0329331Y1701141
X0345079Y1701141
X0337205Y1690905
X0352953Y1690905
X0329331Y1686968
X0345079Y1686968
X0337205Y1676732
X0352953Y1676732
X0329331Y1672795
X0345079Y1672795
X0305709Y1733425
X0321457Y1733425
X0297835Y1729488
X0313583Y1729488
X0305709Y1719251
X0321457Y1719251
X0297835Y1715314
X0313583Y1715314
X0305709Y1705078
X0321457Y1705078
X0297835Y1701141
X0313583Y1701141
X0305709Y1690905
X0321457Y1690905
X0297835Y1686968
X0313583Y1686968
X0305709Y1676732
X0321457Y1676732
X0297835Y1672795
X0313583Y1672795
X0270275Y1733425
X0286023Y1733425
X0262401Y1729488
X0278149Y1729488
X0270275Y1719251
X0286023Y1719251
X0262401Y1715314
X0278149Y1715314
X0270275Y1705078
X0286023Y1705078
X0262401Y1701141
X0278149Y1701141
X0270275Y1690905
X0286023Y1690905
X0262401Y1686968
X0278149Y1686968
X0270275Y1676732
X0286023Y1676732
X0262401Y1672795
X0278149Y1672795
X0270275Y1662558
X0286023Y1662558
X0262401Y1658621
X0278149Y1658621
X0270275Y1648385
X0286023Y1648385
X0262401Y1644448
X0278149Y1644448
X0238779Y1733425
X0254527Y1733425
X0230905Y1729488
X0246653Y1729488
X0238779Y1719251
X0254527Y1719251
X0230905Y1715314
X0246653Y1715314
X0238779Y1705078
X0254527Y1705078
X0230905Y1701141
X0246653Y1701141
X0238779Y1690905
X0254527Y1690905
X0230905Y1686968
X0246653Y1686968
X0238779Y1676732
X0254527Y1676732
X0230905Y1672795
X0246653Y1672795
X0238779Y1662558
X0254527Y1662558
X0230905Y1658621
X0246653Y1658621
X0238779Y1648385
X0254527Y1648385
X0230905Y1644448
X0246653Y1644448
X0534448Y1733425
X0550196Y1733425
X0526574Y1729488
X0542322Y1729488
X0534448Y1719251
X0550196Y1719251
X0526574Y1715314
X0542322Y1715314
X0534448Y1705078
X0550196Y1705078
X0526574Y1701141
X0542322Y1701141
X0534448Y1690905
X0550196Y1690905
X0526574Y1686968
X0542322Y1686968
X0534448Y1676732
X0550196Y1676732
X0526574Y1672795
X0542322Y1672795
X0502952Y1733425
X0518700Y1733425
X0495078Y1729488
X0510826Y1729488
X0502952Y1719251
X0518700Y1719251
X0495078Y1715314
X0510826Y1715314
X0502952Y1705078
X0518700Y1705078
X0495078Y1701141
X0510826Y1701141
X0502952Y1690905
X0518700Y1690905
X0495078Y1686968
X0510826Y1686968
X0502952Y1676732
X0518700Y1676732
X0495078Y1672795
X0510826Y1672795
X0601378Y1733425
X0617126Y1733425
X0593504Y1729488
X0609252Y1729488
X0601378Y1719251
X0617126Y1719251
X0593504Y1715314
X0609252Y1715314
X0601378Y1705078
X0617126Y1705078
X0593504Y1701141
X0609252Y1701141
X0601378Y1690905
X0617126Y1690905
X0593504Y1686968
X0609252Y1686968
X0601378Y1676732
X0617126Y1676732
X0593504Y1672795
X0609252Y1672795
X0569882Y1733425
X0585630Y1733425
X0562008Y1729488
X0577756Y1729488
X0569882Y1719251
X0585630Y1719251
X0562008Y1715314
X0577756Y1715314
X0569882Y1705078
X0585630Y1705078
X0562008Y1701141
X0577756Y1701141
X0569882Y1690905
X0585630Y1690905
X0562008Y1686968
X0577756Y1686968
X0569882Y1676732
X0585630Y1676732
X0562008Y1672795
X0577756Y1672795
X1345078Y1733425
X1360826Y1733425
X1337204Y1729488
X1352952Y1729488
X1345078Y1719251
X1360826Y1719251
X1337204Y1715314
X1352952Y1715314
X1345078Y1705078
X1360826Y1705078
X1337204Y1701141
X1352952Y1701141
X1345078Y1690905
X1360826Y1690905
X1337204Y1686968
X1352952Y1686968
X1345078Y1676732
X1360826Y1676732
X1337204Y1672795
X1352952Y1672795
X1313582Y1733425
X1329330Y1733425
X1305708Y1729488
X1321456Y1729488
X1313582Y1719251
X1329330Y1719251
X1305708Y1715314
X1321456Y1715314
X1313582Y1705078
X1329330Y1705078
X1305708Y1701141
X1321456Y1701141
X1313582Y1690905
X1329330Y1690905
X1305708Y1686968
X1321456Y1686968
X1313582Y1676732
X1329330Y1676732
X1305708Y1672795
X1321456Y1672795
X1278148Y1733425
X1293896Y1733425
X1270274Y1729488
X1286022Y1729488
X1278148Y1719251
X1293896Y1719251
X1270274Y1715314
X1286022Y1715314
X1278148Y1705078
X1293896Y1705078
X1270274Y1701141
X1286022Y1701141
X1278148Y1690905
X1293896Y1690905
X1270274Y1686968
X1286022Y1686968
X1278148Y1676732
X1293896Y1676732
X1270274Y1672795
X1286022Y1672795
X1246652Y1733425
X1262400Y1733425
X1238778Y1729488
X1254526Y1729488
X1246652Y1719251
X1262400Y1719251
X1238778Y1715314
X1254526Y1715314
X1246652Y1705078
X1262400Y1705078
X1238778Y1701141
X1254526Y1701141
X1246652Y1690905
X1262400Y1690905
X1238778Y1686968
X1254526Y1686968
X1246652Y1676732
X1262400Y1676732
X1238778Y1672795
X1254526Y1672795
X1542322Y1733425
X1558070Y1733425
X1534448Y1729488
X1550196Y1729488
X1542322Y1719251
X1558070Y1719251
X1534448Y1715314
X1550196Y1715314
X1542322Y1705078
X1558070Y1705078
X1534448Y1701141
X1550196Y1701141
X1542322Y1690905
X1558070Y1690905
X1534448Y1686968
X1550196Y1686968
X1542322Y1676732
X1558070Y1676732
X1534448Y1672795
X1550196Y1672795
X1510826Y1733425
X1526574Y1733425
X1502952Y1729488
X1518700Y1729488
X1510826Y1719251
X1526574Y1719251
X1502952Y1715314
X1518700Y1715314
X1510826Y1705078
X1526574Y1705078
X1502952Y1701141
X1518700Y1701141
X1510826Y1690905
X1526574Y1690905
X1502952Y1686968
X1518700Y1686968
X1510826Y1676732
X1526574Y1676732
X1502952Y1672795
X1518700Y1672795
X1609252Y1733425
X1625000Y1733425
X1601378Y1729488
X1617126Y1729488
X1609252Y1719251
X1625000Y1719251
X1601378Y1715314
X1617126Y1715314
X1609252Y1705078
X1625000Y1705078
X1601378Y1701141
X1617126Y1701141
X1609252Y1690905
X1625000Y1690905
X1601378Y1686968
X1617126Y1686968
X1609252Y1676732
X1625000Y1676732
X1601378Y1672795
X1617126Y1672795
X1577756Y1733425
X1593504Y1733425
X1569882Y1729488
X1585630Y1729488
X1577756Y1719251
X1593504Y1719251
X1569882Y1715314
X1585630Y1715314
X1577756Y1705078
X1593504Y1705078
X1569882Y1701141
X1585630Y1701141
X1577756Y1690905
X1593504Y1690905
X1569882Y1686968
X1585630Y1686968
X1577756Y1676732
X1593504Y1676732
X1569882Y1672795
X1585630Y1672795
M00
X0805690Y0220472
X0793879Y0214567
X0789942Y0204724
X0793879Y0194881
X0805690Y0188976
X0817501Y0194881
X0821438Y0204724
X0817501Y0214567
X0854090Y1420331
X0850326Y1429417
X0841240Y1433181
X0832154Y1429417
X0828390Y1420331
X0832154Y1411245
X0841240Y1407481
X0850326Y1411245
X0911495Y0321654
X0916546Y0309460
X0928740Y0304409
X0940934Y0309460
X0945985Y0321654
X0940934Y0333848
X0928740Y0338899
X0916546Y0333848
X1029090Y1420331
X1025326Y1429417
X1016240Y1433181
X1007154Y1429417
X1003390Y1420331
X1007154Y1411245
X1016240Y1407481
X1025326Y1411245
X1057659Y0220472
X1045848Y0214567
X1041911Y0204724
X1045848Y0194881
X1057659Y0188976
X1069470Y0194881
X1073407Y0204724
X1069470Y0214567
M00
X1249152Y0060384
R03X-0007874
X1431175Y0087432
R03X0007874
M00
X1077638Y0133866
M00
X0326731Y0653394
X0326731Y0663237
X0363731Y0653394
X0363731Y0663237
X0433624Y0594259
X0443467Y0594259
X0754645Y1426892
X0754645Y1436735
X1166535Y1412479
X1166535Y1422322
X1291146Y1375715
X1291146Y1385558
X1320516Y1375715
X1320516Y1385558
X1487677Y0640145
X1487677Y0649988
X1415690Y0601230
X1425533Y0601230
X1524437Y0640365
X1524437Y0650208
X1700840Y1424519
X1700840Y1434362
X1701285Y0198612
X1701285Y0208455
X1731660Y0198612
X1731660Y0208455
X1800002Y0284934
X1800002Y0294777
X1770442Y0284934
X1770442Y0294777
M00
X0938780Y1714890
R02X-0010000
X0938780Y1704890
R02X-0010000
X0938780Y1694890
R02X-0010000
X0938780Y1684890
R02X-0010000
X1038780Y1714890
R03Y-0010000
X1028780Y1714890
R03Y-0010000
X1003780Y1714890
R03Y-0010000
X0993780Y1714890
R03Y-0010000
X0958780Y1714890
X0968780Y1714890
X0958780Y1684890
R02Y0010000
X0968780Y1684890
R02Y0010000
X0898780Y1714890
R03Y-0010000
X0888780Y1714890
R03Y-0010000
X0853780Y1714890
X0863780Y1714890
X0853780Y1684890
R02Y0010000
X0863780Y1684890
R02Y0010000
X0818780Y1714890
X0828780Y1714890
X0818780Y1684890
R02Y0010000
X0828780Y1684890
R02Y0010000
M00
X0099729Y0289822
R02X-0010000
X0099729Y0310256
R02X-0010000
X0757184Y1722772
R02Y-0010000
X1080970Y1660958
R02Y-0010000
X1072863Y1429176
R02Y-0010000
X1299439Y0092812
R02Y0010000
X1550377Y0581353
R02X-0010000
M00
X0315598Y0012480
X0266858Y0012480
X0186622Y0012480
X0137272Y0012480
X0057646Y0012480
X0760480Y0033267
X0711740Y0033267
X0631504Y0033267
X0582154Y0033267
X0502528Y0033267
X1156378Y0133866
X1173858Y0207205
X1173858Y0217205
X1183858Y0207205
X1183858Y0217205
X1193858Y0207205
X1193858Y0217205
X1391260Y0174213
X1391260Y0164213
X1381260Y0174213
X1381260Y0164213
X1371260Y0174213
X1371260Y0164213
X1361260Y0174213
X1361260Y0164213
X1351260Y0174213
X1351260Y0164213
X1790007Y0012480
X1741267Y0012480
X1661031Y0012480
X1611681Y0012480
X1532055Y0012480
M00
X0609016Y0274272
R07X-0010000
M00
X1864706Y1722195
X1869706Y1709011
X1859706Y1709011
X1886177Y1722507
X1881177Y1709323
X1891177Y1709323
X1864986Y1390234
X1859986Y1403418
X1869986Y1403418
X1886223Y1391283
X1891223Y1404467
X1881223Y1404467
X1887579Y1171532
X1892579Y1158348
X1882579Y1158348
X1866790Y1171255
X1861790Y1158071
X1871790Y1158071
X1888273Y0837632
X1883273Y0850816
X1893273Y0850816
X1887240Y0796658
X1892240Y0783474
X1882240Y0783474
X1865648Y0796913
X1860648Y0783729
X1870648Y0783729
X1867295Y0837583
X1872295Y0850767
X1862295Y0850767
X1887711Y0463680
X1882711Y0476864
X1892711Y0476864
X1866790Y0463389
X1871790Y0476573
X1861790Y0476573
X1887340Y0424013
X1892340Y0410829
X1882340Y0410829
X1886862Y0094107
X1881862Y0107291
X1891862Y0107291
X2076128Y0424013
X2071128Y0410829
X2081128Y0410829
X2077012Y0095128
X2082012Y0108312
X2072012Y0108312
M00
X0900197Y0175177
X0944685Y0155197
M00
X0027048Y1533228
X0079590Y1369350
X0137284Y1533228
X0276440Y1357539
X0215418Y0658055
X0443764Y1339823
X0420125Y0656008
X0523173Y0578174
X0681440Y1385138
X0791678Y1385138
X0873622Y1145275
X0983858Y1145275
X1052960Y1369350
X1249812Y1357539
X1370284Y0582303
X1417134Y1339823
X1533552Y0682342
X1629732Y1383523
X1664890Y0642972
X1761575Y0159134
X1739968Y1383527
X1714330Y1570984
X1824566Y1570988
X1838150Y0201929
M00
X0277098Y0185236
X0395208Y0185236
M00
X0887519Y1528191
M00
X0051180Y1714961
X0040708Y1368908
X0040708Y0631889
X0027559Y0087795
X0373622Y0087795
X0395671Y1714960
X0707677Y1714960
X0661024Y0631890
X0800787Y0087795
X0931693Y0757874
X0931692Y1072835
X0931693Y1387795
X1045866Y0087795
X1155709Y1714961
X1271260Y0631890
X1461806Y1714961
X1499606Y0087795
X1806298Y1714961
X1816772Y1368897
X1816772Y0631889
X1829921Y0087795
M00
X0766889Y1530256
X0766889Y1486756
M00
X0398673Y-0018871
X0398673Y-0028871
X0373673Y-0018871
X0373673Y-0028871
X0398673Y-0018871
X0398673Y-0008871
X0373673Y-0018871
X0373673Y-0008871
X0718093Y-0028871
X0718093Y-0018871
X0743093Y-0028871
X0743093Y-0018871
X0718093Y-0008871
X0718093Y-0018871
X0743093Y-0008871
X0743093Y-0018871
X0850152Y0004989
X0850152Y-0005011
X0825152Y0004989
X0825152Y-0005011
X0850152Y-0035011
X0850152Y-0025011
X0825152Y-0035011
X0825152Y-0025011
X0850152Y0024989
X0850152Y0014989
X0825152Y0024989
X0825152Y0014989
X0850152Y-0015011
X0850152Y-0025011
X0825152Y-0015011
X0825152Y-0025011
X0850152Y0004989
X0850152Y0014989
X0825152Y0004989
X0825152Y0014989
X0850152Y-0015011
X0850152Y-0005011
X0825152Y-0015011
X0825152Y-0005011
X1169572Y-0005011
X1169572Y0004989
X1194572Y-0005011
X1194572Y0004989
X1169572Y-0025011
X1169572Y-0035011
X1194572Y-0025011
X1194572Y-0035011
X1169572Y0014989
X1169572Y0024989
X1194572Y0014989
X1194572Y0024989
X1169572Y-0025011
X1169572Y-0015011
X1194572Y-0025011
X1194572Y-0015011
X1169572Y0014989
X1169572Y0004989
X1194572Y0014989
X1194572Y0004989
X1169572Y-0005011
X1169572Y-0015011
X1194572Y-0005011
X1194572Y-0015011
X1253672Y-0015011
X1253672Y-0005011
X1228672Y-0015011
X1228672Y-0005011
X1253672Y-0015011
X1253672Y-0025011
X1228672Y-0015011
X1228672Y-0025011
X1253672Y0004989
X1253672Y-0005011
X1228672Y0004989
X1228672Y-0005011
X1253672Y-0035011
X1253672Y-0025011
X1228672Y-0035011
X1228672Y-0025011
X1253672Y0004989
X1253672Y0014989
X1228672Y0004989
X1228672Y0014989
X1253672Y0024989
X1253672Y0014989
X1228672Y0024989
X1228672Y0014989
X1428431Y0014989
X1428431Y0024989
X1453431Y0014989
X1453431Y0024989
X1428431Y-0005011
X1428431Y-0015011
X1453431Y-0005011
X1453431Y-0015011
X1428431Y-0025011
X1428431Y-0015011
X1453431Y-0025011
X1453431Y-0015011
X1428431Y-0025011
X1428431Y-0035011
X1453431Y-0025011
X1453431Y-0035011
X1428431Y0014989
X1428431Y0004989
X1453431Y0014989
X1453431Y0004989
X1428431Y-0005011
X1428431Y0004989
X1453431Y-0005011
X1453431Y0004989
X1546966Y-0019212
X1546966Y-0029212
X1521966Y-0019212
X1521966Y-0029212
X1546966Y-0039212
X1546966Y-0029212
X1521966Y-0039212
X1521966Y-0029212
X1721725Y-0029212
X1721725Y-0019212
X1746725Y-0029212
X1746725Y-0019212
X1721725Y-0029212
X1721725Y-0039212
X1746725Y-0029212
X1746725Y-0039212
M00
X0312921Y0024291
X0060303Y0020354
X0757803Y0045078
X0505185Y0041141
X0929331Y0160413
X0922441Y0237697
X1787330Y0024291
X1534712Y0020354
M00
X1225530Y0067471
X1454797Y0080345
M00
X0676509Y0224606
M00
X0676509Y0145866
M00
X1066280Y1704890
X0791280Y1704890
M00
X1766929Y1714960
M00
X0031818Y1424257
X0044000Y0154200
X1800449Y0126194
X1804650Y1667292
M00
X0441043Y1672205
X0441043Y1718465
X0441043Y1698268
X1416437Y1672205
X1416437Y1718465
X1416437Y1698268
M00
X0561133Y0838505
X0320189Y0838505
X0274913Y1019214
X0320189Y1199923
X0561133Y1199923
X0606409Y1019214
X0841240Y1420331
X1016240Y1420331
X1537275Y0838504
X1296331Y0838504
X1251055Y1019213
X1296331Y1199922
X1537275Y1199922
X1582551Y1019213
M00
X0805690Y0204724
X1057659Y0204724
M00
X0117933Y0605376
X0763602Y0605413
X1094076Y0605378
X1739745Y0605411
M30
